(kicad_pcb
	(version 20260206)
	(generator "pcbnew")
	(generator_version "10.0")
	(general
		(thickness 1.6)
		(legacy_teardrops no)
	)
	(paper "A4")
	(layers
		(0 "F.Cu" signal "TOP")
		(4 "In1.Cu" signal "L2GND")
		(6 "In2.Cu" signal "L3VCC")
		(2 "B.Cu" signal "BOTTOM")
		(9 "F.Adhes" user "F.Adhesive")
		(11 "B.Adhes" user "B.Adhesive")
		(13 "F.Paste" user "Package Geometry/Pastemask Top")
		(15 "B.Paste" user "Package Geometry/Pastemask Bottom")
		(5 "F.SilkS" user "Ref Des/Silkscreen Top")
		(7 "B.SilkS" user "Ref Des/Silkscreen Bottom")
		(1 "F.Mask" user "Board Geometry/Soldermask Top")
		(3 "B.Mask" user "Board Geometry/Soldermask Bottom")
		(17 "Dwgs.User" user "User.Drawings")
		(19 "Cmts.User" user "User.Comments")
		(21 "Eco1.User" user "User.Eco1")
		(23 "Eco2.User" user "User.Eco2")
		(25 "Edge.Cuts" user "Board Geometry/Outline")
		(27 "Margin" user)
		(31 "F.CrtYd" user "Package Geometry/Place Bound Top")
		(29 "B.CrtYd" user "Package Geometry/Place Bound Bottom")
		(35 "F.Fab" user "Ref Des/Assembly Top")
		(33 "B.Fab" user "Ref Des/Assembly Bottom")
	)
	(setup
		(pad_to_mask_clearance 0)
		(allow_soldermask_bridges_in_footprints no)
		(tenting
			(front yes)
			(back yes)
		)
		(covering
			(front no)
			(back no)
		)
		(plugging
			(front no)
			(back no)
		)
		(capping no)
		(filling no)
		(pcbplotparams
			(layerselection 0x00000000_00000000_55555555_5755f5ff)
			(plot_on_all_layers_selection 0x00000000_00000000_00000000_00000000)
			(disableapertmacros no)
			(usegerberextensions no)
			(usegerberattributes yes)
			(usegerberadvancedattributes yes)
			(creategerberjobfile yes)
			(dashed_line_dash_ratio 12)
			(dashed_line_gap_ratio 3)
			(svgprecision 4)
			(plotframeref no)
			(mode 1)
			(useauxorigin no)
			(pdf_front_fp_property_popups yes)
			(pdf_back_fp_property_popups yes)
			(pdf_metadata yes)
			(pdf_single_document no)
			(dxfpolygonmode yes)
			(dxfimperialunits yes)
			(dxfusepcbnewfont yes)
			(psnegative no)
			(psa4output no)
			(plot_black_and_white yes)
			(sketchpadsonfab no)
			(plotpadnumbers no)
			(hidednponfab no)
			(sketchdnponfab yes)
			(crossoutdnponfab yes)
			(subtractmaskfromsilk no)
			(outputformat 1)
			(mirror no)
			(drillshape 1)
			(scaleselection 1)
			(outputdirectory "")
		)
	)
	(footprint ""
		(layer "F.Cu")
		(at 11.811 -47.65294 90)
		(property "Reference" "R28"
			(at 0 0 90)
			(layer "F.SilkS")
			(hide yes)
			(effects
				(font
					(size 1.27 1.27)
				)
			)
		)
		(property "Value" "4K7R2F-GP"
			(at 0.064008 -4.679696 90)
			(unlocked yes)
			(layer "F.Fab")
			(hide yes)
			(effects
				(font
					(size 2.54 2.54)
					(thickness 0.381)
				)
			)
		)
		(property "Device Type" "R402H16"
			(at 0.064008 -6.203696 90)
			(unlocked yes)
			(layer "F.Fab")
			(hide yes)
			(effects
				(font
					(size 2.54 2.54)
					(thickness 0.381)
				)
			)
		)
		(duplicate_pad_numbers_are_jumpers no)
		(fp_line
			(start 0.508 -0.9398)
			(end -0.508 -0.9398)
			(stroke
				(width 0.1524)
				(type default)
			)
			(layer "F.SilkS")
		)
		(fp_line
			(start -0.508 -0.9398)
			(end -0.508 0.9398)
			(stroke
				(width 0.1524)
				(type default)
			)
			(layer "F.SilkS")
		)
		(fp_rect
			(start -0.508 0.9398)
			(end 0.508 -0.9398)
			(stroke
				(width 0)
				(type default)
			)
			(fill no)
			(layer "F.CrtYd")
		)
		(fp_rect
			(start -0.508 0.9398)
			(end 0.508 -0.9398)
			(stroke
				(width 0)
				(type default)
			)
			(fill no)
			(layer "F.Fab")
		)
		(pad "1" smd custom
			(at 0 -0.4445 90)
			(size 0.1397 0.1397)
			(layers "F.Cu" "F.Mask" "F.Paste")
			(net "TEMP_1_A1")
			(options
				(clearance outline)
				(anchor circle)
			)
			(primitives
				(gr_poly
					(pts
						(arc
							(start -0.1778 -0.2794)
							(mid -0.249642 -0.249642)
							(end -0.2794 -0.1778)
						)
						(arc
							(start -0.2794 0.1778)
							(mid -0.249642 0.249642)
							(end -0.1778 0.2794)
						)
						(arc
							(start 0.1778 0.2794)
							(mid 0.249642 0.249642)
							(end 0.2794 0.1778)
						)
						(arc
							(start 0.2794 -0.1778)
							(mid 0.249642 -0.249642)
							(end 0.1778 -0.2794)
						)
					)
					(width 0)
					(fill yes)
				)
			)
		)
		(pad "2" smd custom
			(at 0 0.4445 90)
			(size 0.1397 0.1397)
			(layers "F.Cu" "F.Mask" "F.Paste")
			(net "GND")
			(options
				(clearance outline)
				(anchor circle)
			)
			(primitives
				(gr_poly
					(pts
						(arc
							(start -0.1778 -0.2794)
							(mid -0.249642 -0.249642)
							(end -0.2794 -0.1778)
						)
						(arc
							(start -0.2794 0.1778)
							(mid -0.249642 0.249642)
							(end -0.1778 0.2794)
						)
						(arc
							(start 0.1778 0.2794)
							(mid 0.249642 0.249642)
							(end 0.2794 0.1778)
						)
						(arc
							(start 0.2794 -0.1778)
							(mid 0.249642 -0.249642)
							(end 0.1778 -0.2794)
						)
					)
					(width 0)
					(fill yes)
				)
			)
		)
	)
	(footprint ""
		(layer "F.Cu")
		(at 1.8288 -51.054)
		(property "Reference" "R30"
			(at 0 0 0)
			(layer "F.SilkS")
			(hide yes)
			(effects
				(font
					(size 1.27 1.27)
				)
			)
		)
		(property "Value" "0R2J-2-GP"
			(at 0.064008 -4.679696 0)
			(unlocked yes)
			(layer "F.Fab")
			(hide yes)
			(effects
				(font
					(size 2.54 2.54)
					(thickness 0.381)
				)
			)
		)
		(property "Device Type" "R402H16"
			(at 0.064008 -6.203696 0)
			(unlocked yes)
			(layer "F.Fab")
			(hide yes)
			(effects
				(font
					(size 2.54 2.54)
					(thickness 0.381)
				)
			)
		)
		(duplicate_pad_numbers_are_jumpers no)
		(fp_line
			(start -0.508 -0.9398)
			(end -0.508 0.9398)
			(stroke
				(width 0.1524)
				(type default)
			)
			(layer "F.SilkS")
		)
		(fp_line
			(start 0.508 -0.9398)
			(end -0.508 -0.9398)
			(stroke
				(width 0.1524)
				(type default)
			)
			(layer "F.SilkS")
		)
		(fp_rect
			(start -0.508 0.9398)
			(end 0.508 -0.9398)
			(stroke
				(width 0)
				(type default)
			)
			(fill no)
			(layer "F.CrtYd")
		)
		(fp_rect
			(start -0.508 0.9398)
			(end 0.508 -0.9398)
			(stroke
				(width 0)
				(type default)
			)
			(fill no)
			(layer "F.Fab")
		)
		(pad "1" smd custom
			(at 0 -0.4445)
			(size 0.1397 0.1397)
			(layers "F.Cu" "F.Mask" "F.Paste")
			(net "TEMP_1_SCL")
			(options
				(clearance outline)
				(anchor circle)
			)
			(primitives
				(gr_poly
					(pts
						(arc
							(start -0.1778 -0.2794)
							(mid -0.249642 -0.249642)
							(end -0.2794 -0.1778)
						)
						(arc
							(start -0.2794 0.1778)
							(mid -0.249642 0.249642)
							(end -0.1778 0.2794)
						)
						(arc
							(start 0.1778 0.2794)
							(mid 0.249642 0.249642)
							(end 0.2794 0.1778)
						)
						(arc
							(start 0.2794 -0.1778)
							(mid 0.249642 -0.249642)
							(end 0.1778 -0.2794)
						)
					)
					(width 0)
					(fill yes)
				)
			)
		)
		(pad "2" smd custom
			(at 0 0.4445)
			(size 0.1397 0.1397)
			(layers "F.Cu" "F.Mask" "F.Paste")
			(net "I2C_DPB_A_SCL")
			(options
				(clearance outline)
				(anchor circle)
			)
			(primitives
				(gr_poly
					(pts
						(arc
							(start -0.1778 -0.2794)
							(mid -0.249642 -0.249642)
							(end -0.2794 -0.1778)
						)
						(arc
							(start -0.2794 0.1778)
							(mid -0.249642 0.249642)
							(end -0.1778 0.2794)
						)
						(arc
							(start 0.1778 0.2794)
							(mid 0.249642 0.249642)
							(end 0.2794 0.1778)
						)
						(arc
							(start 0.2794 -0.1778)
							(mid 0.249642 -0.249642)
							(end 0.1778 -0.2794)
						)
					)
					(width 0)
					(fill yes)
				)
			)
		)
	)
	(footprint ""
		(layer "F.Cu")
		(at 7.3914 -49.022 -90)
		(property "Reference" "U7"
			(at 0 0 270)
			(layer "F.SilkS")
			(hide yes)
			(effects
				(font
					(size 1.27 1.27)
				)
			)
		)
		(property "Value" "TMP75AIDGKR-GP"
			(at -0.1143 -9.1948 270)
			(unlocked yes)
			(layer "F.Fab")
			(hide yes)
			(effects
				(font
					(size 1.016 1.016)
					(thickness 0.1524)
				)
			)
		)
		(property "Device Type" "MSOP8-1H44"
			(at -0.1143 -10.795 270)
			(unlocked yes)
			(layer "F.Fab")
			(hide yes)
			(effects
				(font
					(size 1.016 1.016)
					(thickness 0.1524)
				)
			)
		)
		(duplicate_pad_numbers_are_jumpers no)
		(fp_line
			(start -1.778 1.0922)
			(end -1.778 3.048)
			(stroke
				(width 0.508)
				(type default)
			)
			(layer "F.SilkS")
		)
		(fp_line
			(start -1.9558 1.016)
			(end 1.0795 1.016)
			(stroke
				(width 0.1524)
				(type default)
			)
			(layer "F.SilkS")
		)
		(fp_line
			(start 1.0795 1.016)
			(end 1.0795 -1.016)
			(stroke
				(width 0.1524)
				(type default)
			)
			(layer "F.SilkS")
		)
		(fp_line
			(start -1.4478 -0.0381)
			(end -1.9558 0.4699)
			(stroke
				(width 0.1524)
				(type default)
			)
			(layer "F.SilkS")
		)
		(fp_line
			(start -1.9558 -0.5461)
			(end -1.4478 -0.0381)
			(stroke
				(width 0.1524)
				(type default)
			)
			(layer "F.SilkS")
		)
		(fp_line
			(start -1.9558 -1.016)
			(end -1.9558 1.016)
			(stroke
				(width 0.1524)
				(type default)
			)
			(layer "F.SilkS")
		)
		(fp_line
			(start 1.0795 -1.016)
			(end -1.9558 -1.016)
			(stroke
				(width 0.1524)
				(type default)
			)
			(layer "F.SilkS")
		)
		(fp_poly
			(pts
				(xy -1.1557 -1.016) (xy -1.1557 1.016) (xy 1.1557 1.016) (xy 1.1557 -1.016)
			)
			(stroke
				(width 0)
				(type default)
			)
			(fill yes)
			(layer "F.SilkS")
		)
		(fp_rect
			(start -1.4986 2.4511)
			(end 1.4986 -2.4511)
			(stroke
				(width 0)
				(type default)
			)
			(fill no)
			(layer "F.CrtYd")
		)
		(fp_poly
			(pts
				(xy -2.032 3.302) (xy -2.032 -3.302) (xy 2.032 -3.302) (xy 2.032 -2.1209) (xy 1.4986 -2.1209) (xy 1.4986 -2.4511)
				(xy -1.4986 -2.4511) (xy -1.4986 2.4511) (xy 1.4986 2.4511) (xy 1.4986 -2.1082) (xy 2.032 -2.1082)
				(xy 2.032 3.302)
			)
			(stroke
				(width 0)
				(type default)
			)
			(fill no)
			(layer "F.CrtYd")
		)
		(fp_rect
			(start -2.032 3.302)
			(end 2.032 -3.302)
			(stroke
				(width 0)
				(type default)
			)
			(fill no)
			(layer "F.Fab")
		)
		(pad "1" smd rect
			(at -0.97536 2.05486 270)
			(size 0.3556 1.524)
			(layers "F.Cu" "F.Mask" "F.Paste")
			(net "TEMP_1_SDA")
		)
		(pad "2" smd rect
			(at -0.32512 2.05486 270)
			(size 0.3556 1.524)
			(layers "F.Cu" "F.Mask" "F.Paste")
			(net "TEMP_1_SCL")
		)
		(pad "3" smd rect
			(at 0.32512 2.05486 270)
			(size 0.3556 1.524)
			(layers "F.Cu" "F.Mask" "F.Paste")
			(net "TEMP_1_ALERT")
		)
		(pad "4" smd rect
			(at 0.97536 2.05486 270)
			(size 0.3556 1.524)
			(layers "F.Cu" "F.Mask" "F.Paste")
			(net "GND")
		)
		(pad "5" smd rect
			(at 0.97536 -2.05486 270)
			(size 0.3556 1.524)
			(layers "F.Cu" "F.Mask" "F.Paste")
			(net "TEMP_1_A2")
		)
		(pad "6" smd rect
			(at 0.32512 -2.05486 270)
			(size 0.3556 1.524)
			(layers "F.Cu" "F.Mask" "F.Paste")
			(net "TEMP_1_A1")
		)
		(pad "7" smd rect
			(at -0.32512 -2.05486 270)
			(size 0.3556 1.524)
			(layers "F.Cu" "F.Mask" "F.Paste")
			(net "TEMP_1_A0")
		)
		(pad "8" smd rect
			(at -0.97536 -2.05486 270)
			(size 0.3556 1.524)
			(layers "F.Cu" "F.Mask" "F.Paste")
			(net "P3V3_STBY_A")
		)
	)
	(footprint ""
		(layer "F.Cu")
		(at 50.23104 -13.976858)
		(property "Reference" "C10"
			(at 0 0 0)
			(layer "F.SilkS")
			(hide yes)
			(effects
				(font
					(size 1.27 1.27)
				)
			)
		)
		(property "Value" "SCD1U16V2KX-3GP"
			(at 1.1811 -3.3909 0)
			(unlocked yes)
			(layer "F.Fab")
			(hide yes)
			(effects
				(font
					(size 2.54 2.54)
					(thickness 0.381)
				)
			)
		)
		(property "Device Type" "C402H22"
			(at 1.1811 -4.9149 0)
			(unlocked yes)
			(layer "F.Fab")
			(hide yes)
			(effects
				(font
					(size 2.54 2.54)
					(thickness 0.381)
				)
			)
		)
		(duplicate_pad_numbers_are_jumpers no)
		(fp_rect
			(start -0.4318 0.9525)
			(end 0.4318 -0.9525)
			(stroke
				(width 0)
				(type default)
			)
			(fill no)
			(layer "F.CrtYd")
		)
		(fp_rect
			(start -0.4318 0.9525)
			(end 0.4318 -0.9525)
			(stroke
				(width 0)
				(type default)
			)
			(fill no)
			(layer "F.Fab")
		)
		(pad "1" smd custom
			(at 0 -0.4445)
			(size 0.1524 0.1524)
			(layers "F.Cu" "F.Mask" "F.Paste")
			(net "P3V3_STBY_B")
			(options
				(clearance outline)
				(anchor circle)
			)
			(primitives
				(gr_poly
					(pts
						(arc
							(start 0.3048 -0.2032)
							(mid 0.275042 -0.275042)
							(end 0.2032 -0.3048)
						)
						(arc
							(start -0.2032 -0.3048)
							(mid -0.275042 -0.275042)
							(end -0.3048 -0.2032)
						)
						(arc
							(start -0.3048 0.2032)
							(mid -0.275042 0.275042)
							(end -0.2032 0.3048)
						)
						(arc
							(start 0.2032 0.3048)
							(mid 0.275042 0.275042)
							(end 0.3048 0.2032)
						)
					)
					(width 0)
					(fill yes)
				)
			)
		)
		(pad "2" smd custom
			(at 0 0.4445)
			(size 0.1524 0.1524)
			(layers "F.Cu" "F.Mask" "F.Paste")
			(net "GND")
			(options
				(clearance outline)
				(anchor circle)
			)
			(primitives
				(gr_poly
					(pts
						(arc
							(start 0.3048 -0.2032)
							(mid 0.275042 -0.275042)
							(end 0.2032 -0.3048)
						)
						(arc
							(start -0.2032 -0.3048)
							(mid -0.275042 -0.275042)
							(end -0.3048 -0.2032)
						)
						(arc
							(start -0.3048 0.2032)
							(mid -0.275042 0.275042)
							(end -0.2032 0.3048)
						)
						(arc
							(start 0.2032 0.3048)
							(mid 0.275042 0.275042)
							(end 0.3048 0.2032)
						)
					)
					(width 0)
					(fill yes)
				)
			)
		)
	)
	(footprint ""
		(layer "F.Cu")
		(at 27.9146 -6.3246 90)
		(property "Reference" "R16"
			(at 0 0 90)
			(layer "F.SilkS")
			(hide yes)
			(effects
				(font
					(size 1.27 1.27)
				)
			)
		)
		(property "Value" "0R2J-2-GP"
			(at 0.064008 -3.993896 90)
			(unlocked yes)
			(layer "F.Fab")
			(hide yes)
			(effects
				(font
					(size 1.016 1.016)
					(thickness 0.1524)
				)
			)
		)
		(property "Device Type" "R402H16"
			(at 0.064008 -5.517896 90)
			(unlocked yes)
			(layer "F.Fab")
			(hide yes)
			(effects
				(font
					(size 1.016 1.016)
					(thickness 0.1524)
				)
			)
		)
		(duplicate_pad_numbers_are_jumpers no)
		(fp_line
			(start 0.508 -0.9398)
			(end -0.508 -0.9398)
			(stroke
				(width 0.1524)
				(type default)
			)
			(layer "F.SilkS")
		)
		(fp_line
			(start -0.508 -0.9398)
			(end -0.508 0.9398)
			(stroke
				(width 0.1524)
				(type default)
			)
			(layer "F.SilkS")
		)
		(fp_rect
			(start -0.508 0.9398)
			(end 0.508 -0.9398)
			(stroke
				(width 0)
				(type default)
			)
			(fill no)
			(layer "F.CrtYd")
		)
		(fp_rect
			(start -0.508 0.9398)
			(end 0.508 -0.9398)
			(stroke
				(width 0)
				(type default)
			)
			(fill no)
			(layer "F.Fab")
		)
		(pad "1" smd custom
			(at 0 -0.4445 90)
			(size 0.1397 0.1397)
			(layers "F.Cu" "F.Mask" "F.Paste")
			(net "D_FLIP_A_D")
			(options
				(clearance outline)
				(anchor circle)
			)
			(primitives
				(gr_poly
					(pts
						(arc
							(start -0.1778 -0.2794)
							(mid -0.249642 -0.249642)
							(end -0.2794 -0.1778)
						)
						(arc
							(start -0.2794 0.1778)
							(mid -0.249642 0.249642)
							(end -0.1778 0.2794)
						)
						(arc
							(start 0.1778 0.2794)
							(mid 0.249642 0.249642)
							(end 0.2794 0.1778)
						)
						(arc
							(start 0.2794 -0.1778)
							(mid 0.249642 -0.249642)
							(end 0.1778 -0.2794)
						)
					)
					(width 0)
					(fill yes)
				)
			)
		)
		(pad "2" smd custom
			(at 0 0.4445 90)
			(size 0.1397 0.1397)
			(layers "F.Cu" "F.Mask" "F.Paste")
			(net "D_FLIP_A_Q#")
			(options
				(clearance outline)
				(anchor circle)
			)
			(primitives
				(gr_poly
					(pts
						(arc
							(start -0.1778 -0.2794)
							(mid -0.249642 -0.249642)
							(end -0.2794 -0.1778)
						)
						(arc
							(start -0.2794 0.1778)
							(mid -0.249642 0.249642)
							(end -0.1778 0.2794)
						)
						(arc
							(start 0.1778 0.2794)
							(mid 0.249642 0.249642)
							(end 0.2794 0.1778)
						)
						(arc
							(start 0.2794 -0.1778)
							(mid 0.249642 -0.249642)
							(end 0.1778 -0.2794)
						)
					)
					(width 0)
					(fill yes)
				)
			)
		)
	)
	(footprint ""
		(layer "F.Cu")
		(at 33.6804 -9.1186 180)
		(property "Reference" "C30"
			(at 0 0 180)
			(layer "F.SilkS")
			(hide yes)
			(effects
				(font
					(size 1.27 1.27)
				)
			)
		)
		(property "Value" "SCD1U16V2KX-3GP"
			(at 1.1811 -2.7051 180)
			(unlocked yes)
			(layer "F.Fab")
			(hide yes)
			(effects
				(font
					(size 1.016 1.016)
					(thickness 0.1524)
				)
			)
		)
		(property "Device Type" "C402H22"
			(at 1.1811 -4.2291 180)
			(unlocked yes)
			(layer "F.Fab")
			(hide yes)
			(effects
				(font
					(size 1.016 1.016)
					(thickness 0.1524)
				)
			)
		)
		(duplicate_pad_numbers_are_jumpers no)
		(fp_rect
			(start -0.4318 0.9525)
			(end 0.4318 -0.9525)
			(stroke
				(width 0)
				(type default)
			)
			(fill no)
			(layer "F.CrtYd")
		)
		(fp_rect
			(start -0.4318 0.9525)
			(end 0.4318 -0.9525)
			(stroke
				(width 0)
				(type default)
			)
			(fill no)
			(layer "F.Fab")
		)
		(pad "1" smd custom
			(at 0 -0.4445 180)
			(size 0.1524 0.1524)
			(layers "F.Cu" "F.Mask" "F.Paste")
			(net "P3V3_STBY_B")
			(options
				(clearance outline)
				(anchor circle)
			)
			(primitives
				(gr_poly
					(pts
						(arc
							(start 0.3048 -0.2032)
							(mid 0.275042 -0.275042)
							(end 0.2032 -0.3048)
						)
						(arc
							(start -0.2032 -0.3048)
							(mid -0.275042 -0.275042)
							(end -0.3048 -0.2032)
						)
						(arc
							(start -0.3048 0.2032)
							(mid -0.275042 0.275042)
							(end -0.2032 0.3048)
						)
						(arc
							(start 0.2032 0.3048)
							(mid 0.275042 0.275042)
							(end 0.3048 0.2032)
						)
					)
					(width 0)
					(fill yes)
				)
			)
		)
		(pad "2" smd custom
			(at 0 0.4445 180)
			(size 0.1524 0.1524)
			(layers "F.Cu" "F.Mask" "F.Paste")
			(net "GND")
			(options
				(clearance outline)
				(anchor circle)
			)
			(primitives
				(gr_poly
					(pts
						(arc
							(start 0.3048 -0.2032)
							(mid 0.275042 -0.275042)
							(end 0.2032 -0.3048)
						)
						(arc
							(start -0.2032 -0.3048)
							(mid -0.275042 -0.275042)
							(end -0.3048 -0.2032)
						)
						(arc
							(start -0.3048 0.2032)
							(mid -0.275042 0.275042)
							(end -0.2032 0.3048)
						)
						(arc
							(start 0.2032 0.3048)
							(mid 0.275042 0.275042)
							(end 0.3048 0.2032)
						)
					)
					(width 0)
					(fill yes)
				)
			)
		)
	)
	(footprint ""
		(layer "F.Cu")
		(at 2.820162 -59.905138 180)
		(property "Reference" "L1"
			(at 0 0 180)
			(layer "F.SilkS")
			(hide yes)
			(effects
				(font
					(size 1.27 1.27)
				)
			)
		)
		(property "Value" "BLM21PG300SN-2GP"
			(at 0.0254 -6.3754 180)
			(unlocked yes)
			(layer "F.Fab")
			(hide yes)
			(effects
				(font
					(size 2.54 2.54)
					(thickness 0.381)
				)
			)
		)
		(property "Device Type" "L20125H42"
			(at 0.0254 -8.2804 180)
			(unlocked yes)
			(layer "F.Fab")
			(hide yes)
			(effects
				(font
					(size 2.54 2.54)
					(thickness 0.381)
				)
			)
		)
		(duplicate_pad_numbers_are_jumpers no)
		(fp_line
			(start 0.9144 1.7018)
			(end 0.9144 -1.7018)
			(stroke
				(width 0.1524)
				(type default)
			)
			(layer "F.SilkS")
		)
		(fp_line
			(start 0.9144 -1.7018)
			(end -0.9144 -1.7018)
			(stroke
				(width 0.1524)
				(type default)
			)
			(layer "F.SilkS")
		)
		(fp_line
			(start -0.9144 1.7018)
			(end 0.9144 1.7018)
			(stroke
				(width 0.1524)
				(type default)
			)
			(layer "F.SilkS")
		)
		(fp_line
			(start -0.9144 -1.7018)
			(end -0.9144 1.7018)
			(stroke
				(width 0.1524)
				(type default)
			)
			(layer "F.SilkS")
		)
		(fp_rect
			(start -1.0033 1.778)
			(end 1.0033 -1.778)
			(stroke
				(width 0)
				(type default)
			)
			(fill no)
			(layer "F.CrtYd")
		)
		(fp_poly
			(pts
				(xy -1.0033 -1.778) (xy 1.0033 -1.778) (xy 1.0033 1.778) (xy -1.0033 1.778)
			)
			(stroke
				(width 0)
				(type default)
			)
			(fill no)
			(layer "F.Fab")
		)
		(pad "1" smd rect
			(at 0 -0.9652 180)
			(size 1.397 1.143)
			(layers "F.Cu" "F.Mask" "F.Paste")
			(net "P5V_VBUS_A")
		)
		(pad "2" smd rect
			(at 0 0.9652 180)
			(size 1.397 1.143)
			(layers "F.Cu" "F.Mask" "F.Paste")
			(net "P5V_USB_A")
		)
	)
	(footprint ""
		(layer "F.Cu")
		(at 3.8862 -72.5551 180)
		(property "Reference" "D7"
			(at 0 0 180)
			(layer "F.SilkS")
			(hide yes)
			(effects
				(font
					(size 1.27 1.27)
				)
			)
		)
		(property "Value" "PESD5V0X1UAB-GP"
			(at 0 -4.690618 180)
			(unlocked yes)
			(layer "F.Fab")
			(hide yes)
			(effects
				(font
					(size 1.016 1.016)
					(thickness 0.1524)
				)
			)
		)
		(property "Device Type" "SOD523AKH26"
			(at 0 -6.214618 180)
			(unlocked yes)
			(layer "F.Fab")
			(hide yes)
			(effects
				(font
					(size 1.016 1.016)
					(thickness 0.1524)
				)
			)
		)
		(duplicate_pad_numbers_are_jumpers no)
		(fp_line
			(start 0.5334 1.524)
			(end -0.5334 1.524)
			(stroke
				(width 0.1524)
				(type default)
			)
			(layer "F.SilkS")
		)
		(fp_line
			(start 0.5334 -1.4478)
			(end 0.5334 1.524)
			(stroke
				(width 0.1524)
				(type default)
			)
			(layer "F.SilkS")
		)
		(fp_line
			(start 0.4064 1.651)
			(end -0.4064 1.651)
			(stroke
				(width 0.4064)
				(type default)
			)
			(layer "F.SilkS")
		)
		(fp_line
			(start -0.5334 1.524)
			(end -0.5334 -1.4478)
			(stroke
				(width 0.1524)
				(type default)
			)
			(layer "F.SilkS")
		)
		(fp_line
			(start -0.5334 -1.4478)
			(end 0.5334 -1.4478)
			(stroke
				(width 0.1524)
				(type default)
			)
			(layer "F.SilkS")
		)
		(fp_rect
			(start -0.6096 1.8542)
			(end 0.6096 -1.524)
			(stroke
				(width 0)
				(type default)
			)
			(fill no)
			(layer "F.CrtYd")
		)
		(fp_poly
			(pts
				(xy -0.6096 -1.524) (xy 0.6096 -1.524) (xy 0.6096 1.8542) (xy -0.6096 1.8542)
			)
			(stroke
				(width 0)
				(type default)
			)
			(fill no)
			(layer "F.Fab")
		)
		(pad "A" smd rect
			(at 0 -0.762 180)
			(size 0.5588 1.016)
			(layers "F.Cu" "F.Mask" "F.Paste")
			(net "GND")
		)
		(pad "K" smd rect
			(at 0 0.762 180)
			(size 0.5588 1.016)
			(layers "F.Cu" "F.Mask" "F.Paste")
			(net "PWR_BTN_A")
		)
	)
	(footprint ""
		(layer "F.Cu")
		(at 31.70301 -9.903714 180)
		(property "Reference" "U20"
			(at 0 0 180)
			(layer "F.SilkS")
			(hide yes)
			(effects
				(font
					(size 1.27 1.27)
				)
			)
		)
		(property "Value" "SN74LVC1G74DCUT-GP"
			(at 0 -11.1252 180)
			(unlocked yes)
			(layer "F.Fab")
			(hide yes)
			(effects
				(font
					(size 1.016 1.016)
					(thickness 0.1524)
				)
			)
		)
		(property "Device Type" "SSOIC8-4H36"
			(at 0 -12.6492 180)
			(unlocked yes)
			(layer "F.Fab")
			(hide yes)
			(effects
				(font
					(size 1.016 1.016)
					(thickness 0.1524)
				)
			)
		)
		(duplicate_pad_numbers_are_jumpers no)
		(fp_line
			(start 1.2573 2.1844)
			(end -1.2573 2.1844)
			(stroke
				(width 0.1524)
				(type default)
			)
			(layer "F.SilkS")
		)
		(fp_line
			(start 1.2573 -2.1844)
			(end 1.2573 2.1844)
			(stroke
				(width 0.1524)
				(type default)
			)
			(layer "F.SilkS")
		)
		(fp_line
			(start -0.9017 -0.0381)
			(end -1.2065 0.2667)
			(stroke
				(width 0.1524)
				(type default)
			)
			(layer "F.SilkS")
		)
		(fp_line
			(start -1.2065 0.2667)
			(end -1.27 0.2667)
			(stroke
				(width 0.1524)
				(type default)
			)
			(layer "F.SilkS")
		)
		(fp_line
			(start -1.2192 -0.3556)
			(end -0.9017 -0.0381)
			(stroke
				(width 0.1524)
				(type default)
			)
			(layer "F.SilkS")
		)
		(fp_line
			(start -1.2573 2.1844)
			(end -1.2573 -2.1844)
			(stroke
				(width 0.1524)
				(type default)
			)
			(layer "F.SilkS")
		)
		(fp_line
			(start -1.2573 -0.3556)
			(end -1.2192 -0.3556)
			(stroke
				(width 0.1524)
				(type default)
			)
			(layer "F.SilkS")
		)
		(fp_line
			(start -1.2573 -2.1844)
			(end 1.2573 -2.1844)
			(stroke
				(width 0.1524)
				(type default)
			)
			(layer "F.SilkS")
		)
		(fp_line
			(start -1.2954 0.4572)
			(end -1.2954 2.159)
			(stroke
				(width 0.4064)
				(type default)
			)
			(layer "F.SilkS")
		)
		(fp_poly
			(pts
				(xy -1.5113 2.4384) (xy 1.5113 2.4384) (xy 1.5113 -2.4384) (xy -1.5113 -2.4384)
			)
			(stroke
				(width 0)
				(type default)
			)
			(fill no)
			(layer "F.CrtYd")
		)
		(fp_poly
			(pts
				(xy -1.5113 -2.4384) (xy 1.5113 -2.4384) (xy 1.5113 2.4384) (xy -1.5113 2.4384)
			)
			(stroke
				(width 0)
				(type default)
			)
			(fill no)
			(layer "F.Fab")
		)
		(pad "1" smd rect
			(at -0.75057 1.1684 180)
			(size 0.3048 1.524)
			(layers "F.Cu" "F.Mask" "F.Paste")
			(net "DEBUG_HDR_B_UART_SEL")
		)
		(pad "2" smd rect
			(at -0.25019 1.1684 180)
			(size 0.3048 1.524)
			(layers "F.Cu" "F.Mask" "F.Paste")
			(net "D_FLIP_B_D")
		)
		(pad "3" smd rect
			(at 0.25019 1.1684 180)
			(size 0.3048 1.524)
			(layers "F.Cu" "F.Mask" "F.Paste")
			(net "D_FLIP_B_Q#")
		)
		(pad "4" smd rect
			(at 0.75057 1.1684 180)
			(size 0.3048 1.524)
			(layers "F.Cu" "F.Mask" "F.Paste")
			(net "GND")
		)
		(pad "5" smd rect
			(at 0.75057 -1.1684 180)
			(size 0.3048 1.524)
			(layers "F.Cu" "F.Mask" "F.Paste")
			(net "UART_SEL_B_MUX")
		)
		(pad "6" smd rect
			(at 0.25019 -1.1684 180)
			(size 0.3048 1.524)
			(layers "F.Cu" "F.Mask" "F.Paste")
			(net "D_FLIP_CLR_B#")
		)
		(pad "7" smd rect
			(at -0.25019 -1.1684 180)
			(size 0.3048 1.524)
			(layers "F.Cu" "F.Mask" "F.Paste")
			(net "D_FLIP_PRE_B#")
		)
		(pad "8" smd rect
			(at -0.75057 -1.1684 180)
			(size 0.3048 1.524)
			(layers "F.Cu" "F.Mask" "F.Paste")
			(net "P3V3_STBY_B")
		)
	)
	(footprint ""
		(layer "F.Cu")
		(at 42.917364 -21.64842 180)
		(property "Reference" "C24"
			(at 0 0 180)
			(layer "F.SilkS")
			(hide yes)
			(effects
				(font
					(size 1.27 1.27)
				)
			)
		)
		(property "Value" "SCD1U16V2KX-3GP"
			(at 1.1811 -2.7051 180)
			(unlocked yes)
			(layer "F.Fab")
			(hide yes)
			(effects
				(font
					(size 1.016 1.016)
					(thickness 0.1524)
				)
			)
		)
		(property "Device Type" "C402H22"
			(at 1.1811 -4.2291 180)
			(unlocked yes)
			(layer "F.Fab")
			(hide yes)
			(effects
				(font
					(size 1.016 1.016)
					(thickness 0.1524)
				)
			)
		)
		(duplicate_pad_numbers_are_jumpers no)
		(fp_rect
			(start -0.4318 0.9525)
			(end 0.4318 -0.9525)
			(stroke
				(width 0)
				(type default)
			)
			(fill no)
			(layer "F.CrtYd")
		)
		(fp_rect
			(start -0.4318 0.9525)
			(end 0.4318 -0.9525)
			(stroke
				(width 0)
				(type default)
			)
			(fill no)
			(layer "F.Fab")
		)
		(pad "1" smd custom
			(at 0 -0.4445 180)
			(size 0.1524 0.1524)
			(layers "F.Cu" "F.Mask" "F.Paste")
			(net "P3V3_STBY_B")
			(options
				(clearance outline)
				(anchor circle)
			)
			(primitives
				(gr_poly
					(pts
						(arc
							(start 0.3048 -0.2032)
							(mid 0.275042 -0.275042)
							(end 0.2032 -0.3048)
						)
						(arc
							(start -0.2032 -0.3048)
							(mid -0.275042 -0.275042)
							(end -0.3048 -0.2032)
						)
						(arc
							(start -0.3048 0.2032)
							(mid -0.275042 0.275042)
							(end -0.2032 0.3048)
						)
						(arc
							(start 0.2032 0.3048)
							(mid 0.275042 0.275042)
							(end 0.3048 0.2032)
						)
					)
					(width 0)
					(fill yes)
				)
			)
		)
		(pad "2" smd custom
			(at 0 0.4445 180)
			(size 0.1524 0.1524)
			(layers "F.Cu" "F.Mask" "F.Paste")
			(net "GND")
			(options
				(clearance outline)
				(anchor circle)
			)
			(primitives
				(gr_poly
					(pts
						(arc
							(start 0.3048 -0.2032)
							(mid 0.275042 -0.275042)
							(end 0.2032 -0.3048)
						)
						(arc
							(start -0.2032 -0.3048)
							(mid -0.275042 -0.275042)
							(end -0.3048 -0.2032)
						)
						(arc
							(start -0.3048 0.2032)
							(mid -0.275042 0.275042)
							(end -0.2032 0.3048)
						)
						(arc
							(start 0.2032 0.3048)
							(mid 0.275042 0.275042)
							(end 0.3048 0.2032)
						)
					)
					(width 0)
					(fill yes)
				)
			)
		)
	)
	(footprint ""
		(layer "F.Cu")
		(at 3.0734 -21.082)
		(property "Reference" "R6"
			(at 0 0 0)
			(layer "F.SilkS")
			(hide yes)
			(effects
				(font
					(size 1.27 1.27)
				)
			)
		)
		(property "Value" "4K7R2F-GP"
			(at 0.064008 -4.679696 0)
			(unlocked yes)
			(layer "F.Fab")
			(hide yes)
			(effects
				(font
					(size 2.54 2.54)
					(thickness 0.381)
				)
			)
		)
		(property "Device Type" "R402H16"
			(at 0.064008 -6.203696 0)
			(unlocked yes)
			(layer "F.Fab")
			(hide yes)
			(effects
				(font
					(size 2.54 2.54)
					(thickness 0.381)
				)
			)
		)
		(duplicate_pad_numbers_are_jumpers no)
		(fp_line
			(start -0.508 -0.9398)
			(end -0.508 0.9398)
			(stroke
				(width 0.1524)
				(type default)
			)
			(layer "F.SilkS")
		)
		(fp_line
			(start 0.508 -0.9398)
			(end -0.508 -0.9398)
			(stroke
				(width 0.1524)
				(type default)
			)
			(layer "F.SilkS")
		)
		(fp_rect
			(start -0.508 0.9398)
			(end 0.508 -0.9398)
			(stroke
				(width 0)
				(type default)
			)
			(fill no)
			(layer "F.CrtYd")
		)
		(fp_rect
			(start -0.508 0.9398)
			(end 0.508 -0.9398)
			(stroke
				(width 0)
				(type default)
			)
			(fill no)
			(layer "F.Fab")
		)
		(pad "1" smd custom
			(at 0 -0.4445)
			(size 0.1397 0.1397)
			(layers "F.Cu" "F.Mask" "F.Paste")
			(net "P3V3_STBY_A")
			(options
				(clearance outline)
				(anchor circle)
			)
			(primitives
				(gr_poly
					(pts
						(arc
							(start -0.1778 -0.2794)
							(mid -0.249642 -0.249642)
							(end -0.2794 -0.1778)
						)
						(arc
							(start -0.2794 0.1778)
							(mid -0.249642 0.249642)
							(end -0.1778 0.2794)
						)
						(arc
							(start 0.1778 0.2794)
							(mid 0.249642 0.249642)
							(end 0.2794 0.1778)
						)
						(arc
							(start 0.2794 -0.1778)
							(mid 0.249642 -0.249642)
							(end 0.1778 -0.2794)
						)
					)
					(width 0)
					(fill yes)
				)
			)
		)
		(pad "2" smd custom
			(at 0 0.4445)
			(size 0.1397 0.1397)
			(layers "F.Cu" "F.Mask" "F.Paste")
			(net "I2C_DEBUG_A_SCL")
			(options
				(clearance outline)
				(anchor circle)
			)
			(primitives
				(gr_poly
					(pts
						(arc
							(start -0.1778 -0.2794)
							(mid -0.249642 -0.249642)
							(end -0.2794 -0.1778)
						)
						(arc
							(start -0.2794 0.1778)
							(mid -0.249642 0.249642)
							(end -0.1778 0.2794)
						)
						(arc
							(start 0.1778 0.2794)
							(mid 0.249642 0.249642)
							(end 0.2794 0.1778)
						)
						(arc
							(start 0.2794 -0.1778)
							(mid 0.249642 -0.249642)
							(end 0.1778 -0.2794)
						)
					)
					(width 0)
					(fill yes)
				)
			)
		)
	)
	(footprint ""
		(layer "F.Cu")
		(at 12.487148 -39.158418 90)
		(property "Reference" "R21"
			(at 0 0 90)
			(layer "F.SilkS")
			(hide yes)
			(effects
				(font
					(size 1.27 1.27)
				)
			)
		)
		(property "Value" "22KR2F-GP"
			(at 0.064008 -4.679696 90)
			(unlocked yes)
			(layer "F.Fab")
			(hide yes)
			(effects
				(font
					(size 2.54 2.54)
					(thickness 0.381)
				)
			)
		)
		(property "Device Type" "R402H16"
			(at 0.064008 -6.203696 90)
			(unlocked yes)
			(layer "F.Fab")
			(hide yes)
			(effects
				(font
					(size 2.54 2.54)
					(thickness 0.381)
				)
			)
		)
		(duplicate_pad_numbers_are_jumpers no)
		(fp_line
			(start 0.508 -0.9398)
			(end -0.508 -0.9398)
			(stroke
				(width 0.1524)
				(type default)
			)
			(layer "F.SilkS")
		)
		(fp_line
			(start -0.508 -0.9398)
			(end -0.508 0.9398)
			(stroke
				(width 0.1524)
				(type default)
			)
			(layer "F.SilkS")
		)
		(fp_rect
			(start -0.508 0.9398)
			(end 0.508 -0.9398)
			(stroke
				(width 0)
				(type default)
			)
			(fill no)
			(layer "F.CrtYd")
		)
		(fp_rect
			(start -0.508 0.9398)
			(end 0.508 -0.9398)
			(stroke
				(width 0)
				(type default)
			)
			(fill no)
			(layer "F.Fab")
		)
		(pad "1" smd custom
			(at 0 -0.4445 90)
			(size 0.1397 0.1397)
			(layers "F.Cu" "F.Mask" "F.Paste")
			(net "P3V3_STBY_A")
			(options
				(clearance outline)
				(anchor circle)
			)
			(primitives
				(gr_poly
					(pts
						(arc
							(start -0.1778 -0.2794)
							(mid -0.249642 -0.249642)
							(end -0.2794 -0.1778)
						)
						(arc
							(start -0.2794 0.1778)
							(mid -0.249642 0.249642)
							(end -0.1778 0.2794)
						)
						(arc
							(start 0.1778 0.2794)
							(mid 0.249642 0.249642)
							(end 0.2794 0.1778)
						)
						(arc
							(start 0.2794 -0.1778)
							(mid 0.249642 -0.249642)
							(end 0.1778 -0.2794)
						)
					)
					(width 0)
					(fill yes)
				)
			)
		)
		(pad "2" smd custom
			(at 0 0.4445 90)
			(size 0.1397 0.1397)
			(layers "F.Cu" "F.Mask" "F.Paste")
			(net "SYS_RESET_BTN_A")
			(options
				(clearance outline)
				(anchor circle)
			)
			(primitives
				(gr_poly
					(pts
						(arc
							(start -0.1778 -0.2794)
							(mid -0.249642 -0.249642)
							(end -0.2794 -0.1778)
						)
						(arc
							(start -0.2794 0.1778)
							(mid -0.249642 0.249642)
							(end -0.1778 0.2794)
						)
						(arc
							(start 0.1778 0.2794)
							(mid 0.249642 0.249642)
							(end 0.2794 0.1778)
						)
						(arc
							(start 0.2794 -0.1778)
							(mid 0.249642 -0.249642)
							(end 0.1778 -0.2794)
						)
					)
					(width 0)
					(fill yes)
				)
			)
		)
	)
	(footprint ""
		(layer "F.Cu")
		(at 42.909744 -19.739102)
		(property "Reference" "R13"
			(at 0 0 0)
			(layer "F.SilkS")
			(hide yes)
			(effects
				(font
					(size 1.27 1.27)
				)
			)
		)
		(property "Value" "4K7R2F-GP"
			(at 0.064008 -4.679696 0)
			(unlocked yes)
			(layer "F.Fab")
			(hide yes)
			(effects
				(font
					(size 2.54 2.54)
					(thickness 0.381)
				)
			)
		)
		(property "Device Type" "R402H16"
			(at 0.064008 -6.203696 0)
			(unlocked yes)
			(layer "F.Fab")
			(hide yes)
			(effects
				(font
					(size 2.54 2.54)
					(thickness 0.381)
				)
			)
		)
		(duplicate_pad_numbers_are_jumpers no)
		(fp_line
			(start -0.508 -0.9398)
			(end -0.508 0.9398)
			(stroke
				(width 0.1524)
				(type default)
			)
			(layer "F.SilkS")
		)
		(fp_line
			(start 0.508 -0.9398)
			(end -0.508 -0.9398)
			(stroke
				(width 0.1524)
				(type default)
			)
			(layer "F.SilkS")
		)
		(fp_rect
			(start -0.508 0.9398)
			(end 0.508 -0.9398)
			(stroke
				(width 0)
				(type default)
			)
			(fill no)
			(layer "F.CrtYd")
		)
		(fp_rect
			(start -0.508 0.9398)
			(end 0.508 -0.9398)
			(stroke
				(width 0)
				(type default)
			)
			(fill no)
			(layer "F.Fab")
		)
		(pad "1" smd custom
			(at 0 -0.4445)
			(size 0.1397 0.1397)
			(layers "F.Cu" "F.Mask" "F.Paste")
			(net "P3V3_STBY_B")
			(options
				(clearance outline)
				(anchor circle)
			)
			(primitives
				(gr_poly
					(pts
						(arc
							(start -0.1778 -0.2794)
							(mid -0.249642 -0.249642)
							(end -0.2794 -0.1778)
						)
						(arc
							(start -0.2794 0.1778)
							(mid -0.249642 0.249642)
							(end -0.1778 0.2794)
						)
						(arc
							(start 0.1778 0.2794)
							(mid 0.249642 0.249642)
							(end 0.2794 0.1778)
						)
						(arc
							(start 0.2794 -0.1778)
							(mid 0.249642 -0.249642)
							(end 0.1778 -0.2794)
						)
					)
					(width 0)
					(fill yes)
				)
			)
		)
		(pad "2" smd custom
			(at 0 0.4445)
			(size 0.1397 0.1397)
			(layers "F.Cu" "F.Mask" "F.Paste")
			(net "I2C_DEBUG_B_SCL")
			(options
				(clearance outline)
				(anchor circle)
			)
			(primitives
				(gr_poly
					(pts
						(arc
							(start -0.1778 -0.2794)
							(mid -0.249642 -0.249642)
							(end -0.2794 -0.1778)
						)
						(arc
							(start -0.2794 0.1778)
							(mid -0.249642 0.249642)
							(end -0.1778 0.2794)
						)
						(arc
							(start 0.1778 0.2794)
							(mid 0.249642 0.249642)
							(end 0.2794 0.1778)
						)
						(arc
							(start 0.2794 -0.1778)
							(mid 0.249642 -0.249642)
							(end 0.1778 -0.2794)
						)
					)
					(width 0)
					(fill yes)
				)
			)
		)
	)
	(footprint ""
		(layer "F.Cu")
		(at 48.895 -17.399 180)
		(property "Reference" "R70"
			(at 0 0 180)
			(layer "F.SilkS")
			(hide yes)
			(effects
				(font
					(size 1.27 1.27)
				)
			)
		)
		(property "Value" "4K7R2F-GP"
			(at 0.064008 -3.993896 180)
			(unlocked yes)
			(layer "F.Fab")
			(hide yes)
			(effects
				(font
					(size 1.016 1.016)
					(thickness 0.1524)
				)
			)
		)
		(property "Device Type" "R402H16"
			(at 0.064008 -5.517896 180)
			(unlocked yes)
			(layer "F.Fab")
			(hide yes)
			(effects
				(font
					(size 1.016 1.016)
					(thickness 0.1524)
				)
			)
		)
		(duplicate_pad_numbers_are_jumpers no)
		(fp_line
			(start 0.508 -0.9398)
			(end -0.508 -0.9398)
			(stroke
				(width 0.1524)
				(type default)
			)
			(layer "F.SilkS")
		)
		(fp_line
			(start -0.508 -0.9398)
			(end -0.508 0.9398)
			(stroke
				(width 0.1524)
				(type default)
			)
			(layer "F.SilkS")
		)
		(fp_rect
			(start -0.508 0.9398)
			(end 0.508 -0.9398)
			(stroke
				(width 0)
				(type default)
			)
			(fill no)
			(layer "F.CrtYd")
		)
		(fp_rect
			(start -0.508 0.9398)
			(end 0.508 -0.9398)
			(stroke
				(width 0)
				(type default)
			)
			(fill no)
			(layer "F.Fab")
		)
		(pad "1" smd custom
			(at 0 -0.4445 180)
			(size 0.1397 0.1397)
			(layers "F.Cu" "F.Mask" "F.Paste")
			(net "TCA9555_B_A0")
			(options
				(clearance outline)
				(anchor circle)
			)
			(primitives
				(gr_poly
					(pts
						(arc
							(start -0.1778 -0.2794)
							(mid -0.249642 -0.249642)
							(end -0.2794 -0.1778)
						)
						(arc
							(start -0.2794 0.1778)
							(mid -0.249642 0.249642)
							(end -0.1778 0.2794)
						)
						(arc
							(start 0.1778 0.2794)
							(mid 0.249642 0.249642)
							(end 0.2794 0.1778)
						)
						(arc
							(start 0.2794 -0.1778)
							(mid 0.249642 -0.249642)
							(end 0.1778 -0.2794)
						)
					)
					(width 0)
					(fill yes)
				)
			)
		)
		(pad "2" smd custom
			(at 0 0.4445 180)
			(size 0.1397 0.1397)
			(layers "F.Cu" "F.Mask" "F.Paste")
			(net "GND")
			(options
				(clearance outline)
				(anchor circle)
			)
			(primitives
				(gr_poly
					(pts
						(arc
							(start -0.1778 -0.2794)
							(mid -0.249642 -0.249642)
							(end -0.2794 -0.1778)
						)
						(arc
							(start -0.2794 0.1778)
							(mid -0.249642 0.249642)
							(end -0.1778 0.2794)
						)
						(arc
							(start 0.1778 0.2794)
							(mid 0.249642 0.249642)
							(end 0.2794 0.1778)
						)
						(arc
							(start 0.2794 -0.1778)
							(mid 0.249642 -0.249642)
							(end 0.1778 -0.2794)
						)
					)
					(width 0)
					(fill yes)
				)
			)
		)
	)
	(footprint ""
		(layer "F.Cu")
		(at 54.706012 -7.01167 180)
		(property "Reference" "R74"
			(at 0 0 180)
			(layer "F.SilkS")
			(hide yes)
			(effects
				(font
					(size 1.27 1.27)
				)
			)
		)
		(property "Value" "4K7R2F-GP"
			(at 0.064008 -3.993896 180)
			(unlocked yes)
			(layer "F.Fab")
			(hide yes)
			(effects
				(font
					(size 1.016 1.016)
					(thickness 0.1524)
				)
			)
		)
		(property "Device Type" "R402H16"
			(at 0.064008 -5.517896 180)
			(unlocked yes)
			(layer "F.Fab")
			(hide yes)
			(effects
				(font
					(size 1.016 1.016)
					(thickness 0.1524)
				)
			)
		)
		(duplicate_pad_numbers_are_jumpers no)
		(fp_line
			(start 0.508 -0.9398)
			(end -0.508 -0.9398)
			(stroke
				(width 0.1524)
				(type default)
			)
			(layer "F.SilkS")
		)
		(fp_line
			(start -0.508 -0.9398)
			(end -0.508 0.9398)
			(stroke
				(width 0.1524)
				(type default)
			)
			(layer "F.SilkS")
		)
		(fp_rect
			(start -0.508 0.9398)
			(end 0.508 -0.9398)
			(stroke
				(width 0)
				(type default)
			)
			(fill no)
			(layer "F.CrtYd")
		)
		(fp_rect
			(start -0.508 0.9398)
			(end 0.508 -0.9398)
			(stroke
				(width 0)
				(type default)
			)
			(fill no)
			(layer "F.Fab")
		)
		(pad "1" smd custom
			(at 0 -0.4445 180)
			(size 0.1397 0.1397)
			(layers "F.Cu" "F.Mask" "F.Paste")
			(net "P3V3_STBY_B")
			(options
				(clearance outline)
				(anchor circle)
			)
			(primitives
				(gr_poly
					(pts
						(arc
							(start -0.1778 -0.2794)
							(mid -0.249642 -0.249642)
							(end -0.2794 -0.1778)
						)
						(arc
							(start -0.2794 0.1778)
							(mid -0.249642 0.249642)
							(end -0.1778 0.2794)
						)
						(arc
							(start 0.1778 0.2794)
							(mid 0.249642 0.249642)
							(end 0.2794 0.1778)
						)
						(arc
							(start 0.2794 -0.1778)
							(mid 0.249642 -0.249642)
							(end 0.1778 -0.2794)
						)
					)
					(width 0)
					(fill yes)
				)
			)
		)
		(pad "2" smd custom
			(at 0 0.4445 180)
			(size 0.1397 0.1397)
			(layers "F.Cu" "F.Mask" "F.Paste")
			(net "TCA9555_B_A2")
			(options
				(clearance outline)
				(anchor circle)
			)
			(primitives
				(gr_poly
					(pts
						(arc
							(start -0.1778 -0.2794)
							(mid -0.249642 -0.249642)
							(end -0.2794 -0.1778)
						)
						(arc
							(start -0.2794 0.1778)
							(mid -0.249642 0.249642)
							(end -0.1778 0.2794)
						)
						(arc
							(start 0.1778 0.2794)
							(mid 0.249642 0.249642)
							(end 0.2794 0.1778)
						)
						(arc
							(start 0.2794 -0.1778)
							(mid 0.249642 -0.249642)
							(end 0.1778 -0.2794)
						)
					)
					(width 0)
					(fill yes)
				)
			)
		)
	)
	(footprint ""
		(layer "F.Cu")
		(at 50.673 -48.7934 -90)
		(property "Reference" "U8"
			(at 0 0 270)
			(layer "F.SilkS")
			(hide yes)
			(effects
				(font
					(size 1.27 1.27)
				)
			)
		)
		(property "Value" "TMP75AIDGKR-GP"
			(at -0.1143 -9.1948 270)
			(unlocked yes)
			(layer "F.Fab")
			(hide yes)
			(effects
				(font
					(size 1.016 1.016)
					(thickness 0.1524)
				)
			)
		)
		(property "Device Type" "MSOP8-1H44"
			(at -0.1143 -10.795 270)
			(unlocked yes)
			(layer "F.Fab")
			(hide yes)
			(effects
				(font
					(size 1.016 1.016)
					(thickness 0.1524)
				)
			)
		)
		(duplicate_pad_numbers_are_jumpers no)
		(fp_line
			(start -1.778 1.0922)
			(end -1.778 3.048)
			(stroke
				(width 0.508)
				(type default)
			)
			(layer "F.SilkS")
		)
		(fp_line
			(start -1.9558 1.016)
			(end 1.0795 1.016)
			(stroke
				(width 0.1524)
				(type default)
			)
			(layer "F.SilkS")
		)
		(fp_line
			(start 1.0795 1.016)
			(end 1.0795 -1.016)
			(stroke
				(width 0.1524)
				(type default)
			)
			(layer "F.SilkS")
		)
		(fp_line
			(start -1.4478 -0.0381)
			(end -1.9558 0.4699)
			(stroke
				(width 0.1524)
				(type default)
			)
			(layer "F.SilkS")
		)
		(fp_line
			(start -1.9558 -0.5461)
			(end -1.4478 -0.0381)
			(stroke
				(width 0.1524)
				(type default)
			)
			(layer "F.SilkS")
		)
		(fp_line
			(start -1.9558 -1.016)
			(end -1.9558 1.016)
			(stroke
				(width 0.1524)
				(type default)
			)
			(layer "F.SilkS")
		)
		(fp_line
			(start 1.0795 -1.016)
			(end -1.9558 -1.016)
			(stroke
				(width 0.1524)
				(type default)
			)
			(layer "F.SilkS")
		)
		(fp_poly
			(pts
				(xy -1.1557 -1.016) (xy -1.1557 1.016) (xy 1.1557 1.016) (xy 1.1557 -1.016)
			)
			(stroke
				(width 0)
				(type default)
			)
			(fill yes)
			(layer "F.SilkS")
		)
		(fp_rect
			(start -1.4986 2.4511)
			(end 1.4986 -2.4511)
			(stroke
				(width 0)
				(type default)
			)
			(fill no)
			(layer "F.CrtYd")
		)
		(fp_poly
			(pts
				(xy -2.032 3.302) (xy -2.032 -3.302) (xy 2.032 -3.302) (xy 2.032 -2.1209) (xy 1.4986 -2.1209) (xy 1.4986 -2.4511)
				(xy -1.4986 -2.4511) (xy -1.4986 2.4511) (xy 1.4986 2.4511) (xy 1.4986 -2.1082) (xy 2.032 -2.1082)
				(xy 2.032 3.302)
			)
			(stroke
				(width 0)
				(type default)
			)
			(fill no)
			(layer "F.CrtYd")
		)
		(fp_rect
			(start -2.032 3.302)
			(end 2.032 -3.302)
			(stroke
				(width 0)
				(type default)
			)
			(fill no)
			(layer "F.Fab")
		)
		(pad "1" smd rect
			(at -0.97536 2.05486 270)
			(size 0.3556 1.524)
			(layers "F.Cu" "F.Mask" "F.Paste")
			(net "TEMP_2_SDA")
		)
		(pad "2" smd rect
			(at -0.32512 2.05486 270)
			(size 0.3556 1.524)
			(layers "F.Cu" "F.Mask" "F.Paste")
			(net "TEMP_2_SCL")
		)
		(pad "3" smd rect
			(at 0.32512 2.05486 270)
			(size 0.3556 1.524)
			(layers "F.Cu" "F.Mask" "F.Paste")
			(net "TEMP_2_ALERT")
		)
		(pad "4" smd rect
			(at 0.97536 2.05486 270)
			(size 0.3556 1.524)
			(layers "F.Cu" "F.Mask" "F.Paste")
			(net "GND")
		)
		(pad "5" smd rect
			(at 0.97536 -2.05486 270)
			(size 0.3556 1.524)
			(layers "F.Cu" "F.Mask" "F.Paste")
			(net "TEMP_2_A2")
		)
		(pad "6" smd rect
			(at 0.32512 -2.05486 270)
			(size 0.3556 1.524)
			(layers "F.Cu" "F.Mask" "F.Paste")
			(net "TEMP_2_A1")
		)
		(pad "7" smd rect
			(at -0.32512 -2.05486 270)
			(size 0.3556 1.524)
			(layers "F.Cu" "F.Mask" "F.Paste")
			(net "TEMP_2_A0")
		)
		(pad "8" smd rect
			(at -0.97536 -2.05486 270)
			(size 0.3556 1.524)
			(layers "F.Cu" "F.Mask" "F.Paste")
			(net "P3V3_STBY_B")
		)
	)
	(footprint ""
		(layer "F.Cu")
		(at 55.0164 -29.2608 90)
		(property "Reference" "C18"
			(at 0 0 90)
			(layer "F.SilkS")
			(hide yes)
			(effects
				(font
					(size 1.27 1.27)
				)
			)
		)
		(property "Value" "SCD1U16V2KX-3GP"
			(at 1.1811 -3.3909 90)
			(unlocked yes)
			(layer "F.Fab")
			(hide yes)
			(effects
				(font
					(size 2.54 2.54)
					(thickness 0.381)
				)
			)
		)
		(property "Device Type" "C402H22"
			(at 1.1811 -4.9149 90)
			(unlocked yes)
			(layer "F.Fab")
			(hide yes)
			(effects
				(font
					(size 2.54 2.54)
					(thickness 0.381)
				)
			)
		)
		(duplicate_pad_numbers_are_jumpers no)
		(fp_rect
			(start -0.4318 0.9525)
			(end 0.4318 -0.9525)
			(stroke
				(width 0)
				(type default)
			)
			(fill no)
			(layer "F.CrtYd")
		)
		(fp_rect
			(start -0.4318 0.9525)
			(end 0.4318 -0.9525)
			(stroke
				(width 0)
				(type default)
			)
			(fill no)
			(layer "F.Fab")
		)
		(pad "1" smd custom
			(at 0 -0.4445 90)
			(size 0.1524 0.1524)
			(layers "F.Cu" "F.Mask" "F.Paste")
			(net "P3V3_STBY_B")
			(options
				(clearance outline)
				(anchor circle)
			)
			(primitives
				(gr_poly
					(pts
						(arc
							(start 0.3048 -0.2032)
							(mid 0.275042 -0.275042)
							(end 0.2032 -0.3048)
						)
						(arc
							(start -0.2032 -0.3048)
							(mid -0.275042 -0.275042)
							(end -0.3048 -0.2032)
						)
						(arc
							(start -0.3048 0.2032)
							(mid -0.275042 0.275042)
							(end -0.2032 0.3048)
						)
						(arc
							(start 0.2032 0.3048)
							(mid 0.275042 0.275042)
							(end 0.3048 0.2032)
						)
					)
					(width 0)
					(fill yes)
				)
			)
		)
		(pad "2" smd custom
			(at 0 0.4445 90)
			(size 0.1524 0.1524)
			(layers "F.Cu" "F.Mask" "F.Paste")
			(net "GND")
			(options
				(clearance outline)
				(anchor circle)
			)
			(primitives
				(gr_poly
					(pts
						(arc
							(start 0.3048 -0.2032)
							(mid 0.275042 -0.275042)
							(end 0.2032 -0.3048)
						)
						(arc
							(start -0.2032 -0.3048)
							(mid -0.275042 -0.275042)
							(end -0.3048 -0.2032)
						)
						(arc
							(start -0.3048 0.2032)
							(mid -0.275042 0.275042)
							(end -0.2032 0.3048)
						)
						(arc
							(start 0.2032 0.3048)
							(mid 0.275042 0.275042)
							(end 0.3048 0.2032)
						)
					)
					(width 0)
					(fill yes)
				)
			)
		)
	)
	(footprint ""
		(layer "F.Cu")
		(at 9.525 -23.2156 90)
		(property "Reference" "R77"
			(at 0 0 90)
			(layer "F.SilkS")
			(hide yes)
			(effects
				(font
					(size 1.27 1.27)
				)
			)
		)
		(property "Value" "4K7R2F-GP"
			(at 0.064008 -3.993896 90)
			(unlocked yes)
			(layer "F.Fab")
			(hide yes)
			(effects
				(font
					(size 1.016 1.016)
					(thickness 0.1524)
				)
			)
		)
		(property "Device Type" "R402H16"
			(at 0.064008 -5.517896 90)
			(unlocked yes)
			(layer "F.Fab")
			(hide yes)
			(effects
				(font
					(size 1.016 1.016)
					(thickness 0.1524)
				)
			)
		)
		(duplicate_pad_numbers_are_jumpers no)
		(fp_line
			(start 0.508 -0.9398)
			(end -0.508 -0.9398)
			(stroke
				(width 0.1524)
				(type default)
			)
			(layer "F.SilkS")
		)
		(fp_line
			(start -0.508 -0.9398)
			(end -0.508 0.9398)
			(stroke
				(width 0.1524)
				(type default)
			)
			(layer "F.SilkS")
		)
		(fp_rect
			(start -0.508 0.9398)
			(end 0.508 -0.9398)
			(stroke
				(width 0)
				(type default)
			)
			(fill no)
			(layer "F.CrtYd")
		)
		(fp_rect
			(start -0.508 0.9398)
			(end 0.508 -0.9398)
			(stroke
				(width 0)
				(type default)
			)
			(fill no)
			(layer "F.Fab")
		)
		(pad "1" smd custom
			(at 0 -0.4445 90)
			(size 0.1397 0.1397)
			(layers "F.Cu" "F.Mask" "F.Paste")
			(net "P3V3_STBY_A")
			(options
				(clearance outline)
				(anchor circle)
			)
			(primitives
				(gr_poly
					(pts
						(arc
							(start -0.1778 -0.2794)
							(mid -0.249642 -0.249642)
							(end -0.2794 -0.1778)
						)
						(arc
							(start -0.2794 0.1778)
							(mid -0.249642 0.249642)
							(end -0.1778 0.2794)
						)
						(arc
							(start 0.1778 0.2794)
							(mid 0.249642 0.249642)
							(end 0.2794 0.1778)
						)
						(arc
							(start 0.2794 -0.1778)
							(mid 0.249642 -0.249642)
							(end 0.1778 -0.2794)
						)
					)
					(width 0)
					(fill yes)
				)
			)
		)
		(pad "2" smd custom
			(at 0 0.4445 90)
			(size 0.1397 0.1397)
			(layers "F.Cu" "F.Mask" "F.Paste")
			(net "DEBUG_RST_A_BTN_N")
			(options
				(clearance outline)
				(anchor circle)
			)
			(primitives
				(gr_poly
					(pts
						(arc
							(start -0.1778 -0.2794)
							(mid -0.249642 -0.249642)
							(end -0.2794 -0.1778)
						)
						(arc
							(start -0.2794 0.1778)
							(mid -0.249642 0.249642)
							(end -0.1778 0.2794)
						)
						(arc
							(start 0.1778 0.2794)
							(mid 0.249642 0.249642)
							(end 0.2794 0.1778)
						)
						(arc
							(start 0.2794 -0.1778)
							(mid 0.249642 -0.249642)
							(end 0.1778 -0.2794)
						)
					)
					(width 0)
					(fill yes)
				)
			)
		)
	)
	(footprint ""
		(layer "F.Cu")
		(at 2.436622 -62.373764 -90)
		(property "Reference" "C4"
			(at 0 0 270)
			(layer "F.SilkS")
			(hide yes)
			(effects
				(font
					(size 1.27 1.27)
				)
			)
		)
		(property "Value" "SC1U16V3KX-5GP"
			(at 0 -3.5052 270)
			(unlocked yes)
			(layer "F.Fab")
			(hide yes)
			(effects
				(font
					(size 2.54 2.54)
					(thickness 0.381)
				)
			)
		)
		(property "Device Type" "C603H36"
			(at 0 -5.0292 270)
			(unlocked yes)
			(layer "F.Fab")
			(hide yes)
			(effects
				(font
					(size 2.54 2.54)
					(thickness 0.381)
				)
			)
		)
		(duplicate_pad_numbers_are_jumpers no)
		(fp_line
			(start 0.508 0)
			(end -0.508 0)
			(stroke
				(width 0.2032)
				(type default)
			)
			(layer "F.SilkS")
		)
		(fp_rect
			(start -0.5842 1.3335)
			(end 0.5842 -1.3335)
			(stroke
				(width 0)
				(type default)
			)
			(fill no)
			(layer "F.CrtYd")
		)
		(fp_rect
			(start -0.5842 1.3335)
			(end 0.5842 -1.3335)
			(stroke
				(width 0)
				(type default)
			)
			(fill no)
			(layer "F.Fab")
		)
		(pad "1" smd custom
			(at 0 -0.762 270)
			(size 0.2159 0.2159)
			(layers "F.Cu" "F.Mask" "F.Paste")
			(net "P5V_USB_A")
			(options
				(clearance outline)
				(anchor circle)
			)
			(primitives
				(gr_poly
					(pts
						(arc
							(start -0.3302 -0.4318)
							(mid -0.402042 -0.402042)
							(end -0.4318 -0.3302)
						)
						(arc
							(start -0.4318 0.3302)
							(mid -0.402042 0.402042)
							(end -0.3302 0.4318)
						)
						(arc
							(start 0.3302 0.4318)
							(mid 0.402042 0.402042)
							(end 0.4318 0.3302)
						)
						(arc
							(start 0.4318 -0.3302)
							(mid 0.402042 -0.402042)
							(end 0.3302 -0.4318)
						)
					)
					(width 0)
					(fill yes)
				)
			)
		)
		(pad "2" smd custom
			(at 0 0.762 270)
			(size 0.2159 0.2159)
			(layers "F.Cu" "F.Mask" "F.Paste")
			(net "GND")
			(options
				(clearance outline)
				(anchor circle)
			)
			(primitives
				(gr_poly
					(pts
						(arc
							(start -0.3302 -0.4318)
							(mid -0.402042 -0.402042)
							(end -0.4318 -0.3302)
						)
						(arc
							(start -0.4318 0.3302)
							(mid -0.402042 0.402042)
							(end -0.3302 0.4318)
						)
						(arc
							(start 0.3302 0.4318)
							(mid 0.402042 0.402042)
							(end 0.4318 0.3302)
						)
						(arc
							(start 0.4318 -0.3302)
							(mid 0.402042 -0.402042)
							(end 0.3302 -0.4318)
						)
					)
					(width 0)
					(fill yes)
				)
			)
		)
	)
	(footprint ""
		(layer "F.Cu")
		(at 52.197 -44.2976)
		(property "Reference" "R38"
			(at 0 0 0)
			(layer "F.SilkS")
			(hide yes)
			(effects
				(font
					(size 1.27 1.27)
				)
			)
		)
		(property "Value" "0R2J-2-GP"
			(at 0.064008 -4.679696 0)
			(unlocked yes)
			(layer "F.Fab")
			(hide yes)
			(effects
				(font
					(size 2.54 2.54)
					(thickness 0.381)
				)
			)
		)
		(property "Device Type" "R402H16"
			(at 0.064008 -6.203696 0)
			(unlocked yes)
			(layer "F.Fab")
			(hide yes)
			(effects
				(font
					(size 2.54 2.54)
					(thickness 0.381)
				)
			)
		)
		(duplicate_pad_numbers_are_jumpers no)
		(fp_line
			(start -0.508 -0.9398)
			(end -0.508 0.9398)
			(stroke
				(width 0.1524)
				(type default)
			)
			(layer "F.SilkS")
		)
		(fp_line
			(start 0.508 -0.9398)
			(end -0.508 -0.9398)
			(stroke
				(width 0.1524)
				(type default)
			)
			(layer "F.SilkS")
		)
		(fp_rect
			(start -0.508 0.9398)
			(end 0.508 -0.9398)
			(stroke
				(width 0)
				(type default)
			)
			(fill no)
			(layer "F.CrtYd")
		)
		(fp_rect
			(start -0.508 0.9398)
			(end 0.508 -0.9398)
			(stroke
				(width 0)
				(type default)
			)
			(fill no)
			(layer "F.Fab")
		)
		(pad "1" smd custom
			(at 0 -0.4445)
			(size 0.1397 0.1397)
			(layers "F.Cu" "F.Mask" "F.Paste")
			(net "TEMP_2_SCL")
			(options
				(clearance outline)
				(anchor circle)
			)
			(primitives
				(gr_poly
					(pts
						(arc
							(start -0.1778 -0.2794)
							(mid -0.249642 -0.249642)
							(end -0.2794 -0.1778)
						)
						(arc
							(start -0.2794 0.1778)
							(mid -0.249642 0.249642)
							(end -0.1778 0.2794)
						)
						(arc
							(start 0.1778 0.2794)
							(mid 0.249642 0.249642)
							(end 0.2794 0.1778)
						)
						(arc
							(start 0.2794 -0.1778)
							(mid 0.249642 -0.249642)
							(end 0.1778 -0.2794)
						)
					)
					(width 0)
					(fill yes)
				)
			)
		)
		(pad "2" smd custom
			(at 0 0.4445)
			(size 0.1397 0.1397)
			(layers "F.Cu" "F.Mask" "F.Paste")
			(net "I2C_DPB_B_SCL")
			(options
				(clearance outline)
				(anchor circle)
			)
			(primitives
				(gr_poly
					(pts
						(arc
							(start -0.1778 -0.2794)
							(mid -0.249642 -0.249642)
							(end -0.2794 -0.1778)
						)
						(arc
							(start -0.2794 0.1778)
							(mid -0.249642 0.249642)
							(end -0.1778 0.2794)
						)
						(arc
							(start 0.1778 0.2794)
							(mid 0.249642 0.249642)
							(end 0.2794 0.1778)
						)
						(arc
							(start 0.2794 -0.1778)
							(mid 0.249642 -0.249642)
							(end 0.1778 -0.2794)
						)
					)
					(width 0)
					(fill yes)
				)
			)
		)
	)
	(footprint ""
		(layer "F.Cu")
		(at 9.298686 -40.573452 -90)
		(property "Reference" "R25"
			(at 0 0 270)
			(layer "F.SilkS")
			(hide yes)
			(effects
				(font
					(size 1.27 1.27)
				)
			)
		)
		(property "Value" "120R3J-2-GP"
			(at -0.0254 -3.2004 270)
			(unlocked yes)
			(layer "F.Fab")
			(hide yes)
			(effects
				(font
					(size 2.54 2.54)
					(thickness 0.381)
				)
			)
		)
		(property "Device Type" "R603H22"
			(at -0.0254 -4.7244 270)
			(unlocked yes)
			(layer "F.Fab")
			(hide yes)
			(effects
				(font
					(size 2.54 2.54)
					(thickness 0.381)
				)
			)
		)
		(duplicate_pad_numbers_are_jumpers no)
		(fp_line
			(start -0.4826 0)
			(end -0.2032 0)
			(stroke
				(width 0.2032)
				(type default)
			)
			(layer "F.SilkS")
		)
		(fp_line
			(start 0.2032 0)
			(end 0.4826 0)
			(stroke
				(width 0.2032)
				(type default)
			)
			(layer "F.SilkS")
		)
		(fp_rect
			(start -0.5842 1.3335)
			(end 0.5842 -1.3335)
			(stroke
				(width 0)
				(type default)
			)
			(fill no)
			(layer "F.CrtYd")
		)
		(fp_rect
			(start -0.5842 1.3335)
			(end 0.5842 -1.3335)
			(stroke
				(width 0)
				(type default)
			)
			(fill no)
			(layer "F.Fab")
		)
		(pad "1" smd custom
			(at 0 -0.762 270)
			(size 0.2159 0.2159)
			(layers "F.Cu" "F.Mask" "F.Paste")
			(net "P5V_USB_A")
			(options
				(clearance outline)
				(anchor circle)
			)
			(primitives
				(gr_poly
					(pts
						(arc
							(start -0.3302 -0.4318)
							(mid -0.402042 -0.402042)
							(end -0.4318 -0.3302)
						)
						(arc
							(start -0.4318 0.3302)
							(mid -0.402042 0.402042)
							(end -0.3302 0.4318)
						)
						(arc
							(start 0.3302 0.4318)
							(mid 0.402042 0.402042)
							(end 0.4318 0.3302)
						)
						(arc
							(start 0.4318 -0.3302)
							(mid 0.402042 -0.402042)
							(end 0.3302 -0.4318)
						)
					)
					(width 0)
					(fill yes)
				)
			)
		)
		(pad "2" smd custom
			(at 0 0.762 270)
			(size 0.2159 0.2159)
			(layers "F.Cu" "F.Mask" "F.Paste")
			(net "SYS_FAULT_A_R")
			(options
				(clearance outline)
				(anchor circle)
			)
			(primitives
				(gr_poly
					(pts
						(arc
							(start -0.3302 -0.4318)
							(mid -0.402042 -0.402042)
							(end -0.4318 -0.3302)
						)
						(arc
							(start -0.4318 0.3302)
							(mid -0.402042 0.402042)
							(end -0.3302 0.4318)
						)
						(arc
							(start 0.3302 0.4318)
							(mid 0.402042 0.402042)
							(end 0.4318 0.3302)
						)
						(arc
							(start 0.4318 -0.3302)
							(mid 0.402042 -0.402042)
							(end 0.3302 -0.4318)
						)
					)
					(width 0)
					(fill yes)
				)
			)
		)
	)
	(footprint ""
		(layer "F.Cu")
		(at 7.747 -70.358 -90)
		(property "Reference" "C16"
			(at 0 0 270)
			(layer "F.SilkS")
			(hide yes)
			(effects
				(font
					(size 1.27 1.27)
				)
			)
		)
		(property "Value" "SC1000P2KV6KX-GP-U"
			(at 0.0508 -3.5052 270)
			(unlocked yes)
			(layer "F.Fab")
			(hide yes)
			(effects
				(font
					(size 1.016 1.016)
					(thickness 0.1524)
				)
			)
		)
		(property "Device Type" "C1206H58"
			(at 0.0508 -5.0292 270)
			(unlocked yes)
			(layer "F.Fab")
			(hide yes)
			(effects
				(font
					(size 1.016 1.016)
					(thickness 0.1524)
				)
			)
		)
		(duplicate_pad_numbers_are_jumpers no)
		(fp_line
			(start -1.016 2.2352)
			(end -1.016 0.8128)
			(stroke
				(width 0.1524)
				(type default)
			)
			(layer "F.SilkS")
		)
		(fp_line
			(start 1.016 2.2352)
			(end -1.016 2.2352)
			(stroke
				(width 0.1524)
				(type default)
			)
			(layer "F.SilkS")
		)
		(fp_line
			(start 1.016 0.8382)
			(end 1.016 2.2352)
			(stroke
				(width 0.1524)
				(type default)
			)
			(layer "F.SilkS")
		)
		(fp_line
			(start -1.016 -2.2352)
			(end -1.016 -0.8382)
			(stroke
				(width 0.1524)
				(type default)
			)
			(layer "F.SilkS")
		)
		(fp_line
			(start 1.016 -2.2352)
			(end 1.016 -0.8382)
			(stroke
				(width 0.1524)
				(type default)
			)
			(layer "F.SilkS")
		)
		(fp_line
			(start 1.016 -2.2352)
			(end -1.016 -2.2352)
			(stroke
				(width 0.1524)
				(type default)
			)
			(layer "F.SilkS")
		)
		(fp_rect
			(start -1.0922 2.3114)
			(end 1.0922 -2.3114)
			(stroke
				(width 0)
				(type default)
			)
			(fill no)
			(layer "F.CrtYd")
		)
		(fp_poly
			(pts
				(xy -1.0922 -2.3114) (xy 1.0922 -2.3114) (xy 1.0922 2.3114) (xy -1.0922 2.3114)
			)
			(stroke
				(width 0)
				(type default)
			)
			(fill no)
			(layer "F.Fab")
		)
		(pad "1" smd rect
			(at 0 -1.397 270)
			(size 1.651 1.27)
			(layers "F.Cu" "F.Mask" "F.Paste")
			(net "USB_CONN_A_GND")
		)
		(pad "2" smd rect
			(at 0 1.397 270)
			(size 1.651 1.27)
			(layers "F.Cu" "F.Mask" "F.Paste")
			(net "GND")
		)
	)
	(footprint ""
		(layer "F.Cu")
		(at 49.696116 -72.650096 180)
		(property "Reference" "C7"
			(at 0 0 180)
			(layer "F.SilkS")
			(hide yes)
			(effects
				(font
					(size 1.27 1.27)
				)
			)
		)
		(property "Value" "SC1U16V3KX-5GP"
			(at 0 -3.5052 180)
			(unlocked yes)
			(layer "F.Fab")
			(hide yes)
			(effects
				(font
					(size 2.54 2.54)
					(thickness 0.381)
				)
			)
		)
		(property "Device Type" "C603H36"
			(at 0 -5.0292 180)
			(unlocked yes)
			(layer "F.Fab")
			(hide yes)
			(effects
				(font
					(size 2.54 2.54)
					(thickness 0.381)
				)
			)
		)
		(duplicate_pad_numbers_are_jumpers no)
		(fp_line
			(start 0.508 0)
			(end -0.508 0)
			(stroke
				(width 0.2032)
				(type default)
			)
			(layer "F.SilkS")
		)
		(fp_rect
			(start -0.5842 1.3335)
			(end 0.5842 -1.3335)
			(stroke
				(width 0)
				(type default)
			)
			(fill no)
			(layer "F.CrtYd")
		)
		(fp_rect
			(start -0.5842 1.3335)
			(end 0.5842 -1.3335)
			(stroke
				(width 0)
				(type default)
			)
			(fill no)
			(layer "F.Fab")
		)
		(pad "1" smd custom
			(at 0 -0.762 180)
			(size 0.2159 0.2159)
			(layers "F.Cu" "F.Mask" "F.Paste")
			(net "P5V_USB_B")
			(options
				(clearance outline)
				(anchor circle)
			)
			(primitives
				(gr_poly
					(pts
						(arc
							(start -0.3302 -0.4318)
							(mid -0.402042 -0.402042)
							(end -0.4318 -0.3302)
						)
						(arc
							(start -0.4318 0.3302)
							(mid -0.402042 0.402042)
							(end -0.3302 0.4318)
						)
						(arc
							(start 0.3302 0.4318)
							(mid 0.402042 0.402042)
							(end 0.4318 0.3302)
						)
						(arc
							(start 0.4318 -0.3302)
							(mid 0.402042 -0.402042)
							(end 0.3302 -0.4318)
						)
					)
					(width 0)
					(fill yes)
				)
			)
		)
		(pad "2" smd custom
			(at 0 0.762 180)
			(size 0.2159 0.2159)
			(layers "F.Cu" "F.Mask" "F.Paste")
			(net "GND")
			(options
				(clearance outline)
				(anchor circle)
			)
			(primitives
				(gr_poly
					(pts
						(arc
							(start -0.3302 -0.4318)
							(mid -0.402042 -0.402042)
							(end -0.4318 -0.3302)
						)
						(arc
							(start -0.4318 0.3302)
							(mid -0.402042 0.402042)
							(end -0.3302 0.4318)
						)
						(arc
							(start 0.3302 0.4318)
							(mid 0.402042 0.402042)
							(end 0.4318 0.3302)
						)
						(arc
							(start 0.4318 -0.3302)
							(mid 0.402042 -0.402042)
							(end 0.3302 -0.4318)
						)
					)
					(width 0)
					(fill yes)
				)
			)
		)
	)
	(footprint ""
		(layer "F.Cu")
		(at 55.583328 -32.145986)
		(property "Reference" "R53"
			(at 0 0 0)
			(layer "F.SilkS")
			(hide yes)
			(effects
				(font
					(size 1.27 1.27)
				)
			)
		)
		(property "Value" "4K7R2F-GP"
			(at 0.064008 -4.679696 0)
			(unlocked yes)
			(layer "F.Fab")
			(hide yes)
			(effects
				(font
					(size 2.54 2.54)
					(thickness 0.381)
				)
			)
		)
		(property "Device Type" "R402H16"
			(at 0.064008 -6.203696 0)
			(unlocked yes)
			(layer "F.Fab")
			(hide yes)
			(effects
				(font
					(size 2.54 2.54)
					(thickness 0.381)
				)
			)
		)
		(duplicate_pad_numbers_are_jumpers no)
		(fp_line
			(start -0.508 -0.9398)
			(end -0.508 0.9398)
			(stroke
				(width 0.1524)
				(type default)
			)
			(layer "F.SilkS")
		)
		(fp_line
			(start 0.508 -0.9398)
			(end -0.508 -0.9398)
			(stroke
				(width 0.1524)
				(type default)
			)
			(layer "F.SilkS")
		)
		(fp_rect
			(start -0.508 0.9398)
			(end 0.508 -0.9398)
			(stroke
				(width 0)
				(type default)
			)
			(fill no)
			(layer "F.CrtYd")
		)
		(fp_rect
			(start -0.508 0.9398)
			(end 0.508 -0.9398)
			(stroke
				(width 0)
				(type default)
			)
			(fill no)
			(layer "F.Fab")
		)
		(pad "1" smd custom
			(at 0 -0.4445)
			(size 0.1397 0.1397)
			(layers "F.Cu" "F.Mask" "F.Paste")
			(net "P3V3_STBY_B")
			(options
				(clearance outline)
				(anchor circle)
			)
			(primitives
				(gr_poly
					(pts
						(arc
							(start -0.1778 -0.2794)
							(mid -0.249642 -0.249642)
							(end -0.2794 -0.1778)
						)
						(arc
							(start -0.2794 0.1778)
							(mid -0.249642 0.249642)
							(end -0.1778 0.2794)
						)
						(arc
							(start 0.1778 0.2794)
							(mid 0.249642 0.249642)
							(end 0.2794 0.1778)
						)
						(arc
							(start 0.2794 -0.1778)
							(mid 0.249642 -0.249642)
							(end 0.1778 -0.2794)
						)
					)
					(width 0)
					(fill yes)
				)
			)
		)
		(pad "2" smd custom
			(at 0 0.4445)
			(size 0.1397 0.1397)
			(layers "F.Cu" "F.Mask" "F.Paste")
			(net "RST_B_TS")
			(options
				(clearance outline)
				(anchor circle)
			)
			(primitives
				(gr_poly
					(pts
						(arc
							(start -0.1778 -0.2794)
							(mid -0.249642 -0.249642)
							(end -0.2794 -0.1778)
						)
						(arc
							(start -0.2794 0.1778)
							(mid -0.249642 0.249642)
							(end -0.1778 0.2794)
						)
						(arc
							(start 0.1778 0.2794)
							(mid 0.249642 0.249642)
							(end 0.2794 0.1778)
						)
						(arc
							(start 0.2794 -0.1778)
							(mid 0.249642 -0.249642)
							(end 0.1778 -0.2794)
						)
					)
					(width 0)
					(fill yes)
				)
			)
		)
	)
	(footprint ""
		(layer "F.Cu")
		(at 8.199882 -43.999912 90)
		(property "Reference" "LED1"
			(at 0 0 90)
			(layer "F.SilkS")
			(hide yes)
			(effects
				(font
					(size 1.27 1.27)
				)
			)
		)
		(property "Value" "LED-Y-167-GP"
			(at 3.3274 -0.4572 90)
			(unlocked yes)
			(layer "F.Fab")
			(hide yes)
			(effects
				(font
					(size 1.016 1.016)
					(thickness 0.1524)
				)
			)
		)
		(property "Device Type" "LED-100-4035-1A2KH274"
			(at 3.3274 -1.9812 90)
			(unlocked yes)
			(layer "F.Fab")
			(hide yes)
			(effects
				(font
					(size 1.016 1.016)
					(thickness 0.1524)
				)
			)
		)
		(duplicate_pad_numbers_are_jumpers no)
		(fp_line
			(start 1.905 -0.254)
			(end 1.397 0.254)
			(stroke
				(width 0.1524)
				(type default)
			)
			(layer "F.SilkS")
		)
		(fp_line
			(start 1.397 -0.254)
			(end 1.397 -0.762)
			(stroke
				(width 0.1524)
				(type default)
			)
			(layer "F.SilkS")
		)
		(fp_line
			(start 0.889 -0.254)
			(end 1.905 -0.254)
			(stroke
				(width 0.1524)
				(type default)
			)
			(layer "F.SilkS")
		)
		(fp_line
			(start 1.397 0.254)
			(end 0.889 -0.254)
			(stroke
				(width 0.1524)
				(type default)
			)
			(layer "F.SilkS")
		)
		(fp_line
			(start 1.397 0.254)
			(end 1.397 0.762)
			(stroke
				(width 0.1524)
				(type default)
			)
			(layer "F.SilkS")
		)
		(fp_line
			(start 0.889 0.254)
			(end 1.905 0.254)
			(stroke
				(width 0.1524)
				(type default)
			)
			(layer "F.SilkS")
		)
		(fp_line
			(start 1.427988 1.7526)
			(end 0.685546 1.7526)
			(stroke
				(width 0.1524)
				(type default)
			)
			(layer "F.SilkS")
		)
		(fp_line
			(start -0.685546 1.7526)
			(end -1.427988 1.7526)
			(stroke
				(width 0.1524)
				(type default)
			)
			(layer "F.SilkS")
		)
		(fp_arc
			(start 0.685546 1.7526)
			(mid 0 2.108377)
			(end -0.685546 1.7526)
			(stroke
				(width 0.1524)
				(type default)
			)
			(layer "F.SilkS")
		)
		(fp_arc
			(start -1.427988 1.7526)
			(mid 0 -2.260698)
			(end 1.427988 1.7526)
			(stroke
				(width 0.1524)
				(type default)
			)
			(layer "F.SilkS")
		)
		(fp_circle
			(center 0 -1.27)
			(end 0 -0.3302)
			(stroke
				(width 0.3048)
				(type default)
			)
			(fill no)
			(layer "F.SilkS")
		)
		(fp_circle
			(center 0 1.27)
			(end 0 2.2098)
			(stroke
				(width 0.3048)
				(type default)
			)
			(fill no)
			(layer "F.SilkS")
		)
		(fp_poly
			(pts
				(arc
					(start -1.334516 1.4986)
					(mid 0 -2.006673)
					(end 1.334516 1.4986)
				)
			)
			(stroke
				(width 0)
				(type default)
			)
			(fill no)
			(layer "F.CrtYd")
		)
		(fp_poly
			(pts
				(arc
					(start 0.806704 2.0066)
					(mid 0 2.362406)
					(end -0.806704 2.0066)
				)
				(arc
					(start -1.515618 2.0066)
					(mid -1.123616 -2.249673)
					(end 2.5146 -0.00635)
				)
				(arc
					(start 2.006854 -0.00635)
					(mid -0.824269 -1.829777)
					(end -1.334516 1.498854)
				)
				(arc
					(start 1.334516 1.498854)
					(mid 1.829775 0.824269)
					(end 2.006854 0.00635)
				)
				(arc
					(start 2.5146 0.00635)
					(mid 2.249622 1.12359)
					(end 1.515618 2.0066)
				)
			)
			(stroke
				(width 0)
				(type default)
			)
			(fill no)
			(layer "F.CrtYd")
		)
		(fp_poly
			(pts
				(arc
					(start 0.806704 2.0066)
					(mid 0 2.362406)
					(end -0.806704 2.0066)
				)
				(arc
					(start -1.515618 2.0066)
					(mid 0 -2.514665)
					(end 1.515618 2.0066)
				)
			)
			(stroke
				(width 0)
				(type default)
			)
			(fill no)
			(layer "F.Fab")
		)
		(pad "1A" thru_hole circle
			(at 0 -1.27 90)
			(size 1.1684 1.1684)
			(drill 0.8128)
			(layers "*.Cu" "*.Mask")
			(remove_unused_layers no)
			(net "SYS_FAULT_A_R")
			(clearance 0.1778)
			(thermal_gap 0.1778)
		)
		(pad "2K" thru_hole circle
			(at 0 1.27 90)
			(size 1.1684 1.1684)
			(drill 0.8128)
			(layers "*.Cu" "*.Mask")
			(remove_unused_layers no)
			(net "FAULT_LED_A")
			(clearance 0.1778)
			(thermal_gap 0.1778)
		)
	)
	(footprint ""
		(layer "F.Cu")
		(at 12.7 -15.1638 -90)
		(property "Reference" "R7"
			(at 0 0 270)
			(layer "F.SilkS")
			(hide yes)
			(effects
				(font
					(size 1.27 1.27)
				)
			)
		)
		(property "Value" "0R2J-2-GP"
			(at 0.064008 -4.679696 270)
			(unlocked yes)
			(layer "F.Fab")
			(hide yes)
			(effects
				(font
					(size 2.54 2.54)
					(thickness 0.381)
				)
			)
		)
		(property "Device Type" "R402H16"
			(at 0.064008 -6.203696 270)
			(unlocked yes)
			(layer "F.Fab")
			(hide yes)
			(effects
				(font
					(size 2.54 2.54)
					(thickness 0.381)
				)
			)
		)
		(duplicate_pad_numbers_are_jumpers no)
		(fp_line
			(start -0.508 -0.9398)
			(end -0.508 0.9398)
			(stroke
				(width 0.1524)
				(type default)
			)
			(layer "F.SilkS")
		)
		(fp_line
			(start 0.508 -0.9398)
			(end -0.508 -0.9398)
			(stroke
				(width 0.1524)
				(type default)
			)
			(layer "F.SilkS")
		)
		(fp_rect
			(start -0.508 0.9398)
			(end 0.508 -0.9398)
			(stroke
				(width 0)
				(type default)
			)
			(fill no)
			(layer "F.CrtYd")
		)
		(fp_rect
			(start -0.508 0.9398)
			(end 0.508 -0.9398)
			(stroke
				(width 0)
				(type default)
			)
			(fill no)
			(layer "F.Fab")
		)
		(pad "1" smd custom
			(at 0 -0.4445 270)
			(size 0.1397 0.1397)
			(layers "F.Cu" "F.Mask" "F.Paste")
			(net "I2C_DEBUG_A_SCL_R")
			(options
				(clearance outline)
				(anchor circle)
			)
			(primitives
				(gr_poly
					(pts
						(arc
							(start -0.1778 -0.2794)
							(mid -0.249642 -0.249642)
							(end -0.2794 -0.1778)
						)
						(arc
							(start -0.2794 0.1778)
							(mid -0.249642 0.249642)
							(end -0.1778 0.2794)
						)
						(arc
							(start 0.1778 0.2794)
							(mid 0.249642 0.249642)
							(end 0.2794 0.1778)
						)
						(arc
							(start 0.2794 -0.1778)
							(mid 0.249642 -0.249642)
							(end 0.1778 -0.2794)
						)
					)
					(width 0)
					(fill yes)
				)
			)
		)
		(pad "2" smd custom
			(at 0 0.4445 270)
			(size 0.1397 0.1397)
			(layers "F.Cu" "F.Mask" "F.Paste")
			(net "I2C_DEBUG_A_SCL_L")
			(options
				(clearance outline)
				(anchor circle)
			)
			(primitives
				(gr_poly
					(pts
						(arc
							(start -0.1778 -0.2794)
							(mid -0.249642 -0.249642)
							(end -0.2794 -0.1778)
						)
						(arc
							(start -0.2794 0.1778)
							(mid -0.249642 0.249642)
							(end -0.1778 0.2794)
						)
						(arc
							(start 0.1778 0.2794)
							(mid 0.249642 0.249642)
							(end 0.2794 0.1778)
						)
						(arc
							(start 0.2794 -0.1778)
							(mid 0.249642 -0.249642)
							(end 0.1778 -0.2794)
						)
					)
					(width 0)
					(fill yes)
				)
			)
		)
	)
	(footprint ""
		(layer "F.Cu")
		(at 55.722012 -7.01167)
		(property "Reference" "R73"
			(at 0 0 0)
			(layer "F.SilkS")
			(hide yes)
			(effects
				(font
					(size 1.27 1.27)
				)
			)
		)
		(property "Value" "4K7R2F-GP"
			(at 0.064008 -3.993896 0)
			(unlocked yes)
			(layer "F.Fab")
			(hide yes)
			(effects
				(font
					(size 1.016 1.016)
					(thickness 0.1524)
				)
			)
		)
		(property "Device Type" "R402H16"
			(at 0.064008 -5.517896 0)
			(unlocked yes)
			(layer "F.Fab")
			(hide yes)
			(effects
				(font
					(size 1.016 1.016)
					(thickness 0.1524)
				)
			)
		)
		(duplicate_pad_numbers_are_jumpers no)
		(fp_line
			(start -0.508 -0.9398)
			(end -0.508 0.9398)
			(stroke
				(width 0.1524)
				(type default)
			)
			(layer "F.SilkS")
		)
		(fp_line
			(start 0.508 -0.9398)
			(end -0.508 -0.9398)
			(stroke
				(width 0.1524)
				(type default)
			)
			(layer "F.SilkS")
		)
		(fp_rect
			(start -0.508 0.9398)
			(end 0.508 -0.9398)
			(stroke
				(width 0)
				(type default)
			)
			(fill no)
			(layer "F.CrtYd")
		)
		(fp_rect
			(start -0.508 0.9398)
			(end 0.508 -0.9398)
			(stroke
				(width 0)
				(type default)
			)
			(fill no)
			(layer "F.Fab")
		)
		(pad "1" smd custom
			(at 0 -0.4445)
			(size 0.1397 0.1397)
			(layers "F.Cu" "F.Mask" "F.Paste")
			(net "TCA9555_B_A2")
			(options
				(clearance outline)
				(anchor circle)
			)
			(primitives
				(gr_poly
					(pts
						(arc
							(start -0.1778 -0.2794)
							(mid -0.249642 -0.249642)
							(end -0.2794 -0.1778)
						)
						(arc
							(start -0.2794 0.1778)
							(mid -0.249642 0.249642)
							(end -0.1778 0.2794)
						)
						(arc
							(start 0.1778 0.2794)
							(mid 0.249642 0.249642)
							(end 0.2794 0.1778)
						)
						(arc
							(start 0.2794 -0.1778)
							(mid 0.249642 -0.249642)
							(end 0.1778 -0.2794)
						)
					)
					(width 0)
					(fill yes)
				)
			)
		)
		(pad "2" smd custom
			(at 0 0.4445)
			(size 0.1397 0.1397)
			(layers "F.Cu" "F.Mask" "F.Paste")
			(net "GND")
			(options
				(clearance outline)
				(anchor circle)
			)
			(primitives
				(gr_poly
					(pts
						(arc
							(start -0.1778 -0.2794)
							(mid -0.249642 -0.249642)
							(end -0.2794 -0.1778)
						)
						(arc
							(start -0.2794 0.1778)
							(mid -0.249642 0.249642)
							(end -0.1778 0.2794)
						)
						(arc
							(start 0.1778 0.2794)
							(mid 0.249642 0.249642)
							(end 0.2794 0.1778)
						)
						(arc
							(start 0.2794 -0.1778)
							(mid 0.249642 -0.249642)
							(end 0.1778 -0.2794)
						)
					)
					(width 0)
					(fill yes)
				)
			)
		)
	)
	(footprint ""
		(layer "F.Cu")
		(at 9.913874 -17.984216 -90)
		(property "Reference" "R65"
			(at 0 0 270)
			(layer "F.SilkS")
			(hide yes)
			(effects
				(font
					(size 1.27 1.27)
				)
			)
		)
		(property "Value" "4K7R2F-GP"
			(at 0.064008 -3.993896 270)
			(unlocked yes)
			(layer "F.Fab")
			(hide yes)
			(effects
				(font
					(size 1.016 1.016)
					(thickness 0.1524)
				)
			)
		)
		(property "Device Type" "R402H16"
			(at 0.064008 -5.517896 270)
			(unlocked yes)
			(layer "F.Fab")
			(hide yes)
			(effects
				(font
					(size 1.016 1.016)
					(thickness 0.1524)
				)
			)
		)
		(duplicate_pad_numbers_are_jumpers no)
		(fp_line
			(start -0.508 -0.9398)
			(end -0.508 0.9398)
			(stroke
				(width 0.1524)
				(type default)
			)
			(layer "F.SilkS")
		)
		(fp_line
			(start 0.508 -0.9398)
			(end -0.508 -0.9398)
			(stroke
				(width 0.1524)
				(type default)
			)
			(layer "F.SilkS")
		)
		(fp_rect
			(start -0.508 0.9398)
			(end 0.508 -0.9398)
			(stroke
				(width 0)
				(type default)
			)
			(fill no)
			(layer "F.CrtYd")
		)
		(fp_rect
			(start -0.508 0.9398)
			(end 0.508 -0.9398)
			(stroke
				(width 0)
				(type default)
			)
			(fill no)
			(layer "F.Fab")
		)
		(pad "1" smd custom
			(at 0 -0.4445 270)
			(size 0.1397 0.1397)
			(layers "F.Cu" "F.Mask" "F.Paste")
			(net "TCA9555_A_A0")
			(options
				(clearance outline)
				(anchor circle)
			)
			(primitives
				(gr_poly
					(pts
						(arc
							(start -0.1778 -0.2794)
							(mid -0.249642 -0.249642)
							(end -0.2794 -0.1778)
						)
						(arc
							(start -0.2794 0.1778)
							(mid -0.249642 0.249642)
							(end -0.1778 0.2794)
						)
						(arc
							(start 0.1778 0.2794)
							(mid 0.249642 0.249642)
							(end 0.2794 0.1778)
						)
						(arc
							(start 0.2794 -0.1778)
							(mid 0.249642 -0.249642)
							(end 0.1778 -0.2794)
						)
					)
					(width 0)
					(fill yes)
				)
			)
		)
		(pad "2" smd custom
			(at 0 0.4445 270)
			(size 0.1397 0.1397)
			(layers "F.Cu" "F.Mask" "F.Paste")
			(net "GND")
			(options
				(clearance outline)
				(anchor circle)
			)
			(primitives
				(gr_poly
					(pts
						(arc
							(start -0.1778 -0.2794)
							(mid -0.249642 -0.249642)
							(end -0.2794 -0.1778)
						)
						(arc
							(start -0.2794 0.1778)
							(mid -0.249642 0.249642)
							(end -0.1778 0.2794)
						)
						(arc
							(start 0.1778 0.2794)
							(mid 0.249642 0.249642)
							(end 0.2794 0.1778)
						)
						(arc
							(start 0.2794 -0.1778)
							(mid 0.249642 -0.249642)
							(end 0.1778 -0.2794)
						)
					)
					(width 0)
					(fill yes)
				)
			)
		)
	)
	(footprint ""
		(layer "F.Cu")
		(at 10.16 -30.099 90)
		(property "Reference" "R50"
			(at 0 0 90)
			(layer "F.SilkS")
			(hide yes)
			(effects
				(font
					(size 1.27 1.27)
				)
			)
		)
		(property "Value" "4K7R2F-GP"
			(at 0.064008 -4.679696 90)
			(unlocked yes)
			(layer "F.Fab")
			(hide yes)
			(effects
				(font
					(size 2.54 2.54)
					(thickness 0.381)
				)
			)
		)
		(property "Device Type" "R402H16"
			(at 0.064008 -6.203696 90)
			(unlocked yes)
			(layer "F.Fab")
			(hide yes)
			(effects
				(font
					(size 2.54 2.54)
					(thickness 0.381)
				)
			)
		)
		(duplicate_pad_numbers_are_jumpers no)
		(fp_line
			(start 0.508 -0.9398)
			(end -0.508 -0.9398)
			(stroke
				(width 0.1524)
				(type default)
			)
			(layer "F.SilkS")
		)
		(fp_line
			(start -0.508 -0.9398)
			(end -0.508 0.9398)
			(stroke
				(width 0.1524)
				(type default)
			)
			(layer "F.SilkS")
		)
		(fp_rect
			(start -0.508 0.9398)
			(end 0.508 -0.9398)
			(stroke
				(width 0)
				(type default)
			)
			(fill no)
			(layer "F.CrtYd")
		)
		(fp_rect
			(start -0.508 0.9398)
			(end 0.508 -0.9398)
			(stroke
				(width 0)
				(type default)
			)
			(fill no)
			(layer "F.Fab")
		)
		(pad "1" smd custom
			(at 0 -0.4445 90)
			(size 0.1397 0.1397)
			(layers "F.Cu" "F.Mask" "F.Paste")
			(net "RST_A_TS")
			(options
				(clearance outline)
				(anchor circle)
			)
			(primitives
				(gr_poly
					(pts
						(arc
							(start -0.1778 -0.2794)
							(mid -0.249642 -0.249642)
							(end -0.2794 -0.1778)
						)
						(arc
							(start -0.2794 0.1778)
							(mid -0.249642 0.249642)
							(end -0.1778 0.2794)
						)
						(arc
							(start 0.1778 0.2794)
							(mid 0.249642 0.249642)
							(end 0.2794 0.1778)
						)
						(arc
							(start 0.2794 -0.1778)
							(mid 0.249642 -0.249642)
							(end 0.1778 -0.2794)
						)
					)
					(width 0)
					(fill yes)
				)
			)
		)
		(pad "2" smd custom
			(at 0 0.4445 90)
			(size 0.1397 0.1397)
			(layers "F.Cu" "F.Mask" "F.Paste")
			(net "GND")
			(options
				(clearance outline)
				(anchor circle)
			)
			(primitives
				(gr_poly
					(pts
						(arc
							(start -0.1778 -0.2794)
							(mid -0.249642 -0.249642)
							(end -0.2794 -0.1778)
						)
						(arc
							(start -0.2794 0.1778)
							(mid -0.249642 0.249642)
							(end -0.1778 0.2794)
						)
						(arc
							(start 0.1778 0.2794)
							(mid 0.249642 0.249642)
							(end 0.2794 0.1778)
						)
						(arc
							(start 0.2794 -0.1778)
							(mid 0.249642 -0.249642)
							(end 0.1778 -0.2794)
						)
					)
					(width 0)
					(fill yes)
				)
			)
		)
	)
	(footprint ""
		(layer "F.Cu")
		(at 48.527716 -72.650096 180)
		(property "Reference" "C8"
			(at 0 0 180)
			(layer "F.SilkS")
			(hide yes)
			(effects
				(font
					(size 1.27 1.27)
				)
			)
		)
		(property "Value" "SC1U16V3KX-5GP"
			(at 0 -3.5052 180)
			(unlocked yes)
			(layer "F.Fab")
			(hide yes)
			(effects
				(font
					(size 2.54 2.54)
					(thickness 0.381)
				)
			)
		)
		(property "Device Type" "C603H36"
			(at 0 -5.0292 180)
			(unlocked yes)
			(layer "F.Fab")
			(hide yes)
			(effects
				(font
					(size 2.54 2.54)
					(thickness 0.381)
				)
			)
		)
		(duplicate_pad_numbers_are_jumpers no)
		(fp_line
			(start 0.508 0)
			(end -0.508 0)
			(stroke
				(width 0.2032)
				(type default)
			)
			(layer "F.SilkS")
		)
		(fp_rect
			(start -0.5842 1.3335)
			(end 0.5842 -1.3335)
			(stroke
				(width 0)
				(type default)
			)
			(fill no)
			(layer "F.CrtYd")
		)
		(fp_rect
			(start -0.5842 1.3335)
			(end 0.5842 -1.3335)
			(stroke
				(width 0)
				(type default)
			)
			(fill no)
			(layer "F.Fab")
		)
		(pad "1" smd custom
			(at 0 -0.762 180)
			(size 0.2159 0.2159)
			(layers "F.Cu" "F.Mask" "F.Paste")
			(net "P5V_USB_B")
			(options
				(clearance outline)
				(anchor circle)
			)
			(primitives
				(gr_poly
					(pts
						(arc
							(start -0.3302 -0.4318)
							(mid -0.402042 -0.402042)
							(end -0.4318 -0.3302)
						)
						(arc
							(start -0.4318 0.3302)
							(mid -0.402042 0.402042)
							(end -0.3302 0.4318)
						)
						(arc
							(start 0.3302 0.4318)
							(mid 0.402042 0.402042)
							(end 0.4318 0.3302)
						)
						(arc
							(start 0.4318 -0.3302)
							(mid 0.402042 -0.402042)
							(end 0.3302 -0.4318)
						)
					)
					(width 0)
					(fill yes)
				)
			)
		)
		(pad "2" smd custom
			(at 0 0.762 180)
			(size 0.2159 0.2159)
			(layers "F.Cu" "F.Mask" "F.Paste")
			(net "GND")
			(options
				(clearance outline)
				(anchor circle)
			)
			(primitives
				(gr_poly
					(pts
						(arc
							(start -0.3302 -0.4318)
							(mid -0.402042 -0.402042)
							(end -0.4318 -0.3302)
						)
						(arc
							(start -0.4318 0.3302)
							(mid -0.402042 0.402042)
							(end -0.3302 0.4318)
						)
						(arc
							(start 0.3302 0.4318)
							(mid 0.402042 0.402042)
							(end 0.4318 0.3302)
						)
						(arc
							(start 0.4318 -0.3302)
							(mid 0.402042 -0.402042)
							(end 0.3302 -0.4318)
						)
					)
					(width 0)
					(fill yes)
				)
			)
		)
	)
	(footprint ""
		(layer "F.Cu")
		(at 19.6596 -11.938 90)
		(property "Reference" "R3"
			(at 0 0 90)
			(layer "F.SilkS")
			(hide yes)
			(effects
				(font
					(size 1.27 1.27)
				)
			)
		)
		(property "Value" "0R2J-2-GP"
			(at 0.064008 -4.679696 90)
			(unlocked yes)
			(layer "F.Fab")
			(hide yes)
			(effects
				(font
					(size 2.54 2.54)
					(thickness 0.381)
				)
			)
		)
		(property "Device Type" "R402H16"
			(at 0.064008 -6.203696 90)
			(unlocked yes)
			(layer "F.Fab")
			(hide yes)
			(effects
				(font
					(size 2.54 2.54)
					(thickness 0.381)
				)
			)
		)
		(duplicate_pad_numbers_are_jumpers no)
		(fp_line
			(start 0.508 -0.9398)
			(end -0.508 -0.9398)
			(stroke
				(width 0.1524)
				(type default)
			)
			(layer "F.SilkS")
		)
		(fp_line
			(start -0.508 -0.9398)
			(end -0.508 0.9398)
			(stroke
				(width 0.1524)
				(type default)
			)
			(layer "F.SilkS")
		)
		(fp_rect
			(start -0.508 0.9398)
			(end 0.508 -0.9398)
			(stroke
				(width 0)
				(type default)
			)
			(fill no)
			(layer "F.CrtYd")
		)
		(fp_rect
			(start -0.508 0.9398)
			(end 0.508 -0.9398)
			(stroke
				(width 0)
				(type default)
			)
			(fill no)
			(layer "F.Fab")
		)
		(pad "1" smd custom
			(at 0 -0.4445 90)
			(size 0.1397 0.1397)
			(layers "F.Cu" "F.Mask" "F.Paste")
			(net "UART_SEL_A_MUX_R")
			(options
				(clearance outline)
				(anchor circle)
			)
			(primitives
				(gr_poly
					(pts
						(arc
							(start -0.1778 -0.2794)
							(mid -0.249642 -0.249642)
							(end -0.2794 -0.1778)
						)
						(arc
							(start -0.2794 0.1778)
							(mid -0.249642 0.249642)
							(end -0.1778 0.2794)
						)
						(arc
							(start 0.1778 0.2794)
							(mid 0.249642 0.249642)
							(end 0.2794 0.1778)
						)
						(arc
							(start 0.2794 -0.1778)
							(mid 0.249642 -0.249642)
							(end 0.1778 -0.2794)
						)
					)
					(width 0)
					(fill yes)
				)
			)
		)
		(pad "2" smd custom
			(at 0 0.4445 90)
			(size 0.1397 0.1397)
			(layers "F.Cu" "F.Mask" "F.Paste")
			(net "GND")
			(options
				(clearance outline)
				(anchor circle)
			)
			(primitives
				(gr_poly
					(pts
						(arc
							(start -0.1778 -0.2794)
							(mid -0.249642 -0.249642)
							(end -0.2794 -0.1778)
						)
						(arc
							(start -0.2794 0.1778)
							(mid -0.249642 0.249642)
							(end -0.1778 0.2794)
						)
						(arc
							(start 0.1778 0.2794)
							(mid 0.249642 0.249642)
							(end 0.2794 0.1778)
						)
						(arc
							(start 0.2794 -0.1778)
							(mid 0.249642 -0.249642)
							(end 0.1778 -0.2794)
						)
					)
					(width 0)
					(fill yes)
				)
			)
		)
	)
	(footprint ""
		(layer "F.Cu")
		(at 19.203416 -20.845526 180)
		(property "Reference" "R67"
			(at 0 0 180)
			(layer "F.SilkS")
			(hide yes)
			(effects
				(font
					(size 1.27 1.27)
				)
			)
		)
		(property "Value" "4K7R2F-GP"
			(at 0.064008 -3.993896 180)
			(unlocked yes)
			(layer "F.Fab")
			(hide yes)
			(effects
				(font
					(size 1.016 1.016)
					(thickness 0.1524)
				)
			)
		)
		(property "Device Type" "R402H16"
			(at 0.064008 -5.517896 180)
			(unlocked yes)
			(layer "F.Fab")
			(hide yes)
			(effects
				(font
					(size 1.016 1.016)
					(thickness 0.1524)
				)
			)
		)
		(duplicate_pad_numbers_are_jumpers no)
		(fp_line
			(start 0.508 -0.9398)
			(end -0.508 -0.9398)
			(stroke
				(width 0.1524)
				(type default)
			)
			(layer "F.SilkS")
		)
		(fp_line
			(start -0.508 -0.9398)
			(end -0.508 0.9398)
			(stroke
				(width 0.1524)
				(type default)
			)
			(layer "F.SilkS")
		)
		(fp_rect
			(start -0.508 0.9398)
			(end 0.508 -0.9398)
			(stroke
				(width 0)
				(type default)
			)
			(fill no)
			(layer "F.CrtYd")
		)
		(fp_rect
			(start -0.508 0.9398)
			(end 0.508 -0.9398)
			(stroke
				(width 0)
				(type default)
			)
			(fill no)
			(layer "F.Fab")
		)
		(pad "1" smd custom
			(at 0 -0.4445 180)
			(size 0.1397 0.1397)
			(layers "F.Cu" "F.Mask" "F.Paste")
			(net "TCA9555_A_A2")
			(options
				(clearance outline)
				(anchor circle)
			)
			(primitives
				(gr_poly
					(pts
						(arc
							(start -0.1778 -0.2794)
							(mid -0.249642 -0.249642)
							(end -0.2794 -0.1778)
						)
						(arc
							(start -0.2794 0.1778)
							(mid -0.249642 0.249642)
							(end -0.1778 0.2794)
						)
						(arc
							(start 0.1778 0.2794)
							(mid 0.249642 0.249642)
							(end 0.2794 0.1778)
						)
						(arc
							(start 0.2794 -0.1778)
							(mid 0.249642 -0.249642)
							(end 0.1778 -0.2794)
						)
					)
					(width 0)
					(fill yes)
				)
			)
		)
		(pad "2" smd custom
			(at 0 0.4445 180)
			(size 0.1397 0.1397)
			(layers "F.Cu" "F.Mask" "F.Paste")
			(net "GND")
			(options
				(clearance outline)
				(anchor circle)
			)
			(primitives
				(gr_poly
					(pts
						(arc
							(start -0.1778 -0.2794)
							(mid -0.249642 -0.249642)
							(end -0.2794 -0.1778)
						)
						(arc
							(start -0.2794 0.1778)
							(mid -0.249642 0.249642)
							(end -0.1778 0.2794)
						)
						(arc
							(start 0.1778 0.2794)
							(mid 0.249642 0.249642)
							(end 0.2794 0.1778)
						)
						(arc
							(start 0.2794 -0.1778)
							(mid 0.249642 -0.249642)
							(end 0.1778 -0.2794)
						)
					)
					(width 0)
					(fill yes)
				)
			)
		)
	)
	(footprint ""
		(layer "F.Cu")
		(at 8.948674 -16.942816 90)
		(property "Reference" "R62"
			(at 0 0 90)
			(layer "F.SilkS")
			(hide yes)
			(effects
				(font
					(size 1.27 1.27)
				)
			)
		)
		(property "Value" "4K7R2F-GP"
			(at 0.064008 -3.993896 90)
			(unlocked yes)
			(layer "F.Fab")
			(hide yes)
			(effects
				(font
					(size 1.016 1.016)
					(thickness 0.1524)
				)
			)
		)
		(property "Device Type" "R402H16"
			(at 0.064008 -5.517896 90)
			(unlocked yes)
			(layer "F.Fab")
			(hide yes)
			(effects
				(font
					(size 1.016 1.016)
					(thickness 0.1524)
				)
			)
		)
		(duplicate_pad_numbers_are_jumpers no)
		(fp_line
			(start 0.508 -0.9398)
			(end -0.508 -0.9398)
			(stroke
				(width 0.1524)
				(type default)
			)
			(layer "F.SilkS")
		)
		(fp_line
			(start -0.508 -0.9398)
			(end -0.508 0.9398)
			(stroke
				(width 0.1524)
				(type default)
			)
			(layer "F.SilkS")
		)
		(fp_rect
			(start -0.508 0.9398)
			(end 0.508 -0.9398)
			(stroke
				(width 0)
				(type default)
			)
			(fill no)
			(layer "F.CrtYd")
		)
		(fp_rect
			(start -0.508 0.9398)
			(end 0.508 -0.9398)
			(stroke
				(width 0)
				(type default)
			)
			(fill no)
			(layer "F.Fab")
		)
		(pad "1" smd custom
			(at 0 -0.4445 90)
			(size 0.1397 0.1397)
			(layers "F.Cu" "F.Mask" "F.Paste")
			(net "P3V3_STBY_A")
			(options
				(clearance outline)
				(anchor circle)
			)
			(primitives
				(gr_poly
					(pts
						(arc
							(start -0.1778 -0.2794)
							(mid -0.249642 -0.249642)
							(end -0.2794 -0.1778)
						)
						(arc
							(start -0.2794 0.1778)
							(mid -0.249642 0.249642)
							(end -0.1778 0.2794)
						)
						(arc
							(start 0.1778 0.2794)
							(mid 0.249642 0.249642)
							(end 0.2794 0.1778)
						)
						(arc
							(start 0.2794 -0.1778)
							(mid 0.249642 -0.249642)
							(end 0.1778 -0.2794)
						)
					)
					(width 0)
					(fill yes)
				)
			)
		)
		(pad "2" smd custom
			(at 0 0.4445 90)
			(size 0.1397 0.1397)
			(layers "F.Cu" "F.Mask" "F.Paste")
			(net "TCA9555_A_A0")
			(options
				(clearance outline)
				(anchor circle)
			)
			(primitives
				(gr_poly
					(pts
						(arc
							(start -0.1778 -0.2794)
							(mid -0.249642 -0.249642)
							(end -0.2794 -0.1778)
						)
						(arc
							(start -0.2794 0.1778)
							(mid -0.249642 0.249642)
							(end -0.1778 0.2794)
						)
						(arc
							(start 0.1778 0.2794)
							(mid 0.249642 0.249642)
							(end 0.2794 0.1778)
						)
						(arc
							(start 0.2794 -0.1778)
							(mid 0.249642 -0.249642)
							(end 0.1778 -0.2794)
						)
					)
					(width 0)
					(fill yes)
				)
			)
		)
	)
	(footprint ""
		(layer "F.Cu")
		(at 20.219416 -20.845526)
		(property "Reference" "R64"
			(at 0 0 0)
			(layer "F.SilkS")
			(hide yes)
			(effects
				(font
					(size 1.27 1.27)
				)
			)
		)
		(property "Value" "4K7R2F-GP"
			(at 0.064008 -3.993896 0)
			(unlocked yes)
			(layer "F.Fab")
			(hide yes)
			(effects
				(font
					(size 1.016 1.016)
					(thickness 0.1524)
				)
			)
		)
		(property "Device Type" "R402H16"
			(at 0.064008 -5.517896 0)
			(unlocked yes)
			(layer "F.Fab")
			(hide yes)
			(effects
				(font
					(size 1.016 1.016)
					(thickness 0.1524)
				)
			)
		)
		(duplicate_pad_numbers_are_jumpers no)
		(fp_line
			(start -0.508 -0.9398)
			(end -0.508 0.9398)
			(stroke
				(width 0.1524)
				(type default)
			)
			(layer "F.SilkS")
		)
		(fp_line
			(start 0.508 -0.9398)
			(end -0.508 -0.9398)
			(stroke
				(width 0.1524)
				(type default)
			)
			(layer "F.SilkS")
		)
		(fp_rect
			(start -0.508 0.9398)
			(end 0.508 -0.9398)
			(stroke
				(width 0)
				(type default)
			)
			(fill no)
			(layer "F.CrtYd")
		)
		(fp_rect
			(start -0.508 0.9398)
			(end 0.508 -0.9398)
			(stroke
				(width 0)
				(type default)
			)
			(fill no)
			(layer "F.Fab")
		)
		(pad "1" smd custom
			(at 0 -0.4445)
			(size 0.1397 0.1397)
			(layers "F.Cu" "F.Mask" "F.Paste")
			(net "P3V3_STBY_A")
			(options
				(clearance outline)
				(anchor circle)
			)
			(primitives
				(gr_poly
					(pts
						(arc
							(start -0.1778 -0.2794)
							(mid -0.249642 -0.249642)
							(end -0.2794 -0.1778)
						)
						(arc
							(start -0.2794 0.1778)
							(mid -0.249642 0.249642)
							(end -0.1778 0.2794)
						)
						(arc
							(start 0.1778 0.2794)
							(mid 0.249642 0.249642)
							(end 0.2794 0.1778)
						)
						(arc
							(start 0.2794 -0.1778)
							(mid 0.249642 -0.249642)
							(end 0.1778 -0.2794)
						)
					)
					(width 0)
					(fill yes)
				)
			)
		)
		(pad "2" smd custom
			(at 0 0.4445)
			(size 0.1397 0.1397)
			(layers "F.Cu" "F.Mask" "F.Paste")
			(net "TCA9555_A_A2")
			(options
				(clearance outline)
				(anchor circle)
			)
			(primitives
				(gr_poly
					(pts
						(arc
							(start -0.1778 -0.2794)
							(mid -0.249642 -0.249642)
							(end -0.2794 -0.1778)
						)
						(arc
							(start -0.2794 0.1778)
							(mid -0.249642 0.249642)
							(end -0.1778 0.2794)
						)
						(arc
							(start 0.1778 0.2794)
							(mid 0.249642 0.249642)
							(end 0.2794 0.1778)
						)
						(arc
							(start 0.2794 -0.1778)
							(mid 0.249642 -0.249642)
							(end 0.1778 -0.2794)
						)
					)
					(width 0)
					(fill yes)
				)
			)
		)
	)
	(footprint ""
		(layer "F.Cu")
		(at 54.74208 -36.449)
		(property "Reference" "C13"
			(at 0 0 0)
			(layer "F.SilkS")
			(hide yes)
			(effects
				(font
					(size 1.27 1.27)
				)
			)
		)
		(property "Value" "SC1U16V3KX-5GP"
			(at 0 -3.5052 0)
			(unlocked yes)
			(layer "F.Fab")
			(hide yes)
			(effects
				(font
					(size 2.54 2.54)
					(thickness 0.381)
				)
			)
		)
		(property "Device Type" "C603H36"
			(at 0 -5.0292 0)
			(unlocked yes)
			(layer "F.Fab")
			(hide yes)
			(effects
				(font
					(size 2.54 2.54)
					(thickness 0.381)
				)
			)
		)
		(duplicate_pad_numbers_are_jumpers no)
		(fp_line
			(start 0.508 0)
			(end -0.508 0)
			(stroke
				(width 0.2032)
				(type default)
			)
			(layer "F.SilkS")
		)
		(fp_rect
			(start -0.5842 1.3335)
			(end 0.5842 -1.3335)
			(stroke
				(width 0)
				(type default)
			)
			(fill no)
			(layer "F.CrtYd")
		)
		(fp_rect
			(start -0.5842 1.3335)
			(end 0.5842 -1.3335)
			(stroke
				(width 0)
				(type default)
			)
			(fill no)
			(layer "F.Fab")
		)
		(pad "1" smd custom
			(at 0 -0.762)
			(size 0.2159 0.2159)
			(layers "F.Cu" "F.Mask" "F.Paste")
			(net "SYS_RESET_BTN_B")
			(options
				(clearance outline)
				(anchor circle)
			)
			(primitives
				(gr_poly
					(pts
						(arc
							(start -0.3302 -0.4318)
							(mid -0.402042 -0.402042)
							(end -0.4318 -0.3302)
						)
						(arc
							(start -0.4318 0.3302)
							(mid -0.402042 0.402042)
							(end -0.3302 0.4318)
						)
						(arc
							(start 0.3302 0.4318)
							(mid 0.402042 0.402042)
							(end 0.4318 0.3302)
						)
						(arc
							(start 0.4318 -0.3302)
							(mid 0.402042 -0.402042)
							(end 0.3302 -0.4318)
						)
					)
					(width 0)
					(fill yes)
				)
			)
		)
		(pad "2" smd custom
			(at 0 0.762)
			(size 0.2159 0.2159)
			(layers "F.Cu" "F.Mask" "F.Paste")
			(net "GND")
			(options
				(clearance outline)
				(anchor circle)
			)
			(primitives
				(gr_poly
					(pts
						(arc
							(start -0.3302 -0.4318)
							(mid -0.402042 -0.402042)
							(end -0.4318 -0.3302)
						)
						(arc
							(start -0.4318 0.3302)
							(mid -0.402042 0.402042)
							(end -0.3302 0.4318)
						)
						(arc
							(start 0.3302 0.4318)
							(mid 0.402042 0.402042)
							(end 0.4318 0.3302)
						)
						(arc
							(start 0.4318 -0.3302)
							(mid 0.402042 -0.402042)
							(end 0.3302 -0.4318)
						)
					)
					(width 0)
					(fill yes)
				)
			)
		)
	)
	(footprint ""
		(layer "F.Cu")
		(at 29.550106 -1.299972 180)
		(property "Reference" "CN1"
			(at 0 0 180)
			(layer "F.SilkS")
			(hide yes)
			(effects
				(font
					(size 1.27 1.27)
				)
			)
		)
		(property "Value" "SKT-SAS15P-14P-81-GP"
			(at -24.4729 -9.8044 180)
			(unlocked yes)
			(layer "F.Fab")
			(hide yes)
			(effects
				(font
					(size 1.016 1.016)
					(thickness 0.1524)
				)
			)
		)
		(property "Device Type" "SASM2130081TR"
			(at -24.4729 -11.3284 180)
			(unlocked yes)
			(layer "F.Fab")
			(hide yes)
			(effects
				(font
					(size 1.016 1.016)
					(thickness 0.1524)
				)
			)
		)
		(duplicate_pad_numbers_are_jumpers no)
		(fp_line
			(start 25.0698 1.4478)
			(end -25.0698 1.4478)
			(stroke
				(width 0.1524)
				(type default)
			)
			(layer "F.SilkS")
		)
		(fp_line
			(start 25.0698 -7.999984)
			(end 25.0698 1.4478)
			(stroke
				(width 0.1524)
				(type default)
			)
			(layer "F.SilkS")
		)
		(fp_line
			(start 22.165056 -7.999984)
			(end 25.0698 -7.999984)
			(stroke
				(width 0.1524)
				(type default)
			)
			(layer "F.SilkS")
		)
		(fp_line
			(start 21.66493 -1.500124)
			(end 21.66493 -7.500112)
			(stroke
				(width 0.1524)
				(type default)
			)
			(layer "F.SilkS")
		)
		(fp_line
			(start 15.5448 1.5367)
			(end 16.3068 1.5367)
			(stroke
				(width 0.3302)
				(type default)
			)
			(layer "F.SilkS")
		)
		(fp_line
			(start -21.165058 -0.999998)
			(end 21.165058 -0.999998)
			(stroke
				(width 0.1524)
				(type default)
			)
			(layer "F.SilkS")
		)
		(fp_line
			(start -21.66493 -7.500112)
			(end -21.66493 -1.500124)
			(stroke
				(width 0.1524)
				(type default)
			)
			(layer "F.SilkS")
		)
		(fp_line
			(start -25.0698 1.4478)
			(end -25.0698 -7.999984)
			(stroke
				(width 0.1524)
				(type default)
			)
			(layer "F.SilkS")
		)
		(fp_line
			(start -25.0698 -7.999984)
			(end -22.165056 -7.999984)
			(stroke
				(width 0.1524)
				(type default)
			)
			(layer "F.SilkS")
		)
		(fp_arc
			(start 21.66493 -1.500124)
			(mid 21.518607 -1.146515)
			(end 21.165058 -0.999998)
			(stroke
				(width 0.1524)
				(type default)
			)
			(layer "F.SilkS")
		)
		(fp_arc
			(start 21.66493 -7.500112)
			(mid 21.811503 -7.85359)
			(end 22.165056 -7.999984)
			(stroke
				(width 0.1524)
				(type default)
			)
			(layer "F.SilkS")
		)
		(fp_arc
			(start -21.165058 -0.999998)
			(mid -21.518635 -1.146484)
			(end -21.66493 -1.500124)
			(stroke
				(width 0.1524)
				(type default)
			)
			(layer "F.SilkS")
		)
		(fp_arc
			(start -22.165056 -7.999984)
			(mid -21.811503 -7.85359)
			(end -21.66493 -7.500112)
			(stroke
				(width 0.1524)
				(type default)
			)
			(layer "F.SilkS")
		)
		(fp_poly
			(pts
				(xy 15.957804 1.403096) (xy 15.322804 2.038096) (xy 16.592804 2.038096)
			)
			(stroke
				(width 0)
				(type default)
			)
			(fill yes)
			(layer "F.SilkS")
		)
		(fp_rect
			(start -24.4983 1.1938)
			(end 24.4983 -8.001)
			(stroke
				(width 0)
				(type default)
			)
			(fill no)
			(layer "F.CrtYd")
		)
		(fp_poly
			(pts
				(xy -25.3238 1.7018) (xy -25.3238 -8.509) (xy 25.3238 -8.509) (xy 25.3238 -0.00635) (xy 24.4983 -0.00635)
				(xy 24.4983 -8.001) (xy -24.4983 -8.001) (xy -24.4983 1.1938) (xy 24.4983 1.1938) (xy 24.4983 0.00635)
				(xy 25.3238 0.00635) (xy 25.3238 1.7018)
			)
			(stroke
				(width 0)
				(type default)
			)
			(fill no)
			(layer "F.CrtYd")
		)
		(fp_rect
			(start -25.3238 1.7018)
			(end 25.3238 -8.509)
			(stroke
				(width 0)
				(type default)
			)
			(fill no)
			(layer "F.Fab")
		)
		(fp_text user "Slit"
			(at 3.214878 -3.280918 180)
			(unlocked yes)
			(layer "F.SilkS")
			(effects
				(font
					(size 1.016 1.016)
					(thickness 0.1524)
				)
				(justify left)
			)
		)
		(pad "" np_thru_hole circle
			(at -18.945098 0 180)
			(size 0.254 0.254)
			(drill 1.3208)
			(layers "*.Cu" "*.Mask")
			(clearance 0.889)
			(thermal_gap 0.889)
		)
		(pad "" np_thru_hole circle
			(at 18.945098 0 180)
			(size 0.254 0.254)
			(drill 1.3208)
			(layers "*.Cu" "*.Mask")
			(clearance 0.889)
			(thermal_gap 0.889)
		)
		(pad "G1" smd rect
			(at 23.515066 -1.75006 180)
			(size 2.5908 3.4036)
			(layers "F.Cu" "F.Mask" "F.Paste")
			(net "GND")
		)
		(pad "G2" smd rect
			(at -23.515066 -1.75006 180)
			(size 2.5908 3.4036)
			(layers "F.Cu" "F.Mask" "F.Paste")
			(net "GND")
		)
		(pad "P1" smd rect
			(at 1.905 0.299974 180)
			(size 0.6096 1.6002)
			(layers "F.Cu" "F.Mask" "F.Paste")
			(net "P5V_USB_A")
		)
		(pad "P2" smd rect
			(at 0.635 0.299974 180)
			(size 0.6096 1.6002)
			(layers "F.Cu" "F.Mask" "F.Paste")
			(net "P5V_USB_B")
		)
		(pad "P3" smd rect
			(at -0.635 0.299974 180)
			(size 0.6096 1.6002)
			(layers "F.Cu" "F.Mask" "F.Paste")
			(net "FAULT_LED_B")
		)
		(pad "P4" smd rect
			(at -1.905 0.299974 180)
			(size 0.6096 1.6002)
			(layers "F.Cu" "F.Mask" "F.Paste")
			(net "PWR_LED_B_N")
		)
		(pad "P5" smd rect
			(at -3.175 0.299974 180)
			(size 0.6096 1.6002)
			(layers "F.Cu" "F.Mask" "F.Paste")
			(net "P3V3_STBY_B")
		)
		(pad "P6" smd rect
			(at -4.445 0.299974 180)
			(size 0.6096 1.6002)
			(layers "F.Cu" "F.Mask" "F.Paste")
			(net "SYS_RESET_BTN_B_N")
		)
		(pad "P7" smd rect
			(at -5.715 0.299974 180)
			(size 0.6096 1.6002)
			(layers "F.Cu" "F.Mask" "F.Paste")
			(net "GND")
		)
		(pad "P8" smd rect
			(at -6.985 0.299974 180)
			(size 0.6096 1.6002)
			(layers "F.Cu" "F.Mask" "F.Paste")
			(net "I2C_DPB_B_SCL")
		)
		(pad "P9" smd rect
			(at -8.255 0.299974 180)
			(size 0.6096 1.6002)
			(layers "F.Cu" "F.Mask" "F.Paste")
			(net "I2C_DPB_B_SDA")
		)
		(pad "P10" smd rect
			(at -9.525 0.299974 180)
			(size 0.6096 1.6002)
			(layers "F.Cu" "F.Mask" "F.Paste")
			(net "PWR_BTN_B")
		)
		(pad "P11" smd rect
			(at -10.795 0.299974 180)
			(size 0.6096 1.6002)
			(layers "F.Cu" "F.Mask" "F.Paste")
			(net "UART_IOC_B_TX")
		)
		(pad "P12" smd rect
			(at -12.065 0.299974 180)
			(size 0.6096 1.6002)
			(layers "F.Cu" "F.Mask" "F.Paste")
			(net "UART_IOC_B_RX")
		)
		(pad "P13" smd rect
			(at -13.335 0.299974 180)
			(size 0.6096 1.6002)
			(layers "F.Cu" "F.Mask" "F.Paste")
			(net "GND")
		)
		(pad "P14" smd rect
			(at -14.605 0.299974 180)
			(size 0.6096 1.6002)
			(layers "F.Cu" "F.Mask" "F.Paste")
			(net "UART_EXP_B_TX")
		)
		(pad "P15" smd rect
			(at -15.875 0.299974 180)
			(size 0.6096 1.6002)
			(layers "F.Cu" "F.Mask" "F.Paste")
			(net "UART_EXP_B_RX")
		)
		(pad "S1" smd rect
			(at 15.88008 0.299974 180)
			(size 0.6096 1.6002)
			(layers "F.Cu" "F.Mask" "F.Paste")
			(net "UART_EXP_A_TX")
		)
		(pad "S2" smd rect
			(at 14.61008 0.299974 180)
			(size 0.6096 1.6002)
			(layers "F.Cu" "F.Mask" "F.Paste")
			(net "UART_EXP_A_RX")
		)
		(pad "S3" smd rect
			(at 13.34008 0.299974 180)
			(size 0.6096 1.6002)
			(layers "F.Cu" "F.Mask" "F.Paste")
			(net "GND")
		)
		(pad "S4" smd rect
			(at 12.07008 0.299974 180)
			(size 0.6096 1.6002)
			(layers "F.Cu" "F.Mask" "F.Paste")
			(net "UART_IOC_A_TX")
		)
		(pad "S5" smd rect
			(at 10.80008 0.299974 180)
			(size 0.6096 1.6002)
			(layers "F.Cu" "F.Mask" "F.Paste")
			(net "UART_IOC_A_RX")
		)
		(pad "S6" smd rect
			(at 9.53008 0.299974 180)
			(size 0.6096 1.6002)
			(layers "F.Cu" "F.Mask" "F.Paste")
			(net "GND")
		)
		(pad "S7" smd rect
			(at 8.26008 0.299974 180)
			(size 0.6096 1.6002)
			(layers "F.Cu" "F.Mask" "F.Paste")
			(net "PWR_BTN_A")
		)
		(pad "S8" smd rect
			(at 7.480046 0.299974 180)
			(size 0.508 1.6002)
			(layers "F.Cu" "F.Mask" "F.Paste")
			(net "I2C_DPB_A_SCL")
		)
		(pad "S9" smd rect
			(at 6.679946 0.299974 180)
			(size 0.508 1.6002)
			(layers "F.Cu" "F.Mask" "F.Paste")
			(net "I2C_DPB_A_SDA")
		)
		(pad "S10" smd rect
			(at 5.8801 0.299974 180)
			(size 0.508 1.6002)
			(layers "F.Cu" "F.Mask" "F.Paste")
			(net "SYS_RESET_BTN_A_N")
		)
		(pad "S11" smd rect
			(at 5.08 0.299974 180)
			(size 0.508 1.6002)
			(layers "F.Cu" "F.Mask" "F.Paste")
			(net "P3V3_STBY_A")
		)
		(pad "S12" smd rect
			(at 4.2799 0.299974 180)
			(size 0.508 1.6002)
			(layers "F.Cu" "F.Mask" "F.Paste")
			(net "PWR_LED_A_N")
		)
		(pad "S13" smd rect
			(at 3.480054 0.299974 180)
			(size 0.508 1.6002)
			(layers "F.Cu" "F.Mask" "F.Paste")
			(net "FAULT_LED_A")
		)
		(pad "S14" smd rect
			(at 2.679954 0.299974 180)
			(size 0.508 1.6002)
			(layers "F.Cu" "F.Mask" "F.Paste")
			(net "Net_27")
		)
		(zone
			(layers "F.Cu" "B.Cu" "In1.Cu" "In2.Cu")
			(hatch none 0.5)
			(connect_pads
				(clearance 0)
			)
			(min_thickness 0.25)
			(keepout
				(tracks not_allowed)
				(vias allowed)
				(pads allowed)
				(copperpour not_allowed)
				(footprints allowed)
			)
			(placement
				(enabled no)
				(sheetname "")
			)
			(fill
				(thermal_gap 0.5)
				(thermal_bridge_width 0.5)
				(island_removal_mode 0)
			)
			(polygon
				(pts
					(arc
						(start 11.570208 -1.299972)
						(mid 9.639808 -1.299972)
						(end 11.570208 -1.299972)
					)
				)
			)
		)
		(zone
			(layers "F.Cu" "B.Cu" "In1.Cu" "In2.Cu")
			(hatch none 0.5)
			(connect_pads
				(clearance 0)
			)
			(min_thickness 0.25)
			(keepout
				(tracks not_allowed)
				(vias allowed)
				(pads allowed)
				(copperpour not_allowed)
				(footprints allowed)
			)
			(placement
				(enabled no)
				(sheetname "")
			)
			(fill
				(thermal_gap 0.5)
				(thermal_bridge_width 0.5)
				(island_removal_mode 0)
			)
			(polygon
				(pts
					(arc
						(start 49.460404 -1.299972)
						(mid 47.530004 -1.299972)
						(end 49.460404 -1.299972)
					)
				)
			)
		)
	)
	(footprint ""
		(layer "F.Cu")
		(at 47.9806 -29.3878 90)
		(property "Reference" "D10"
			(at 0 0 90)
			(layer "F.SilkS")
			(hide yes)
			(effects
				(font
					(size 1.27 1.27)
				)
			)
		)
		(property "Value" "PESD5V0X1UAB-GP"
			(at 0 -4.690618 90)
			(unlocked yes)
			(layer "F.Fab")
			(hide yes)
			(effects
				(font
					(size 1.016 1.016)
					(thickness 0.1524)
				)
			)
		)
		(property "Device Type" "SOD523AKH26"
			(at 0 -6.214618 90)
			(unlocked yes)
			(layer "F.Fab")
			(hide yes)
			(effects
				(font
					(size 1.016 1.016)
					(thickness 0.1524)
				)
			)
		)
		(duplicate_pad_numbers_are_jumpers no)
		(fp_line
			(start 0.5334 -1.4478)
			(end 0.5334 1.524)
			(stroke
				(width 0.1524)
				(type default)
			)
			(layer "F.SilkS")
		)
		(fp_line
			(start -0.5334 -1.4478)
			(end 0.5334 -1.4478)
			(stroke
				(width 0.1524)
				(type default)
			)
			(layer "F.SilkS")
		)
		(fp_line
			(start 0.5334 1.524)
			(end -0.5334 1.524)
			(stroke
				(width 0.1524)
				(type default)
			)
			(layer "F.SilkS")
		)
		(fp_line
			(start -0.5334 1.524)
			(end -0.5334 -1.4478)
			(stroke
				(width 0.1524)
				(type default)
			)
			(layer "F.SilkS")
		)
		(fp_line
			(start 0.4064 1.651)
			(end -0.4064 1.651)
			(stroke
				(width 0.4064)
				(type default)
			)
			(layer "F.SilkS")
		)
		(fp_rect
			(start -0.6096 1.8542)
			(end 0.6096 -1.524)
			(stroke
				(width 0)
				(type default)
			)
			(fill no)
			(layer "F.CrtYd")
		)
		(fp_poly
			(pts
				(xy -0.6096 -1.524) (xy 0.6096 -1.524) (xy 0.6096 1.8542) (xy -0.6096 1.8542)
			)
			(stroke
				(width 0)
				(type default)
			)
			(fill no)
			(layer "F.Fab")
		)
		(pad "A" smd rect
			(at 0 -0.762 90)
			(size 0.5588 1.016)
			(layers "F.Cu" "F.Mask" "F.Paste")
			(net "GND")
		)
		(pad "K" smd rect
			(at 0 0.762 90)
			(size 0.5588 1.016)
			(layers "F.Cu" "F.Mask" "F.Paste")
			(net "SYS_RESET_BTN_B")
		)
	)
	(footprint ""
		(layer "F.Cu")
		(at 48.90008 -59.99988 90)
		(property "Reference" "USB2"
			(at 0 0 90)
			(layer "F.SilkS")
			(hide yes)
			(effects
				(font
					(size 1.27 1.27)
				)
			)
		)
		(property "Value" "SKT-USB13-208-GP"
			(at -9.1821 -7.5692 90)
			(unlocked yes)
			(layer "F.Fab")
			(hide yes)
			(effects
				(font
					(size 1.016 1.016)
					(thickness 0.1524)
				)
			)
		)
		(property "Device Type" "SKT-USB13-148074-5"
			(at -9.1821 -9.0932 90)
			(unlocked yes)
			(layer "F.Fab")
			(hide yes)
			(effects
				(font
					(size 1.016 1.016)
					(thickness 0.1524)
				)
			)
		)
		(duplicate_pad_numbers_are_jumpers no)
		(fp_line
			(start 8.0137 -3.9497)
			(end 8.0137 3.9497)
			(stroke
				(width 0.1524)
				(type default)
			)
			(layer "F.SilkS")
		)
		(fp_line
			(start -8.0137 -3.9497)
			(end 8.0137 -3.9497)
			(stroke
				(width 0.1524)
				(type default)
			)
			(layer "F.SilkS")
		)
		(fp_line
			(start 8.0137 3.9497)
			(end -8.0137 3.9497)
			(stroke
				(width 0.1524)
				(type default)
			)
			(layer "F.SilkS")
		)
		(fp_line
			(start -8.0137 3.9497)
			(end -8.0137 -3.9497)
			(stroke
				(width 0.1524)
				(type default)
			)
			(layer "F.SilkS")
		)
		(fp_arc
			(start 4.854956 1.256792)
			(mid 8.078491 2.349096)
			(end 4.686808 2.064512)
			(stroke
				(width 0.3048)
				(type default)
			)
			(layer "F.SilkS")
		)
		(fp_arc
			(start -4.854956 1.256792)
			(mid -3.12974 1.318917)
			(end -4.686808 2.064512)
			(stroke
				(width 0.3048)
				(type default)
			)
			(layer "F.SilkS")
		)
		(fp_arc
			(start 4.686808 2.064512)
			(mid 3.129699 1.318908)
			(end 4.854956 1.256792)
			(stroke
				(width 0.3048)
				(type default)
			)
			(layer "F.SilkS")
		)
		(fp_arc
			(start -4.686808 2.064512)
			(mid -8.078519 2.349102)
			(end -4.854956 1.256792)
			(stroke
				(width 0.3048)
				(type default)
			)
			(layer "F.SilkS")
		)
		(fp_circle
			(center 6.400038 -1.999996)
			(end 6.400038 -0.285496)
			(stroke
				(width 0.3048)
				(type default)
			)
			(fill no)
			(layer "F.SilkS")
		)
		(fp_circle
			(center -6.400038 -1.999996)
			(end -6.400038 -0.285496)
			(stroke
				(width 0.3048)
				(type default)
			)
			(fill no)
			(layer "F.SilkS")
		)
		(fp_circle
			(center 3.50012 -0.999998)
			(end 3.50012 -0.110998)
			(stroke
				(width 0.3048)
				(type default)
			)
			(fill no)
			(layer "F.SilkS")
		)
		(fp_circle
			(center 0.999998 -0.999998)
			(end 0.999998 -0.110998)
			(stroke
				(width 0.3048)
				(type default)
			)
			(fill no)
			(layer "F.SilkS")
		)
		(fp_circle
			(center -0.999998 -0.999998)
			(end -0.999998 -0.110998)
			(stroke
				(width 0.3048)
				(type default)
			)
			(fill no)
			(layer "F.SilkS")
		)
		(fp_circle
			(center -3.50012 -0.999998)
			(end -3.50012 -0.110998)
			(stroke
				(width 0.3048)
				(type default)
			)
			(fill no)
			(layer "F.SilkS")
		)
		(fp_circle
			(center 1.999996 1.500124)
			(end 1.999996 2.389124)
			(stroke
				(width 0.3048)
				(type default)
			)
			(fill no)
			(layer "F.SilkS")
		)
		(fp_circle
			(center 0 1.500124)
			(end 0 2.389124)
			(stroke
				(width 0.3048)
				(type default)
			)
			(fill no)
			(layer "F.SilkS")
		)
		(fp_circle
			(center -1.999996 1.500124)
			(end -1.999996 2.389124)
			(stroke
				(width 0.3048)
				(type default)
			)
			(fill no)
			(layer "F.SilkS")
		)
		(fp_rect
			(start -7.4041 3.6957)
			(end 7.4041 -3.6957)
			(stroke
				(width 0)
				(type default)
			)
			(fill no)
			(layer "F.CrtYd")
		)
		(fp_poly
			(pts
				(xy -8.2677 4.2037) (xy -8.2677 -4.2037) (xy 8.2677 -4.2037) (xy 8.2677 -0.00635) (xy 7.4041 -0.00635)
				(xy 7.4041 -3.6957) (xy -7.4041 -3.6957) (xy -7.4041 3.6957) (xy 7.4041 3.6957) (xy 7.4041 0.00635)
				(xy 8.2677 0.00635) (xy 8.2677 4.2037)
			)
			(stroke
				(width 0)
				(type default)
			)
			(fill no)
			(layer "F.CrtYd")
		)
		(fp_rect
			(start -8.2677 4.2037)
			(end 8.2677 -4.2037)
			(stroke
				(width 0)
				(type default)
			)
			(fill no)
			(layer "F.Fab")
		)
		(pad "1" thru_hole circle
			(at 3.50012 -0.999998 90)
			(size 1.0668 1.0668)
			(drill 0.7112)
			(layers "*.Cu" "*.Mask")
			(remove_unused_layers no)
			(net "P5V_VBUS_B")
			(clearance 0.1778)
			(thermal_gap 0.1778)
		)
		(pad "2" thru_hole circle
			(at 0.999998 -0.999998 90)
			(size 1.0668 1.0668)
			(drill 0.7112)
			(layers "*.Cu" "*.Mask")
			(remove_unused_layers no)
			(net "DEBUG_USB_B_DN")
			(clearance 0.1778)
			(thermal_gap 0.1778)
		)
		(pad "3" thru_hole circle
			(at -0.999998 -0.999998 90)
			(size 1.0668 1.0668)
			(drill 0.7112)
			(layers "*.Cu" "*.Mask")
			(remove_unused_layers no)
			(net "DEBUG_USB_B_DP")
			(clearance 0.1778)
			(thermal_gap 0.1778)
		)
		(pad "4" thru_hole circle
			(at -3.50012 -0.999998 90)
			(size 1.0668 1.0668)
			(drill 0.7112)
			(layers "*.Cu" "*.Mask")
			(remove_unused_layers no)
			(net "GND")
			(clearance 0.1778)
			(thermal_gap 0.1778)
		)
		(pad "5" thru_hole circle
			(at -3.999992 1.500124 90)
			(size 1.0668 1.0668)
			(drill 0.7112)
			(layers "*.Cu" "*.Mask")
			(remove_unused_layers no)
			(net "I2C_DEBUG_B_SCL")
			(clearance 0.1778)
			(thermal_gap 0.1778)
		)
		(pad "6" thru_hole circle
			(at -1.999996 1.500124 90)
			(size 1.0668 1.0668)
			(drill 0.7112)
			(layers "*.Cu" "*.Mask")
			(remove_unused_layers no)
			(net "I2C_DEBUG_B_SDA")
			(clearance 0.1778)
			(thermal_gap 0.1778)
		)
		(pad "7" thru_hole circle
			(at 0 1.500124 90)
			(size 1.0668 1.0668)
			(drill 0.7112)
			(layers "*.Cu" "*.Mask")
			(remove_unused_layers no)
			(net "DEBUG_CARD_B_PRSNT")
			(clearance 0.1778)
			(thermal_gap 0.1778)
		)
		(pad "8" thru_hole circle
			(at 1.999996 1.500124 90)
			(size 1.0668 1.0668)
			(drill 0.7112)
			(layers "*.Cu" "*.Mask")
			(remove_unused_layers no)
			(net "UART_DEBUG_B_TX")
			(clearance 0.1778)
			(thermal_gap 0.1778)
		)
		(pad "9" thru_hole circle
			(at 3.999992 1.500124 90)
			(size 1.0668 1.0668)
			(drill 0.7112)
			(layers "*.Cu" "*.Mask")
			(remove_unused_layers no)
			(net "UART_DEBUG_B_RX")
			(clearance 0.1778)
			(thermal_gap 0.1778)
		)
		(pad "10" thru_hole circle
			(at 6.400038 -1.999996 90)
			(size 2.7178 2.7178)
			(drill 2.3114)
			(layers "*.Cu" "*.Mask")
			(remove_unused_layers no)
			(net "USB_CONN_B_GND")
			(clearance 0.1524)
			(thermal_gap 0.1524)
		)
		(pad "11" thru_hole circle
			(at -6.400038 -1.999996 90)
			(size 2.7178 2.7178)
			(drill 2.3114)
			(layers "*.Cu" "*.Mask")
			(remove_unused_layers no)
			(net "USB_CONN_B_GND")
			(clearance 0.1524)
			(thermal_gap 0.1524)
		)
		(pad "12" thru_hole circle
			(at 6.400038 1.999996 90)
			(size 2.7178 2.7178)
			(drill 2.3114)
			(layers "*.Cu" "*.Mask")
			(remove_unused_layers no)
			(net "USB_CONN_B_GND")
			(clearance 0.1524)
			(thermal_gap 0.1524)
		)
		(pad "13" thru_hole circle
			(at -6.400038 1.999996 90)
			(size 2.7178 2.7178)
			(drill 2.3114)
			(layers "*.Cu" "*.Mask")
			(remove_unused_layers no)
			(net "USB_CONN_B_GND")
			(clearance 0.1524)
			(thermal_gap 0.1524)
		)
		(zone
			(layer "F.Cu")
			(hatch none 0.5)
			(connect_pads
				(clearance 0)
			)
			(min_thickness 0.25)
			(keepout
				(tracks not_allowed)
				(vias allowed)
				(pads allowed)
				(copperpour not_allowed)
				(footprints allowed)
			)
			(placement
				(enabled no)
				(sheetname "")
			)
			(fill
				(thermal_gap 0.5)
				(thermal_bridge_width 0.5)
				(island_removal_mode 0)
			)
			(polygon
				(pts
					(xy 46.060106 -65.099946) (xy 51.740054 -65.099946) (xy 51.740054 -66.199766) (xy 46.060106 -66.199766)
				)
			)
		)
		(zone
			(layer "F.Cu")
			(hatch none 0.5)
			(connect_pads
				(clearance 0)
			)
			(min_thickness 0.25)
			(keepout
				(tracks not_allowed)
				(vias allowed)
				(pads allowed)
				(copperpour not_allowed)
				(footprints allowed)
			)
			(placement
				(enabled no)
				(sheetname "")
			)
			(fill
				(thermal_gap 0.5)
				(thermal_bridge_width 0.5)
				(island_removal_mode 0)
			)
			(polygon
				(pts
					(xy 46.060106 -53.799994) (xy 51.740054 -53.799994) (xy 51.740054 -54.899814) (xy 46.060106 -54.899814)
				)
			)
		)
		(zone
			(layer "F.Cu")
			(hatch none 0.5)
			(connect_pads
				(clearance 0)
			)
			(min_thickness 0.25)
			(keepout
				(tracks allowed)
				(vias not_allowed)
				(pads allowed)
				(copperpour not_allowed)
				(footprints allowed)
			)
			(placement
				(enabled no)
				(sheetname "")
			)
			(fill
				(thermal_gap 0.5)
				(thermal_bridge_width 0.5)
				(island_removal_mode 0)
			)
			(polygon
				(pts
					(xy 51.740054 -65.099946) (xy 51.740054 -66.199766) (xy 46.060106 -66.199766) (xy 46.060106 -65.099946)
				)
			)
		)
		(zone
			(layer "F.Cu")
			(hatch none 0.5)
			(connect_pads
				(clearance 0)
			)
			(min_thickness 0.25)
			(keepout
				(tracks allowed)
				(vias not_allowed)
				(pads allowed)
				(copperpour not_allowed)
				(footprints allowed)
			)
			(placement
				(enabled no)
				(sheetname "")
			)
			(fill
				(thermal_gap 0.5)
				(thermal_bridge_width 0.5)
				(island_removal_mode 0)
			)
			(polygon
				(pts
					(xy 51.740054 -53.799994) (xy 51.740054 -54.899814) (xy 46.060106 -54.899814) (xy 46.060106 -53.799994)
				)
			)
		)
	)
	(footprint ""
		(layer "F.Cu")
		(at 11.811 -48.66894 -90)
		(property "Reference" "R27"
			(at 0 0 270)
			(layer "F.SilkS")
			(hide yes)
			(effects
				(font
					(size 1.27 1.27)
				)
			)
		)
		(property "Value" "4K7R2F-GP"
			(at 0.064008 -4.679696 270)
			(unlocked yes)
			(layer "F.Fab")
			(hide yes)
			(effects
				(font
					(size 2.54 2.54)
					(thickness 0.381)
				)
			)
		)
		(property "Device Type" "R402H16"
			(at 0.064008 -6.203696 270)
			(unlocked yes)
			(layer "F.Fab")
			(hide yes)
			(effects
				(font
					(size 2.54 2.54)
					(thickness 0.381)
				)
			)
		)
		(duplicate_pad_numbers_are_jumpers no)
		(fp_line
			(start -0.508 -0.9398)
			(end -0.508 0.9398)
			(stroke
				(width 0.1524)
				(type default)
			)
			(layer "F.SilkS")
		)
		(fp_line
			(start 0.508 -0.9398)
			(end -0.508 -0.9398)
			(stroke
				(width 0.1524)
				(type default)
			)
			(layer "F.SilkS")
		)
		(fp_rect
			(start -0.508 0.9398)
			(end 0.508 -0.9398)
			(stroke
				(width 0)
				(type default)
			)
			(fill no)
			(layer "F.CrtYd")
		)
		(fp_rect
			(start -0.508 0.9398)
			(end 0.508 -0.9398)
			(stroke
				(width 0)
				(type default)
			)
			(fill no)
			(layer "F.Fab")
		)
		(pad "1" smd custom
			(at 0 -0.4445 270)
			(size 0.1397 0.1397)
			(layers "F.Cu" "F.Mask" "F.Paste")
			(net "P3V3_STBY_A")
			(options
				(clearance outline)
				(anchor circle)
			)
			(primitives
				(gr_poly
					(pts
						(arc
							(start -0.1778 -0.2794)
							(mid -0.249642 -0.249642)
							(end -0.2794 -0.1778)
						)
						(arc
							(start -0.2794 0.1778)
							(mid -0.249642 0.249642)
							(end -0.1778 0.2794)
						)
						(arc
							(start 0.1778 0.2794)
							(mid 0.249642 0.249642)
							(end 0.2794 0.1778)
						)
						(arc
							(start 0.2794 -0.1778)
							(mid 0.249642 -0.249642)
							(end 0.1778 -0.2794)
						)
					)
					(width 0)
					(fill yes)
				)
			)
		)
		(pad "2" smd custom
			(at 0 0.4445 270)
			(size 0.1397 0.1397)
			(layers "F.Cu" "F.Mask" "F.Paste")
			(net "TEMP_1_A0")
			(options
				(clearance outline)
				(anchor circle)
			)
			(primitives
				(gr_poly
					(pts
						(arc
							(start -0.1778 -0.2794)
							(mid -0.249642 -0.249642)
							(end -0.2794 -0.1778)
						)
						(arc
							(start -0.2794 0.1778)
							(mid -0.249642 0.249642)
							(end -0.1778 0.2794)
						)
						(arc
							(start 0.1778 0.2794)
							(mid 0.249642 0.249642)
							(end 0.2794 0.1778)
						)
						(arc
							(start 0.2794 -0.1778)
							(mid 0.249642 -0.249642)
							(end 0.1778 -0.2794)
						)
					)
					(width 0)
					(fill yes)
				)
			)
		)
	)
	(footprint ""
		(layer "F.Cu")
		(at 54.6862 -13.9446)
		(property "Reference" "R9"
			(at 0 0 0)
			(layer "F.SilkS")
			(hide yes)
			(effects
				(font
					(size 1.27 1.27)
				)
			)
		)
		(property "Value" "0R2J-2-GP"
			(at 0.064008 -4.679696 0)
			(unlocked yes)
			(layer "F.Fab")
			(hide yes)
			(effects
				(font
					(size 2.54 2.54)
					(thickness 0.381)
				)
			)
		)
		(property "Device Type" "R402H16"
			(at 0.064008 -6.203696 0)
			(unlocked yes)
			(layer "F.Fab")
			(hide yes)
			(effects
				(font
					(size 2.54 2.54)
					(thickness 0.381)
				)
			)
		)
		(duplicate_pad_numbers_are_jumpers no)
		(fp_line
			(start -0.508 -0.9398)
			(end -0.508 0.9398)
			(stroke
				(width 0.1524)
				(type default)
			)
			(layer "F.SilkS")
		)
		(fp_line
			(start 0.508 -0.9398)
			(end -0.508 -0.9398)
			(stroke
				(width 0.1524)
				(type default)
			)
			(layer "F.SilkS")
		)
		(fp_rect
			(start -0.508 0.9398)
			(end 0.508 -0.9398)
			(stroke
				(width 0)
				(type default)
			)
			(fill no)
			(layer "F.CrtYd")
		)
		(fp_rect
			(start -0.508 0.9398)
			(end 0.508 -0.9398)
			(stroke
				(width 0)
				(type default)
			)
			(fill no)
			(layer "F.Fab")
		)
		(pad "1" smd custom
			(at 0 -0.4445)
			(size 0.1397 0.1397)
			(layers "F.Cu" "F.Mask" "F.Paste")
			(net "UART_SEL_B_MUX")
			(options
				(clearance outline)
				(anchor circle)
			)
			(primitives
				(gr_poly
					(pts
						(arc
							(start -0.1778 -0.2794)
							(mid -0.249642 -0.249642)
							(end -0.2794 -0.1778)
						)
						(arc
							(start -0.2794 0.1778)
							(mid -0.249642 0.249642)
							(end -0.1778 0.2794)
						)
						(arc
							(start 0.1778 0.2794)
							(mid 0.249642 0.249642)
							(end 0.2794 0.1778)
						)
						(arc
							(start 0.2794 -0.1778)
							(mid 0.249642 -0.249642)
							(end 0.1778 -0.2794)
						)
					)
					(width 0)
					(fill yes)
				)
			)
		)
		(pad "2" smd custom
			(at 0 0.4445)
			(size 0.1397 0.1397)
			(layers "F.Cu" "F.Mask" "F.Paste")
			(net "UART_SEL_B_MUX_R")
			(options
				(clearance outline)
				(anchor circle)
			)
			(primitives
				(gr_poly
					(pts
						(arc
							(start -0.1778 -0.2794)
							(mid -0.249642 -0.249642)
							(end -0.2794 -0.1778)
						)
						(arc
							(start -0.2794 0.1778)
							(mid -0.249642 0.249642)
							(end -0.1778 0.2794)
						)
						(arc
							(start 0.1778 0.2794)
							(mid 0.249642 0.249642)
							(end 0.2794 0.1778)
						)
						(arc
							(start 0.2794 -0.1778)
							(mid 0.249642 -0.249642)
							(end 0.1778 -0.2794)
						)
					)
					(width 0)
					(fill yes)
				)
			)
		)
	)
	(footprint ""
		(layer "F.Cu")
		(at 45.466 -17.8308 90)
		(property "Reference" "R58"
			(at 0 0 90)
			(layer "F.SilkS")
			(hide yes)
			(effects
				(font
					(size 1.27 1.27)
				)
			)
		)
		(property "Value" "20KR2F-L-GP"
			(at 0.064008 -3.993896 90)
			(unlocked yes)
			(layer "F.Fab")
			(hide yes)
			(effects
				(font
					(size 1.016 1.016)
					(thickness 0.1524)
				)
			)
		)
		(property "Device Type" "R402H16"
			(at 0.064008 -5.517896 90)
			(unlocked yes)
			(layer "F.Fab")
			(hide yes)
			(effects
				(font
					(size 1.016 1.016)
					(thickness 0.1524)
				)
			)
		)
		(duplicate_pad_numbers_are_jumpers no)
		(fp_line
			(start 0.508 -0.9398)
			(end -0.508 -0.9398)
			(stroke
				(width 0.1524)
				(type default)
			)
			(layer "F.SilkS")
		)
		(fp_line
			(start -0.508 -0.9398)
			(end -0.508 0.9398)
			(stroke
				(width 0.1524)
				(type default)
			)
			(layer "F.SilkS")
		)
		(fp_rect
			(start -0.508 0.9398)
			(end 0.508 -0.9398)
			(stroke
				(width 0)
				(type default)
			)
			(fill no)
			(layer "F.CrtYd")
		)
		(fp_rect
			(start -0.508 0.9398)
			(end 0.508 -0.9398)
			(stroke
				(width 0)
				(type default)
			)
			(fill no)
			(layer "F.Fab")
		)
		(pad "1" smd custom
			(at 0 -0.4445 90)
			(size 0.1397 0.1397)
			(layers "F.Cu" "F.Mask" "F.Paste")
			(net "P3V3_STBY_B")
			(options
				(clearance outline)
				(anchor circle)
			)
			(primitives
				(gr_poly
					(pts
						(arc
							(start -0.1778 -0.2794)
							(mid -0.249642 -0.249642)
							(end -0.2794 -0.1778)
						)
						(arc
							(start -0.2794 0.1778)
							(mid -0.249642 0.249642)
							(end -0.1778 0.2794)
						)
						(arc
							(start 0.1778 0.2794)
							(mid 0.249642 0.249642)
							(end 0.2794 0.1778)
						)
						(arc
							(start 0.2794 -0.1778)
							(mid 0.249642 -0.249642)
							(end 0.1778 -0.2794)
						)
					)
					(width 0)
					(fill yes)
				)
			)
		)
		(pad "2" smd custom
			(at 0 0.4445 90)
			(size 0.1397 0.1397)
			(layers "F.Cu" "F.Mask" "F.Paste")
			(net "I2C_DEBUG_B_SCL_L")
			(options
				(clearance outline)
				(anchor circle)
			)
			(primitives
				(gr_poly
					(pts
						(arc
							(start -0.1778 -0.2794)
							(mid -0.249642 -0.249642)
							(end -0.2794 -0.1778)
						)
						(arc
							(start -0.2794 0.1778)
							(mid -0.249642 0.249642)
							(end -0.1778 0.2794)
						)
						(arc
							(start 0.1778 0.2794)
							(mid 0.249642 0.249642)
							(end 0.2794 0.1778)
						)
						(arc
							(start 0.2794 -0.1778)
							(mid 0.249642 -0.249642)
							(end 0.1778 -0.2794)
						)
					)
					(width 0)
					(fill yes)
				)
			)
		)
	)
	(footprint ""
		(layer "F.Cu")
		(at 53.02377 -29.8196 90)
		(property "Reference" "U6"
			(at 0 0 90)
			(layer "F.SilkS")
			(hide yes)
			(effects
				(font
					(size 1.27 1.27)
				)
			)
		)
		(property "Value" "TPS3422EGDRYR-GP"
			(at -0.1016 -5.4229 90)
			(unlocked yes)
			(layer "F.Fab")
			(hide yes)
			(effects
				(font
					(size 1.016 1.016)
					(thickness 0.1524)
				)
			)
		)
		(property "Device Type" "XSON6H24"
			(at -0.1016 -6.9469 90)
			(unlocked yes)
			(layer "F.Fab")
			(hide yes)
			(effects
				(font
					(size 1.016 1.016)
					(thickness 0.1524)
				)
			)
		)
		(duplicate_pad_numbers_are_jumpers no)
		(fp_line
			(start -0.7239 -0.762)
			(end -0.7239 -0.9398)
			(stroke
				(width 0.1524)
				(type default)
			)
			(layer "F.SilkS")
		)
		(fp_line
			(start -0.9779 -0.508)
			(end -0.7239 -0.762)
			(stroke
				(width 0.1524)
				(type default)
			)
			(layer "F.SilkS")
		)
		(fp_line
			(start -1.1557 -0.508)
			(end -0.9779 -0.508)
			(stroke
				(width 0.1524)
				(type default)
			)
			(layer "F.SilkS")
		)
		(fp_line
			(start 0.9779 0.508)
			(end 1.1557 0.508)
			(stroke
				(width 0.1524)
				(type default)
			)
			(layer "F.SilkS")
		)
		(fp_line
			(start -0.9779 0.508)
			(end -0.7239 0.762)
			(stroke
				(width 0.1524)
				(type default)
			)
			(layer "F.SilkS")
		)
		(fp_line
			(start -1.1557 0.508)
			(end -0.9779 0.508)
			(stroke
				(width 0.1524)
				(type default)
			)
			(layer "F.SilkS")
		)
		(fp_line
			(start 0.7239 0.762)
			(end 0.9779 0.508)
			(stroke
				(width 0.1524)
				(type default)
			)
			(layer "F.SilkS")
		)
		(fp_line
			(start -0.7239 0.762)
			(end -0.7239 0.9398)
			(stroke
				(width 0.1524)
				(type default)
			)
			(layer "F.SilkS")
		)
		(fp_line
			(start 0.7239 0.9398)
			(end 0.7239 0.762)
			(stroke
				(width 0.1524)
				(type default)
			)
			(layer "F.SilkS")
		)
		(fp_poly
			(pts
				(xy 0.846328 -0.607314) (xy 0.846328 -1.016) (xy 1.2319 -0.607314)
			)
			(stroke
				(width 0)
				(type default)
			)
			(fill yes)
			(layer "F.SilkS")
		)
		(fp_rect
			(start -0.7239 0.508)
			(end 0.7239 -0.508)
			(stroke
				(width 0)
				(type default)
			)
			(fill no)
			(layer "F.CrtYd")
		)
		(fp_poly
			(pts
				(xy -1.2319 1.016) (xy -1.2319 -1.016) (xy 1.2319 -1.016) (xy 1.2319 -0.0889) (xy 0.7239 -0.0889)
				(xy 0.7239 -0.508) (xy -0.7239 -0.508) (xy -0.7239 0.508) (xy 0.7239 0.508) (xy 0.7239 -0.0762)
				(xy 1.2319 -0.0762) (xy 1.2319 1.016)
			)
			(stroke
				(width 0)
				(type default)
			)
			(fill no)
			(layer "F.CrtYd")
		)
		(fp_rect
			(start -1.2319 1.016)
			(end 1.2319 -1.016)
			(stroke
				(width 0)
				(type default)
			)
			(fill no)
			(layer "F.Fab")
		)
		(pad "1" smd rect
			(at 0.50038 -0.310134 90)
			(size 0.3048 0.381)
			(layers "F.Cu" "F.Mask" "F.Paste")
			(net "SYS_RESET_BTN_B_N_R")
		)
		(pad "2" smd rect
			(at 0 -0.310134 90)
			(size 0.3048 0.381)
			(layers "F.Cu" "F.Mask" "F.Paste")
			(net "GND")
		)
		(pad "3" smd rect
			(at -0.50038 -0.310134 90)
			(size 0.3048 0.381)
			(layers "F.Cu" "F.Mask" "F.Paste")
			(net "SYS_RESET_BTN_B")
		)
		(pad "4" smd rect
			(at -0.50038 0.310134 90)
			(size 0.3048 0.381)
			(layers "F.Cu" "F.Mask" "F.Paste")
			(net "P3V3_STBY_B")
		)
		(pad "5" smd rect
			(at 0 0.310134 90)
			(size 0.3048 0.381)
			(layers "F.Cu" "F.Mask" "F.Paste")
			(net "RST_B_TS")
		)
		(pad "6" smd rect
			(at 0.50038 0.310134 90)
			(size 0.3048 0.381)
			(layers "F.Cu" "F.Mask" "F.Paste")
			(net "GND")
		)
	)
	(footprint ""
		(layer "F.Cu")
		(at 8.265668 -26.299668 90)
		(property "Reference" "C12"
			(at 0 0 90)
			(layer "F.SilkS")
			(hide yes)
			(effects
				(font
					(size 1.27 1.27)
				)
			)
		)
		(property "Value" "SCD1U16V2KX-3GP"
			(at 1.1811 -3.3909 90)
			(unlocked yes)
			(layer "F.Fab")
			(hide yes)
			(effects
				(font
					(size 2.54 2.54)
					(thickness 0.381)
				)
			)
		)
		(property "Device Type" "C402H22"
			(at 1.1811 -4.9149 90)
			(unlocked yes)
			(layer "F.Fab")
			(hide yes)
			(effects
				(font
					(size 2.54 2.54)
					(thickness 0.381)
				)
			)
		)
		(duplicate_pad_numbers_are_jumpers no)
		(fp_rect
			(start -0.4318 0.9525)
			(end 0.4318 -0.9525)
			(stroke
				(width 0)
				(type default)
			)
			(fill no)
			(layer "F.CrtYd")
		)
		(fp_rect
			(start -0.4318 0.9525)
			(end 0.4318 -0.9525)
			(stroke
				(width 0)
				(type default)
			)
			(fill no)
			(layer "F.Fab")
		)
		(pad "1" smd custom
			(at 0 -0.4445 90)
			(size 0.1524 0.1524)
			(layers "F.Cu" "F.Mask" "F.Paste")
			(net "P3V3_STBY_A")
			(options
				(clearance outline)
				(anchor circle)
			)
			(primitives
				(gr_poly
					(pts
						(arc
							(start 0.3048 -0.2032)
							(mid 0.275042 -0.275042)
							(end 0.2032 -0.3048)
						)
						(arc
							(start -0.2032 -0.3048)
							(mid -0.275042 -0.275042)
							(end -0.3048 -0.2032)
						)
						(arc
							(start -0.3048 0.2032)
							(mid -0.275042 0.275042)
							(end -0.2032 0.3048)
						)
						(arc
							(start 0.2032 0.3048)
							(mid 0.275042 0.275042)
							(end 0.3048 0.2032)
						)
					)
					(width 0)
					(fill yes)
				)
			)
		)
		(pad "2" smd custom
			(at 0 0.4445 90)
			(size 0.1524 0.1524)
			(layers "F.Cu" "F.Mask" "F.Paste")
			(net "GND")
			(options
				(clearance outline)
				(anchor circle)
			)
			(primitives
				(gr_poly
					(pts
						(arc
							(start 0.3048 -0.2032)
							(mid 0.275042 -0.275042)
							(end 0.2032 -0.3048)
						)
						(arc
							(start -0.2032 -0.3048)
							(mid -0.275042 -0.275042)
							(end -0.3048 -0.2032)
						)
						(arc
							(start -0.3048 0.2032)
							(mid -0.275042 0.275042)
							(end -0.2032 0.3048)
						)
						(arc
							(start 0.2032 0.3048)
							(mid 0.275042 0.275042)
							(end 0.3048 0.2032)
						)
					)
					(width 0)
					(fill yes)
				)
			)
		)
	)
	(footprint ""
		(layer "F.Cu")
		(at 45.355002 -50.041556 90)
		(property "Reference" "TP5"
			(at 0 0 90)
			(layer "F.SilkS")
			(hide yes)
			(effects
				(font
					(size 1.27 1.27)
				)
			)
		)
		(property "Value" "TPAD28-2-GP"
			(at -0.0127 -2.3495 90)
			(unlocked yes)
			(layer "F.Fab")
			(hide yes)
			(effects
				(font
					(size 2.54 2.54)
					(thickness 0.381)
				)
			)
		)
		(property "Device Type" "TPAD28"
			(at -0.0127 -3.8735 90)
			(unlocked yes)
			(layer "F.Fab")
			(hide yes)
			(effects
				(font
					(size 2.54 2.54)
					(thickness 0.381)
				)
			)
		)
		(duplicate_pad_numbers_are_jumpers no)
		(fp_poly
			(pts
				(arc
					(start 0 0.3556)
					(mid 0 -0.3556)
					(end 0 0.3556)
				)
			)
			(stroke
				(width 0)
				(type default)
			)
			(fill no)
			(layer "F.CrtYd")
		)
		(fp_poly
			(pts
				(arc
					(start 0 0.6096)
					(mid 0 -0.6096)
					(end 0 0.6096)
				)
			)
			(stroke
				(width 0)
				(type default)
			)
			(fill no)
			(layer "F.Fab")
		)
		(pad "1" smd circle
			(at 0 0 90)
			(size 0.7112 0.7112)
			(layers "F.Cu" "F.Mask" "F.Paste")
			(net "DEBUG_USB_B_DP")
		)
	)
	(footprint ""
		(layer "F.Cu")
		(at 10.1346 -20.9042 180)
		(property "Reference" "C19"
			(at 0 0 180)
			(layer "F.SilkS")
			(hide yes)
			(effects
				(font
					(size 1.27 1.27)
				)
			)
		)
		(property "Value" "SCD1U16V2KX-3GP"
			(at 1.1811 -2.7051 180)
			(unlocked yes)
			(layer "F.Fab")
			(hide yes)
			(effects
				(font
					(size 1.016 1.016)
					(thickness 0.1524)
				)
			)
		)
		(property "Device Type" "C402H22"
			(at 1.1811 -4.2291 180)
			(unlocked yes)
			(layer "F.Fab")
			(hide yes)
			(effects
				(font
					(size 1.016 1.016)
					(thickness 0.1524)
				)
			)
		)
		(duplicate_pad_numbers_are_jumpers no)
		(fp_rect
			(start -0.4318 0.9525)
			(end 0.4318 -0.9525)
			(stroke
				(width 0)
				(type default)
			)
			(fill no)
			(layer "F.CrtYd")
		)
		(fp_rect
			(start -0.4318 0.9525)
			(end 0.4318 -0.9525)
			(stroke
				(width 0)
				(type default)
			)
			(fill no)
			(layer "F.Fab")
		)
		(pad "1" smd custom
			(at 0 -0.4445 180)
			(size 0.1524 0.1524)
			(layers "F.Cu" "F.Mask" "F.Paste")
			(net "P3V3_STBY_A")
			(options
				(clearance outline)
				(anchor circle)
			)
			(primitives
				(gr_poly
					(pts
						(arc
							(start 0.3048 -0.2032)
							(mid 0.275042 -0.275042)
							(end 0.2032 -0.3048)
						)
						(arc
							(start -0.2032 -0.3048)
							(mid -0.275042 -0.275042)
							(end -0.3048 -0.2032)
						)
						(arc
							(start -0.3048 0.2032)
							(mid -0.275042 0.275042)
							(end -0.2032 0.3048)
						)
						(arc
							(start 0.2032 0.3048)
							(mid 0.275042 0.275042)
							(end 0.3048 0.2032)
						)
					)
					(width 0)
					(fill yes)
				)
			)
		)
		(pad "2" smd custom
			(at 0 0.4445 180)
			(size 0.1524 0.1524)
			(layers "F.Cu" "F.Mask" "F.Paste")
			(net "GND")
			(options
				(clearance outline)
				(anchor circle)
			)
			(primitives
				(gr_poly
					(pts
						(arc
							(start 0.3048 -0.2032)
							(mid 0.275042 -0.275042)
							(end 0.2032 -0.3048)
						)
						(arc
							(start -0.2032 -0.3048)
							(mid -0.275042 -0.275042)
							(end -0.3048 -0.2032)
						)
						(arc
							(start -0.3048 0.2032)
							(mid -0.275042 0.275042)
							(end -0.2032 0.3048)
						)
						(arc
							(start 0.2032 0.3048)
							(mid 0.275042 0.275042)
							(end 0.3048 0.2032)
						)
					)
					(width 0)
					(fill yes)
				)
			)
		)
	)
	(footprint ""
		(layer "F.Cu")
		(at 14.7066 -9.8044 -90)
		(property "Reference" "C22"
			(at 0 0 270)
			(layer "F.SilkS")
			(hide yes)
			(effects
				(font
					(size 1.27 1.27)
				)
			)
		)
		(property "Value" "SCD1U16V2KX-3GP"
			(at 1.1811 -2.7051 270)
			(unlocked yes)
			(layer "F.Fab")
			(hide yes)
			(effects
				(font
					(size 1.016 1.016)
					(thickness 0.1524)
				)
			)
		)
		(property "Device Type" "C402H22"
			(at 1.1811 -4.2291 270)
			(unlocked yes)
			(layer "F.Fab")
			(hide yes)
			(effects
				(font
					(size 1.016 1.016)
					(thickness 0.1524)
				)
			)
		)
		(duplicate_pad_numbers_are_jumpers no)
		(fp_rect
			(start -0.4318 0.9525)
			(end 0.4318 -0.9525)
			(stroke
				(width 0)
				(type default)
			)
			(fill no)
			(layer "F.CrtYd")
		)
		(fp_rect
			(start -0.4318 0.9525)
			(end 0.4318 -0.9525)
			(stroke
				(width 0)
				(type default)
			)
			(fill no)
			(layer "F.Fab")
		)
		(pad "1" smd custom
			(at 0 -0.4445 270)
			(size 0.1524 0.1524)
			(layers "F.Cu" "F.Mask" "F.Paste")
			(net "P3V3_STBY_A")
			(options
				(clearance outline)
				(anchor circle)
			)
			(primitives
				(gr_poly
					(pts
						(arc
							(start 0.3048 -0.2032)
							(mid 0.275042 -0.275042)
							(end 0.2032 -0.3048)
						)
						(arc
							(start -0.2032 -0.3048)
							(mid -0.275042 -0.275042)
							(end -0.3048 -0.2032)
						)
						(arc
							(start -0.3048 0.2032)
							(mid -0.275042 0.275042)
							(end -0.2032 0.3048)
						)
						(arc
							(start 0.2032 0.3048)
							(mid 0.275042 0.275042)
							(end 0.3048 0.2032)
						)
					)
					(width 0)
					(fill yes)
				)
			)
		)
		(pad "2" smd custom
			(at 0 0.4445 270)
			(size 0.1524 0.1524)
			(layers "F.Cu" "F.Mask" "F.Paste")
			(net "GND")
			(options
				(clearance outline)
				(anchor circle)
			)
			(primitives
				(gr_poly
					(pts
						(arc
							(start 0.3048 -0.2032)
							(mid 0.275042 -0.275042)
							(end 0.2032 -0.3048)
						)
						(arc
							(start -0.2032 -0.3048)
							(mid -0.275042 -0.275042)
							(end -0.3048 -0.2032)
						)
						(arc
							(start -0.3048 0.2032)
							(mid -0.275042 0.275042)
							(end -0.2032 0.3048)
						)
						(arc
							(start 0.2032 0.3048)
							(mid 0.275042 0.275042)
							(end 0.3048 0.2032)
						)
					)
					(width 0)
					(fill yes)
				)
			)
		)
	)
	(footprint ""
		(layer "F.Cu")
		(at 5.9182 -27.305 180)
		(property "Reference" "R47"
			(at 0 0 180)
			(layer "F.SilkS")
			(hide yes)
			(effects
				(font
					(size 1.27 1.27)
				)
			)
		)
		(property "Value" "100KR2F-L1-GP"
			(at 0.064008 -4.679696 180)
			(unlocked yes)
			(layer "F.Fab")
			(hide yes)
			(effects
				(font
					(size 2.54 2.54)
					(thickness 0.381)
				)
			)
		)
		(property "Device Type" "R402H16"
			(at 0.064008 -6.203696 180)
			(unlocked yes)
			(layer "F.Fab")
			(hide yes)
			(effects
				(font
					(size 2.54 2.54)
					(thickness 0.381)
				)
			)
		)
		(duplicate_pad_numbers_are_jumpers no)
		(fp_line
			(start 0.508 -0.9398)
			(end -0.508 -0.9398)
			(stroke
				(width 0.1524)
				(type default)
			)
			(layer "F.SilkS")
		)
		(fp_line
			(start -0.508 -0.9398)
			(end -0.508 0.9398)
			(stroke
				(width 0.1524)
				(type default)
			)
			(layer "F.SilkS")
		)
		(fp_rect
			(start -0.508 0.9398)
			(end 0.508 -0.9398)
			(stroke
				(width 0)
				(type default)
			)
			(fill no)
			(layer "F.CrtYd")
		)
		(fp_rect
			(start -0.508 0.9398)
			(end 0.508 -0.9398)
			(stroke
				(width 0)
				(type default)
			)
			(fill no)
			(layer "F.Fab")
		)
		(pad "1" smd custom
			(at 0 -0.4445 180)
			(size 0.1397 0.1397)
			(layers "F.Cu" "F.Mask" "F.Paste")
			(net "P3V3_STBY_A")
			(options
				(clearance outline)
				(anchor circle)
			)
			(primitives
				(gr_poly
					(pts
						(arc
							(start -0.1778 -0.2794)
							(mid -0.249642 -0.249642)
							(end -0.2794 -0.1778)
						)
						(arc
							(start -0.2794 0.1778)
							(mid -0.249642 0.249642)
							(end -0.1778 0.2794)
						)
						(arc
							(start 0.1778 0.2794)
							(mid 0.249642 0.249642)
							(end 0.2794 0.1778)
						)
						(arc
							(start 0.2794 -0.1778)
							(mid 0.249642 -0.249642)
							(end 0.1778 -0.2794)
						)
					)
					(width 0)
					(fill yes)
				)
			)
		)
		(pad "2" smd custom
			(at 0 0.4445 180)
			(size 0.1397 0.1397)
			(layers "F.Cu" "F.Mask" "F.Paste")
			(net "SYS_RESET_BTN_A")
			(options
				(clearance outline)
				(anchor circle)
			)
			(primitives
				(gr_poly
					(pts
						(arc
							(start -0.1778 -0.2794)
							(mid -0.249642 -0.249642)
							(end -0.2794 -0.1778)
						)
						(arc
							(start -0.2794 0.1778)
							(mid -0.249642 0.249642)
							(end -0.1778 0.2794)
						)
						(arc
							(start 0.1778 0.2794)
							(mid 0.249642 0.249642)
							(end 0.2794 0.1778)
						)
						(arc
							(start 0.2794 -0.1778)
							(mid 0.249642 -0.249642)
							(end 0.1778 -0.2794)
						)
					)
					(width 0)
					(fill yes)
				)
			)
		)
	)
	(footprint ""
		(layer "F.Cu")
		(at 43.8404 -12.3952 90)
		(property "Reference" "R60"
			(at 0 0 90)
			(layer "F.SilkS")
			(hide yes)
			(effects
				(font
					(size 1.27 1.27)
				)
			)
		)
		(property "Value" "100KR2F-L1-GP"
			(at 0.064008 -3.993896 90)
			(unlocked yes)
			(layer "F.Fab")
			(hide yes)
			(effects
				(font
					(size 1.016 1.016)
					(thickness 0.1524)
				)
			)
		)
		(property "Device Type" "R402H16"
			(at 0.064008 -5.517896 90)
			(unlocked yes)
			(layer "F.Fab")
			(hide yes)
			(effects
				(font
					(size 1.016 1.016)
					(thickness 0.1524)
				)
			)
		)
		(duplicate_pad_numbers_are_jumpers no)
		(fp_line
			(start 0.508 -0.9398)
			(end -0.508 -0.9398)
			(stroke
				(width 0.1524)
				(type default)
			)
			(layer "F.SilkS")
		)
		(fp_line
			(start -0.508 -0.9398)
			(end -0.508 0.9398)
			(stroke
				(width 0.1524)
				(type default)
			)
			(layer "F.SilkS")
		)
		(fp_rect
			(start -0.508 0.9398)
			(end 0.508 -0.9398)
			(stroke
				(width 0)
				(type default)
			)
			(fill no)
			(layer "F.CrtYd")
		)
		(fp_rect
			(start -0.508 0.9398)
			(end 0.508 -0.9398)
			(stroke
				(width 0)
				(type default)
			)
			(fill no)
			(layer "F.Fab")
		)
		(pad "1" smd custom
			(at 0 -0.4445 90)
			(size 0.1397 0.1397)
			(layers "F.Cu" "F.Mask" "F.Paste")
			(net "DEBUG_CARD_B_PRSNT")
			(options
				(clearance outline)
				(anchor circle)
			)
			(primitives
				(gr_poly
					(pts
						(arc
							(start -0.1778 -0.2794)
							(mid -0.249642 -0.249642)
							(end -0.2794 -0.1778)
						)
						(arc
							(start -0.2794 0.1778)
							(mid -0.249642 0.249642)
							(end -0.1778 0.2794)
						)
						(arc
							(start 0.1778 0.2794)
							(mid 0.249642 0.249642)
							(end 0.2794 0.1778)
						)
						(arc
							(start 0.2794 -0.1778)
							(mid 0.249642 -0.249642)
							(end 0.1778 -0.2794)
						)
					)
					(width 0)
					(fill yes)
				)
			)
		)
		(pad "2" smd custom
			(at 0 0.4445 90)
			(size 0.1397 0.1397)
			(layers "F.Cu" "F.Mask" "F.Paste")
			(net "GND")
			(options
				(clearance outline)
				(anchor circle)
			)
			(primitives
				(gr_poly
					(pts
						(arc
							(start -0.1778 -0.2794)
							(mid -0.249642 -0.249642)
							(end -0.2794 -0.1778)
						)
						(arc
							(start -0.2794 0.1778)
							(mid -0.249642 0.249642)
							(end -0.1778 0.2794)
						)
						(arc
							(start 0.1778 0.2794)
							(mid 0.249642 0.249642)
							(end 0.2794 0.1778)
						)
						(arc
							(start 0.2794 -0.1778)
							(mid 0.249642 -0.249642)
							(end 0.1778 -0.2794)
						)
					)
					(width 0)
					(fill yes)
				)
			)
		)
	)
	(footprint ""
		(layer "F.Cu")
		(at 2.437638 -63.583058 -90)
		(property "Reference" "C3"
			(at 0 0 270)
			(layer "F.SilkS")
			(hide yes)
			(effects
				(font
					(size 1.27 1.27)
				)
			)
		)
		(property "Value" "SC1U16V3KX-5GP"
			(at 0 -3.5052 270)
			(unlocked yes)
			(layer "F.Fab")
			(hide yes)
			(effects
				(font
					(size 2.54 2.54)
					(thickness 0.381)
				)
			)
		)
		(property "Device Type" "C603H36"
			(at 0 -5.0292 270)
			(unlocked yes)
			(layer "F.Fab")
			(hide yes)
			(effects
				(font
					(size 2.54 2.54)
					(thickness 0.381)
				)
			)
		)
		(duplicate_pad_numbers_are_jumpers no)
		(fp_line
			(start 0.508 0)
			(end -0.508 0)
			(stroke
				(width 0.2032)
				(type default)
			)
			(layer "F.SilkS")
		)
		(fp_rect
			(start -0.5842 1.3335)
			(end 0.5842 -1.3335)
			(stroke
				(width 0)
				(type default)
			)
			(fill no)
			(layer "F.CrtYd")
		)
		(fp_rect
			(start -0.5842 1.3335)
			(end 0.5842 -1.3335)
			(stroke
				(width 0)
				(type default)
			)
			(fill no)
			(layer "F.Fab")
		)
		(pad "1" smd custom
			(at 0 -0.762 270)
			(size 0.2159 0.2159)
			(layers "F.Cu" "F.Mask" "F.Paste")
			(net "P5V_USB_A")
			(options
				(clearance outline)
				(anchor circle)
			)
			(primitives
				(gr_poly
					(pts
						(arc
							(start -0.3302 -0.4318)
							(mid -0.402042 -0.402042)
							(end -0.4318 -0.3302)
						)
						(arc
							(start -0.4318 0.3302)
							(mid -0.402042 0.402042)
							(end -0.3302 0.4318)
						)
						(arc
							(start 0.3302 0.4318)
							(mid 0.402042 0.402042)
							(end 0.4318 0.3302)
						)
						(arc
							(start 0.4318 -0.3302)
							(mid 0.402042 -0.402042)
							(end 0.3302 -0.4318)
						)
					)
					(width 0)
					(fill yes)
				)
			)
		)
		(pad "2" smd custom
			(at 0 0.762 270)
			(size 0.2159 0.2159)
			(layers "F.Cu" "F.Mask" "F.Paste")
			(net "GND")
			(options
				(clearance outline)
				(anchor circle)
			)
			(primitives
				(gr_poly
					(pts
						(arc
							(start -0.3302 -0.4318)
							(mid -0.402042 -0.402042)
							(end -0.4318 -0.3302)
						)
						(arc
							(start -0.4318 0.3302)
							(mid -0.402042 0.402042)
							(end -0.3302 0.4318)
						)
						(arc
							(start 0.3302 0.4318)
							(mid 0.402042 0.402042)
							(end 0.4318 0.3302)
						)
						(arc
							(start 0.4318 -0.3302)
							(mid 0.402042 -0.402042)
							(end 0.3302 -0.4318)
						)
					)
					(width 0)
					(fill yes)
				)
			)
		)
	)
	(footprint ""
		(layer "F.Cu")
		(at 13.97 -28.067 90)
		(property "Reference" "U15"
			(at 0 0 90)
			(layer "F.SilkS")
			(hide yes)
			(effects
				(font
					(size 1.27 1.27)
				)
			)
		)
		(property "Value" "SN74LVC1G08DCKR-GP"
			(at -2.3368 -8.6868 90)
			(unlocked yes)
			(layer "F.Fab")
			(hide yes)
			(effects
				(font
					(size 1.016 1.016)
					(thickness 0.1524)
				)
			)
		)
		(property "Device Type" "SC70-5H44"
			(at -2.3114 -10.414 90)
			(unlocked yes)
			(layer "F.Fab")
			(hide yes)
			(effects
				(font
					(size 1.016 1.016)
					(thickness 0.1524)
				)
			)
		)
		(duplicate_pad_numbers_are_jumpers no)
		(fp_line
			(start 1.3843 -1.8034)
			(end 1.3843 -1.1176)
			(stroke
				(width 0.3302)
				(type default)
			)
			(layer "F.SilkS")
		)
		(fp_line
			(start 0.6604 -1.8034)
			(end 1.3843 -1.8034)
			(stroke
				(width 0.3302)
				(type default)
			)
			(layer "F.SilkS")
		)
		(fp_line
			(start 1.27 -1.7018)
			(end 1.27 1.7018)
			(stroke
				(width 0.1524)
				(type default)
			)
			(layer "F.SilkS")
		)
		(fp_line
			(start -1.27 -1.7018)
			(end 1.27 -1.7018)
			(stroke
				(width 0.1524)
				(type default)
			)
			(layer "F.SilkS")
		)
		(fp_line
			(start 1.27 1.7018)
			(end -1.27 1.7018)
			(stroke
				(width 0.1524)
				(type default)
			)
			(layer "F.SilkS")
		)
		(fp_line
			(start -1.27 1.7018)
			(end -1.27 -1.7018)
			(stroke
				(width 0.1524)
				(type default)
			)
			(layer "F.SilkS")
		)
		(fp_rect
			(start -1.524 1.9558)
			(end 1.524 -1.9558)
			(stroke
				(width 0)
				(type default)
			)
			(fill no)
			(layer "F.CrtYd")
		)
		(fp_poly
			(pts
				(xy -1.524 -1.9558) (xy 1.524 -1.9558) (xy 1.524 1.9558) (xy -1.524 1.9558)
			)
			(stroke
				(width 0)
				(type default)
			)
			(fill no)
			(layer "F.Fab")
		)
		(pad "1" smd rect
			(at 0.65024 -0.8255 90)
			(size 0.4064 1.2192)
			(layers "F.Cu" "F.Mask" "F.Paste")
			(net "SYS_RESET_BTN_A_N_R")
		)
		(pad "2" smd rect
			(at 0 -0.8255 90)
			(size 0.4064 1.2192)
			(layers "F.Cu" "F.Mask" "F.Paste")
			(net "DEBUG_RST_A_BTN_N")
		)
		(pad "3" smd rect
			(at -0.65024 -0.8255 90)
			(size 0.4064 1.2192)
			(layers "F.Cu" "F.Mask" "F.Paste")
			(net "GND")
		)
		(pad "4" smd rect
			(at -0.65024 0.8255 90)
			(size 0.4064 1.2192)
			(layers "F.Cu" "F.Mask" "F.Paste")
			(net "SYS_RESET_BTN_A_N")
		)
		(pad "5" smd rect
			(at 0.65024 0.8255 90)
			(size 0.4064 1.2192)
			(layers "F.Cu" "F.Mask" "F.Paste")
			(net "P3V3_STBY_A")
		)
	)
	(footprint ""
		(layer "F.Cu")
		(at 48.662082 -39.751 -90)
		(property "Reference" "R26"
			(at 0 0 270)
			(layer "F.SilkS")
			(hide yes)
			(effects
				(font
					(size 1.27 1.27)
				)
			)
		)
		(property "Value" "120R3J-2-GP"
			(at -0.0254 -2.5146 270)
			(unlocked yes)
			(layer "F.Fab")
			(hide yes)
			(effects
				(font
					(size 1.016 1.016)
					(thickness 0.1524)
				)
			)
		)
		(property "Device Type" "R603H22"
			(at -0.0254 -4.0386 270)
			(unlocked yes)
			(layer "F.Fab")
			(hide yes)
			(effects
				(font
					(size 1.016 1.016)
					(thickness 0.1524)
				)
			)
		)
		(duplicate_pad_numbers_are_jumpers no)
		(fp_line
			(start -0.4826 0)
			(end -0.2032 0)
			(stroke
				(width 0.2032)
				(type default)
			)
			(layer "F.SilkS")
		)
		(fp_line
			(start 0.2032 0)
			(end 0.4826 0)
			(stroke
				(width 0.2032)
				(type default)
			)
			(layer "F.SilkS")
		)
		(fp_rect
			(start -0.5842 1.3335)
			(end 0.5842 -1.3335)
			(stroke
				(width 0)
				(type default)
			)
			(fill no)
			(layer "F.CrtYd")
		)
		(fp_rect
			(start -0.5842 1.3335)
			(end 0.5842 -1.3335)
			(stroke
				(width 0)
				(type default)
			)
			(fill no)
			(layer "F.Fab")
		)
		(pad "1" smd custom
			(at 0 -0.762 270)
			(size 0.2159 0.2159)
			(layers "F.Cu" "F.Mask" "F.Paste")
			(net "P5V_USB_B")
			(options
				(clearance outline)
				(anchor circle)
			)
			(primitives
				(gr_poly
					(pts
						(arc
							(start -0.3302 -0.4318)
							(mid -0.402042 -0.402042)
							(end -0.4318 -0.3302)
						)
						(arc
							(start -0.4318 0.3302)
							(mid -0.402042 0.402042)
							(end -0.3302 0.4318)
						)
						(arc
							(start 0.3302 0.4318)
							(mid 0.402042 0.402042)
							(end 0.4318 0.3302)
						)
						(arc
							(start 0.4318 -0.3302)
							(mid 0.402042 -0.402042)
							(end 0.3302 -0.4318)
						)
					)
					(width 0)
					(fill yes)
				)
			)
		)
		(pad "2" smd custom
			(at 0 0.762 270)
			(size 0.2159 0.2159)
			(layers "F.Cu" "F.Mask" "F.Paste")
			(net "SYS_FAULT_B_R")
			(options
				(clearance outline)
				(anchor circle)
			)
			(primitives
				(gr_poly
					(pts
						(arc
							(start -0.3302 -0.4318)
							(mid -0.402042 -0.402042)
							(end -0.4318 -0.3302)
						)
						(arc
							(start -0.4318 0.3302)
							(mid -0.402042 0.402042)
							(end -0.3302 0.4318)
						)
						(arc
							(start 0.3302 0.4318)
							(mid 0.402042 0.402042)
							(end 0.4318 0.3302)
						)
						(arc
							(start 0.4318 -0.3302)
							(mid 0.402042 -0.402042)
							(end 0.3302 -0.4318)
						)
					)
					(width 0)
					(fill yes)
				)
			)
		)
	)
	(footprint ""
		(layer "F.Cu")
		(at 45.974 -20.193 -90)
		(property "Reference" "U12"
			(at 0 0 270)
			(layer "F.SilkS")
			(hide yes)
			(effects
				(font
					(size 1.27 1.27)
				)
			)
		)
		(property "Value" "PCA9306DCTT-GP"
			(at 0 -11.6332 270)
			(unlocked yes)
			(layer "F.Fab")
			(hide yes)
			(effects
				(font
					(size 1.016 1.016)
					(thickness 0.1524)
				)
			)
		)
		(property "Device Type" "SSOIC8H52"
			(at 0 -13.1572 270)
			(unlocked yes)
			(layer "F.Fab")
			(hide yes)
			(effects
				(font
					(size 1.016 1.016)
					(thickness 0.1524)
				)
			)
		)
		(duplicate_pad_numbers_are_jumpers no)
		(fp_line
			(start -1.524 0.5842)
			(end -1.524 2.286)
			(stroke
				(width 0.508)
				(type default)
			)
			(layer "F.SilkS")
		)
		(fp_line
			(start 1.0668 0.5842)
			(end -1.524 0.5842)
			(stroke
				(width 0.1524)
				(type default)
			)
			(layer "F.SilkS")
		)
		(fp_line
			(start -1.397 0)
			(end -1.7018 0.3048)
			(stroke
				(width 0.1524)
				(type default)
			)
			(layer "F.SilkS")
		)
		(fp_line
			(start -1.397 0)
			(end -1.7018 -0.3048)
			(stroke
				(width 0.1524)
				(type default)
			)
			(layer "F.SilkS")
		)
		(fp_line
			(start -1.7018 -0.5842)
			(end -1.7018 2.286)
			(stroke
				(width 0.1524)
				(type default)
			)
			(layer "F.SilkS")
		)
		(fp_line
			(start -1.7018 -0.5842)
			(end 1.0668 -0.5842)
			(stroke
				(width 0.1524)
				(type default)
			)
			(layer "F.SilkS")
		)
		(fp_line
			(start 1.0668 -0.5842)
			(end 1.0668 0.5842)
			(stroke
				(width 0.1524)
				(type default)
			)
			(layer "F.SilkS")
		)
		(fp_poly
			(pts
				(xy -1.1684 -0.5842) (xy 1.0668 -0.5842) (xy 1.0668 0.5842) (xy -1.1684 0.5842)
			)
			(stroke
				(width 0)
				(type default)
			)
			(fill yes)
			(layer "F.SilkS")
		)
		(fp_poly
			(pts
				(xy -1.778 2.54) (xy 1.778 2.54) (xy 1.778 -2.54) (xy -1.778 -2.54)
			)
			(stroke
				(width 0)
				(type default)
			)
			(fill no)
			(layer "F.CrtYd")
		)
		(fp_poly
			(pts
				(xy -1.778 -2.54) (xy 1.778 -2.54) (xy 1.778 2.54) (xy -1.778 2.54)
			)
			(stroke
				(width 0)
				(type default)
			)
			(fill no)
			(layer "F.Fab")
		)
		(pad "1" smd rect
			(at -0.97536 1.6256 270)
			(size 0.3556 1.524)
			(layers "F.Cu" "F.Mask" "F.Paste")
			(net "GND")
		)
		(pad "2" smd rect
			(at -0.32512 1.6256 270)
			(size 0.3556 1.524)
			(layers "F.Cu" "F.Mask" "F.Paste")
			(net "P3V3_STBY_B")
		)
		(pad "3" smd rect
			(at 0.32512 1.6256 270)
			(size 0.3556 1.524)
			(layers "F.Cu" "F.Mask" "F.Paste")
			(net "I2C_DEBUG_B_SCL")
		)
		(pad "4" smd rect
			(at 0.97536 1.6256 270)
			(size 0.3556 1.524)
			(layers "F.Cu" "F.Mask" "F.Paste")
			(net "I2C_DEBUG_B_SDA")
		)
		(pad "5" smd rect
			(at 0.97536 -1.6256 270)
			(size 0.3556 1.524)
			(layers "F.Cu" "F.Mask" "F.Paste")
			(net "I2C_DEBUG_B_SDA_L")
		)
		(pad "6" smd rect
			(at 0.32512 -1.6256 270)
			(size 0.3556 1.524)
			(layers "F.Cu" "F.Mask" "F.Paste")
			(net "I2C_DEBUG_B_SCL_L")
		)
		(pad "7" smd rect
			(at -0.32512 -1.6256 270)
			(size 0.3556 1.524)
			(layers "F.Cu" "F.Mask" "F.Paste")
			(net "P3V3_STBY_B")
		)
		(pad "8" smd rect
			(at -0.97536 -1.6256 270)
			(size 0.3556 1.524)
			(layers "F.Cu" "F.Mask" "F.Paste")
			(net "DEBUG_CARD_B_PRSNT")
		)
	)
	(footprint ""
		(layer "F.Cu")
		(at 53.3146 -44.2976)
		(property "Reference" "R39"
			(at 0 0 0)
			(layer "F.SilkS")
			(hide yes)
			(effects
				(font
					(size 1.27 1.27)
				)
			)
		)
		(property "Value" "0R2J-2-GP"
			(at 0.064008 -4.679696 0)
			(unlocked yes)
			(layer "F.Fab")
			(hide yes)
			(effects
				(font
					(size 2.54 2.54)
					(thickness 0.381)
				)
			)
		)
		(property "Device Type" "R402H16"
			(at 0.064008 -6.203696 0)
			(unlocked yes)
			(layer "F.Fab")
			(hide yes)
			(effects
				(font
					(size 2.54 2.54)
					(thickness 0.381)
				)
			)
		)
		(duplicate_pad_numbers_are_jumpers no)
		(fp_line
			(start -0.508 -0.9398)
			(end -0.508 0.9398)
			(stroke
				(width 0.1524)
				(type default)
			)
			(layer "F.SilkS")
		)
		(fp_line
			(start 0.508 -0.9398)
			(end -0.508 -0.9398)
			(stroke
				(width 0.1524)
				(type default)
			)
			(layer "F.SilkS")
		)
		(fp_rect
			(start -0.508 0.9398)
			(end 0.508 -0.9398)
			(stroke
				(width 0)
				(type default)
			)
			(fill no)
			(layer "F.CrtYd")
		)
		(fp_rect
			(start -0.508 0.9398)
			(end 0.508 -0.9398)
			(stroke
				(width 0)
				(type default)
			)
			(fill no)
			(layer "F.Fab")
		)
		(pad "1" smd custom
			(at 0 -0.4445)
			(size 0.1397 0.1397)
			(layers "F.Cu" "F.Mask" "F.Paste")
			(net "TEMP_2_SDA")
			(options
				(clearance outline)
				(anchor circle)
			)
			(primitives
				(gr_poly
					(pts
						(arc
							(start -0.1778 -0.2794)
							(mid -0.249642 -0.249642)
							(end -0.2794 -0.1778)
						)
						(arc
							(start -0.2794 0.1778)
							(mid -0.249642 0.249642)
							(end -0.1778 0.2794)
						)
						(arc
							(start 0.1778 0.2794)
							(mid 0.249642 0.249642)
							(end 0.2794 0.1778)
						)
						(arc
							(start 0.2794 -0.1778)
							(mid 0.249642 -0.249642)
							(end 0.1778 -0.2794)
						)
					)
					(width 0)
					(fill yes)
				)
			)
		)
		(pad "2" smd custom
			(at 0 0.4445)
			(size 0.1397 0.1397)
			(layers "F.Cu" "F.Mask" "F.Paste")
			(net "I2C_DPB_B_SDA")
			(options
				(clearance outline)
				(anchor circle)
			)
			(primitives
				(gr_poly
					(pts
						(arc
							(start -0.1778 -0.2794)
							(mid -0.249642 -0.249642)
							(end -0.2794 -0.1778)
						)
						(arc
							(start -0.2794 0.1778)
							(mid -0.249642 0.249642)
							(end -0.1778 0.2794)
						)
						(arc
							(start 0.1778 0.2794)
							(mid 0.249642 0.249642)
							(end 0.2794 0.1778)
						)
						(arc
							(start 0.2794 -0.1778)
							(mid 0.249642 -0.249642)
							(end 0.1778 -0.2794)
						)
					)
					(width 0)
					(fill yes)
				)
			)
		)
	)
	(footprint ""
		(layer "F.Cu")
		(at 55.2196 -47.0662 -90)
		(property "Reference" "R42"
			(at 0 0 270)
			(layer "F.SilkS")
			(hide yes)
			(effects
				(font
					(size 1.27 1.27)
				)
			)
		)
		(property "Value" "4K7R2F-GP"
			(at 0.064008 -4.679696 270)
			(unlocked yes)
			(layer "F.Fab")
			(hide yes)
			(effects
				(font
					(size 2.54 2.54)
					(thickness 0.381)
				)
			)
		)
		(property "Device Type" "R402H16"
			(at 0.064008 -6.203696 270)
			(unlocked yes)
			(layer "F.Fab")
			(hide yes)
			(effects
				(font
					(size 2.54 2.54)
					(thickness 0.381)
				)
			)
		)
		(duplicate_pad_numbers_are_jumpers no)
		(fp_line
			(start -0.508 -0.9398)
			(end -0.508 0.9398)
			(stroke
				(width 0.1524)
				(type default)
			)
			(layer "F.SilkS")
		)
		(fp_line
			(start 0.508 -0.9398)
			(end -0.508 -0.9398)
			(stroke
				(width 0.1524)
				(type default)
			)
			(layer "F.SilkS")
		)
		(fp_rect
			(start -0.508 0.9398)
			(end 0.508 -0.9398)
			(stroke
				(width 0)
				(type default)
			)
			(fill no)
			(layer "F.CrtYd")
		)
		(fp_rect
			(start -0.508 0.9398)
			(end 0.508 -0.9398)
			(stroke
				(width 0)
				(type default)
			)
			(fill no)
			(layer "F.Fab")
		)
		(pad "1" smd custom
			(at 0 -0.4445 270)
			(size 0.1397 0.1397)
			(layers "F.Cu" "F.Mask" "F.Paste")
			(net "P3V3_STBY_B")
			(options
				(clearance outline)
				(anchor circle)
			)
			(primitives
				(gr_poly
					(pts
						(arc
							(start -0.1778 -0.2794)
							(mid -0.249642 -0.249642)
							(end -0.2794 -0.1778)
						)
						(arc
							(start -0.2794 0.1778)
							(mid -0.249642 0.249642)
							(end -0.1778 0.2794)
						)
						(arc
							(start 0.1778 0.2794)
							(mid 0.249642 0.249642)
							(end 0.2794 0.1778)
						)
						(arc
							(start 0.2794 -0.1778)
							(mid 0.249642 -0.249642)
							(end 0.1778 -0.2794)
						)
					)
					(width 0)
					(fill yes)
				)
			)
		)
		(pad "2" smd custom
			(at 0 0.4445 270)
			(size 0.1397 0.1397)
			(layers "F.Cu" "F.Mask" "F.Paste")
			(net "TEMP_2_A2")
			(options
				(clearance outline)
				(anchor circle)
			)
			(primitives
				(gr_poly
					(pts
						(arc
							(start -0.1778 -0.2794)
							(mid -0.249642 -0.249642)
							(end -0.2794 -0.1778)
						)
						(arc
							(start -0.2794 0.1778)
							(mid -0.249642 0.249642)
							(end -0.1778 0.2794)
						)
						(arc
							(start 0.1778 0.2794)
							(mid 0.249642 0.249642)
							(end 0.2794 0.1778)
						)
						(arc
							(start 0.2794 -0.1778)
							(mid 0.249642 -0.249642)
							(end 0.1778 -0.2794)
						)
					)
					(width 0)
					(fill yes)
				)
			)
		)
	)
	(footprint ""
		(layer "F.Cu")
		(at 46.36008 -70.226174 90)
		(property "Reference" "L3"
			(at 0 0 90)
			(layer "F.SilkS")
			(hide yes)
			(effects
				(font
					(size 1.27 1.27)
				)
			)
		)
		(property "Value" "BLM21PG300SN-2GP"
			(at 0.0254 -6.3754 90)
			(unlocked yes)
			(layer "F.Fab")
			(hide yes)
			(effects
				(font
					(size 2.54 2.54)
					(thickness 0.381)
				)
			)
		)
		(property "Device Type" "L20125H42"
			(at 0.0254 -8.2804 90)
			(unlocked yes)
			(layer "F.Fab")
			(hide yes)
			(effects
				(font
					(size 2.54 2.54)
					(thickness 0.381)
				)
			)
		)
		(duplicate_pad_numbers_are_jumpers no)
		(fp_line
			(start 0.9144 -1.7018)
			(end -0.9144 -1.7018)
			(stroke
				(width 0.1524)
				(type default)
			)
			(layer "F.SilkS")
		)
		(fp_line
			(start -0.9144 -1.7018)
			(end -0.9144 1.7018)
			(stroke
				(width 0.1524)
				(type default)
			)
			(layer "F.SilkS")
		)
		(fp_line
			(start 0.9144 1.7018)
			(end 0.9144 -1.7018)
			(stroke
				(width 0.1524)
				(type default)
			)
			(layer "F.SilkS")
		)
		(fp_line
			(start -0.9144 1.7018)
			(end 0.9144 1.7018)
			(stroke
				(width 0.1524)
				(type default)
			)
			(layer "F.SilkS")
		)
		(fp_rect
			(start -1.0033 1.778)
			(end 1.0033 -1.778)
			(stroke
				(width 0)
				(type default)
			)
			(fill no)
			(layer "F.CrtYd")
		)
		(fp_poly
			(pts
				(xy -1.0033 -1.778) (xy 1.0033 -1.778) (xy 1.0033 1.778) (xy -1.0033 1.778)
			)
			(stroke
				(width 0)
				(type default)
			)
			(fill no)
			(layer "F.Fab")
		)
		(pad "1" smd rect
			(at 0 -0.9652 90)
			(size 1.397 1.143)
			(layers "F.Cu" "F.Mask" "F.Paste")
			(net "P5V_VBUS_B")
		)
		(pad "2" smd rect
			(at 0 0.9652 90)
			(size 1.397 1.143)
			(layers "F.Cu" "F.Mask" "F.Paste")
			(net "P5V_USB_B")
		)
	)
	(footprint ""
		(layer "F.Cu")
		(at 7.690866 -28.004008 90)
		(property "Reference" "U5"
			(at 0 0 90)
			(layer "F.SilkS")
			(hide yes)
			(effects
				(font
					(size 1.27 1.27)
				)
			)
		)
		(property "Value" "TPS3422EGDRYR-GP"
			(at -0.1016 -5.4229 90)
			(unlocked yes)
			(layer "F.Fab")
			(hide yes)
			(effects
				(font
					(size 1.016 1.016)
					(thickness 0.1524)
				)
			)
		)
		(property "Device Type" "XSON6H24"
			(at -0.1016 -6.9469 90)
			(unlocked yes)
			(layer "F.Fab")
			(hide yes)
			(effects
				(font
					(size 1.016 1.016)
					(thickness 0.1524)
				)
			)
		)
		(duplicate_pad_numbers_are_jumpers no)
		(fp_line
			(start -0.7239 -0.762)
			(end -0.7239 -0.9398)
			(stroke
				(width 0.1524)
				(type default)
			)
			(layer "F.SilkS")
		)
		(fp_line
			(start -0.9779 -0.508)
			(end -0.7239 -0.762)
			(stroke
				(width 0.1524)
				(type default)
			)
			(layer "F.SilkS")
		)
		(fp_line
			(start -1.1557 -0.508)
			(end -0.9779 -0.508)
			(stroke
				(width 0.1524)
				(type default)
			)
			(layer "F.SilkS")
		)
		(fp_line
			(start 0.9779 0.508)
			(end 1.1557 0.508)
			(stroke
				(width 0.1524)
				(type default)
			)
			(layer "F.SilkS")
		)
		(fp_line
			(start -0.9779 0.508)
			(end -0.7239 0.762)
			(stroke
				(width 0.1524)
				(type default)
			)
			(layer "F.SilkS")
		)
		(fp_line
			(start -1.1557 0.508)
			(end -0.9779 0.508)
			(stroke
				(width 0.1524)
				(type default)
			)
			(layer "F.SilkS")
		)
		(fp_line
			(start 0.7239 0.762)
			(end 0.9779 0.508)
			(stroke
				(width 0.1524)
				(type default)
			)
			(layer "F.SilkS")
		)
		(fp_line
			(start -0.7239 0.762)
			(end -0.7239 0.9398)
			(stroke
				(width 0.1524)
				(type default)
			)
			(layer "F.SilkS")
		)
		(fp_line
			(start 0.7239 0.9398)
			(end 0.7239 0.762)
			(stroke
				(width 0.1524)
				(type default)
			)
			(layer "F.SilkS")
		)
		(fp_poly
			(pts
				(xy 0.846328 -0.607314) (xy 0.846328 -1.016) (xy 1.2319 -0.607314)
			)
			(stroke
				(width 0)
				(type default)
			)
			(fill yes)
			(layer "F.SilkS")
		)
		(fp_rect
			(start -0.7239 0.508)
			(end 0.7239 -0.508)
			(stroke
				(width 0)
				(type default)
			)
			(fill no)
			(layer "F.CrtYd")
		)
		(fp_poly
			(pts
				(xy -1.2319 1.016) (xy -1.2319 -1.016) (xy 1.2319 -1.016) (xy 1.2319 -0.0889) (xy 0.7239 -0.0889)
				(xy 0.7239 -0.508) (xy -0.7239 -0.508) (xy -0.7239 0.508) (xy 0.7239 0.508) (xy 0.7239 -0.0762)
				(xy 1.2319 -0.0762) (xy 1.2319 1.016)
			)
			(stroke
				(width 0)
				(type default)
			)
			(fill no)
			(layer "F.CrtYd")
		)
		(fp_rect
			(start -1.2319 1.016)
			(end 1.2319 -1.016)
			(stroke
				(width 0)
				(type default)
			)
			(fill no)
			(layer "F.Fab")
		)
		(pad "1" smd rect
			(at 0.50038 -0.310134 90)
			(size 0.3048 0.381)
			(layers "F.Cu" "F.Mask" "F.Paste")
			(net "SYS_RESET_BTN_A_N_R")
		)
		(pad "2" smd rect
			(at 0 -0.310134 90)
			(size 0.3048 0.381)
			(layers "F.Cu" "F.Mask" "F.Paste")
			(net "GND")
		)
		(pad "3" smd rect
			(at -0.50038 -0.310134 90)
			(size 0.3048 0.381)
			(layers "F.Cu" "F.Mask" "F.Paste")
			(net "SYS_RESET_BTN_A")
		)
		(pad "4" smd rect
			(at -0.50038 0.310134 90)
			(size 0.3048 0.381)
			(layers "F.Cu" "F.Mask" "F.Paste")
			(net "P3V3_STBY_A")
		)
		(pad "5" smd rect
			(at 0 0.310134 90)
			(size 0.3048 0.381)
			(layers "F.Cu" "F.Mask" "F.Paste")
			(net "RST_A_TS")
		)
		(pad "6" smd rect
			(at 0.50038 0.310134 90)
			(size 0.3048 0.381)
			(layers "F.Cu" "F.Mask" "F.Paste")
			(net "GND")
		)
	)
	(footprint ""
		(layer "F.Cu")
		(at 56.6928 -49.4284 180)
		(property "Reference" "R36"
			(at 0 0 180)
			(layer "F.SilkS")
			(hide yes)
			(effects
				(font
					(size 1.27 1.27)
				)
			)
		)
		(property "Value" "4K7R2F-GP"
			(at 0.064008 -4.679696 180)
			(unlocked yes)
			(layer "F.Fab")
			(hide yes)
			(effects
				(font
					(size 2.54 2.54)
					(thickness 0.381)
				)
			)
		)
		(property "Device Type" "R402H16"
			(at 0.064008 -6.203696 180)
			(unlocked yes)
			(layer "F.Fab")
			(hide yes)
			(effects
				(font
					(size 2.54 2.54)
					(thickness 0.381)
				)
			)
		)
		(duplicate_pad_numbers_are_jumpers no)
		(fp_line
			(start 0.508 -0.9398)
			(end -0.508 -0.9398)
			(stroke
				(width 0.1524)
				(type default)
			)
			(layer "F.SilkS")
		)
		(fp_line
			(start -0.508 -0.9398)
			(end -0.508 0.9398)
			(stroke
				(width 0.1524)
				(type default)
			)
			(layer "F.SilkS")
		)
		(fp_rect
			(start -0.508 0.9398)
			(end 0.508 -0.9398)
			(stroke
				(width 0)
				(type default)
			)
			(fill no)
			(layer "F.CrtYd")
		)
		(fp_rect
			(start -0.508 0.9398)
			(end 0.508 -0.9398)
			(stroke
				(width 0)
				(type default)
			)
			(fill no)
			(layer "F.Fab")
		)
		(pad "1" smd custom
			(at 0 -0.4445 180)
			(size 0.1397 0.1397)
			(layers "F.Cu" "F.Mask" "F.Paste")
			(net "TEMP_2_A1")
			(options
				(clearance outline)
				(anchor circle)
			)
			(primitives
				(gr_poly
					(pts
						(arc
							(start -0.1778 -0.2794)
							(mid -0.249642 -0.249642)
							(end -0.2794 -0.1778)
						)
						(arc
							(start -0.2794 0.1778)
							(mid -0.249642 0.249642)
							(end -0.1778 0.2794)
						)
						(arc
							(start 0.1778 0.2794)
							(mid 0.249642 0.249642)
							(end 0.2794 0.1778)
						)
						(arc
							(start 0.2794 -0.1778)
							(mid 0.249642 -0.249642)
							(end 0.1778 -0.2794)
						)
					)
					(width 0)
					(fill yes)
				)
			)
		)
		(pad "2" smd custom
			(at 0 0.4445 180)
			(size 0.1397 0.1397)
			(layers "F.Cu" "F.Mask" "F.Paste")
			(net "GND")
			(options
				(clearance outline)
				(anchor circle)
			)
			(primitives
				(gr_poly
					(pts
						(arc
							(start -0.1778 -0.2794)
							(mid -0.249642 -0.249642)
							(end -0.2794 -0.1778)
						)
						(arc
							(start -0.2794 0.1778)
							(mid -0.249642 0.249642)
							(end -0.1778 0.2794)
						)
						(arc
							(start 0.1778 0.2794)
							(mid 0.249642 0.249642)
							(end 0.2794 0.1778)
						)
						(arc
							(start 0.2794 -0.1778)
							(mid 0.249642 -0.249642)
							(end 0.1778 -0.2794)
						)
					)
					(width 0)
					(fill yes)
				)
			)
		)
	)
	(footprint ""
		(layer "F.Cu")
		(at 54.818534 -56.91632)
		(property "Reference" "D2"
			(at 0 0 0)
			(layer "F.SilkS")
			(hide yes)
			(effects
				(font
					(size 1.27 1.27)
				)
			)
		)
		(property "Value" "PESD3V3L4UW-GP"
			(at 2.2606 1.27 0)
			(unlocked yes)
			(layer "F.Fab")
			(hide yes)
			(effects
				(font
					(size 1.016 1.016)
					(thickness 0.1524)
				)
			)
		)
		(property "Device Type" "SOT-23-5-3H24"
			(at 2.2606 -0.254 0)
			(unlocked yes)
			(layer "F.Fab")
			(hide yes)
			(effects
				(font
					(size 1.016 1.016)
					(thickness 0.1524)
				)
			)
		)
		(duplicate_pad_numbers_are_jumpers no)
		(fp_line
			(start -1.143 0.254)
			(end -1.143 1.524)
			(stroke
				(width 0.3302)
				(type default)
			)
			(layer "F.SilkS")
		)
		(fp_line
			(start -1.143 1.524)
			(end 0.127 1.524)
			(stroke
				(width 0.3302)
				(type default)
			)
			(layer "F.SilkS")
		)
		(fp_line
			(start -1.0541 -1.4351)
			(end -1.0541 1.4351)
			(stroke
				(width 0.1524)
				(type default)
			)
			(layer "F.SilkS")
		)
		(fp_line
			(start -1.0541 1.4351)
			(end 1.0541 1.4351)
			(stroke
				(width 0.1524)
				(type default)
			)
			(layer "F.SilkS")
		)
		(fp_line
			(start 1.0541 -1.4351)
			(end -1.0541 -1.4351)
			(stroke
				(width 0.1524)
				(type default)
			)
			(layer "F.SilkS")
		)
		(fp_line
			(start 1.0541 1.4351)
			(end 1.0541 -1.4351)
			(stroke
				(width 0.1524)
				(type default)
			)
			(layer "F.SilkS")
		)
		(fp_poly
			(pts
				(xy -0.508 1.5113) (xy -0.0762 1.9431) (xy -0.9398 1.9431)
			)
			(stroke
				(width 0)
				(type default)
			)
			(fill yes)
			(layer "F.SilkS")
		)
		(fp_rect
			(start -1.3081 1.6891)
			(end 1.3081 -1.6891)
			(stroke
				(width 0)
				(type default)
			)
			(fill no)
			(layer "F.CrtYd")
		)
		(fp_rect
			(start -1.3081 1.6891)
			(end 1.3081 -1.6891)
			(stroke
				(width 0)
				(type default)
			)
			(fill no)
			(layer "F.Fab")
		)
		(pad "1" smd rect
			(at -0.500126 0.7239)
			(size 0.3048 0.9144)
			(layers "F.Cu" "F.Mask" "F.Paste")
			(net "I2C_DEBUG_B_SDA")
		)
		(pad "2" smd rect
			(at 0 0.7239)
			(size 0.3048 0.9144)
			(layers "F.Cu" "F.Mask" "F.Paste")
			(net "GND")
		)
		(pad "3" smd rect
			(at 0.500126 0.7239)
			(size 0.3048 0.9144)
			(layers "F.Cu" "F.Mask" "F.Paste")
			(net "UART_DEBUG_B_RX")
		)
		(pad "4" smd rect
			(at 0.500126 -0.7239)
			(size 0.3048 0.9144)
			(layers "F.Cu" "F.Mask" "F.Paste")
			(net "UART_DEBUG_B_TX")
		)
		(pad "5" smd rect
			(at -0.500126 -0.7239)
			(size 0.3048 0.9144)
			(layers "F.Cu" "F.Mask" "F.Paste")
			(net "I2C_DEBUG_B_SCL")
		)
	)
	(footprint ""
		(layer "F.Cu")
		(at 9.7536 -14.9352 -90)
		(property "Reference" "C5"
			(at 0 0 270)
			(layer "F.SilkS")
			(hide yes)
			(effects
				(font
					(size 1.27 1.27)
				)
			)
		)
		(property "Value" "SCD1U16V2KX-3GP"
			(at 1.1811 -3.3909 270)
			(unlocked yes)
			(layer "F.Fab")
			(hide yes)
			(effects
				(font
					(size 2.54 2.54)
					(thickness 0.381)
				)
			)
		)
		(property "Device Type" "C402H22"
			(at 1.1811 -4.9149 270)
			(unlocked yes)
			(layer "F.Fab")
			(hide yes)
			(effects
				(font
					(size 2.54 2.54)
					(thickness 0.381)
				)
			)
		)
		(duplicate_pad_numbers_are_jumpers no)
		(fp_rect
			(start -0.4318 0.9525)
			(end 0.4318 -0.9525)
			(stroke
				(width 0)
				(type default)
			)
			(fill no)
			(layer "F.CrtYd")
		)
		(fp_rect
			(start -0.4318 0.9525)
			(end 0.4318 -0.9525)
			(stroke
				(width 0)
				(type default)
			)
			(fill no)
			(layer "F.Fab")
		)
		(pad "1" smd custom
			(at 0 -0.4445 270)
			(size 0.1524 0.1524)
			(layers "F.Cu" "F.Mask" "F.Paste")
			(net "P3V3_STBY_A")
			(options
				(clearance outline)
				(anchor circle)
			)
			(primitives
				(gr_poly
					(pts
						(arc
							(start 0.3048 -0.2032)
							(mid 0.275042 -0.275042)
							(end 0.2032 -0.3048)
						)
						(arc
							(start -0.2032 -0.3048)
							(mid -0.275042 -0.275042)
							(end -0.3048 -0.2032)
						)
						(arc
							(start -0.3048 0.2032)
							(mid -0.275042 0.275042)
							(end -0.2032 0.3048)
						)
						(arc
							(start 0.2032 0.3048)
							(mid 0.275042 0.275042)
							(end 0.3048 0.2032)
						)
					)
					(width 0)
					(fill yes)
				)
			)
		)
		(pad "2" smd custom
			(at 0 0.4445 270)
			(size 0.1524 0.1524)
			(layers "F.Cu" "F.Mask" "F.Paste")
			(net "GND")
			(options
				(clearance outline)
				(anchor circle)
			)
			(primitives
				(gr_poly
					(pts
						(arc
							(start 0.3048 -0.2032)
							(mid 0.275042 -0.275042)
							(end 0.2032 -0.3048)
						)
						(arc
							(start -0.2032 -0.3048)
							(mid -0.275042 -0.275042)
							(end -0.3048 -0.2032)
						)
						(arc
							(start -0.3048 0.2032)
							(mid -0.275042 0.275042)
							(end -0.2032 0.3048)
						)
						(arc
							(start 0.2032 0.3048)
							(mid 0.275042 0.275042)
							(end 0.3048 0.2032)
						)
					)
					(width 0)
					(fill yes)
				)
			)
		)
	)
	(footprint ""
		(layer "F.Cu")
		(at 11.811 -49.68494 90)
		(property "Reference" "R32"
			(at 0 0 90)
			(layer "F.SilkS")
			(hide yes)
			(effects
				(font
					(size 1.27 1.27)
				)
			)
		)
		(property "Value" "4K7R2F-GP"
			(at 0.064008 -4.679696 90)
			(unlocked yes)
			(layer "F.Fab")
			(hide yes)
			(effects
				(font
					(size 2.54 2.54)
					(thickness 0.381)
				)
			)
		)
		(property "Device Type" "R402H16"
			(at 0.064008 -6.203696 90)
			(unlocked yes)
			(layer "F.Fab")
			(hide yes)
			(effects
				(font
					(size 2.54 2.54)
					(thickness 0.381)
				)
			)
		)
		(duplicate_pad_numbers_are_jumpers no)
		(fp_line
			(start 0.508 -0.9398)
			(end -0.508 -0.9398)
			(stroke
				(width 0.1524)
				(type default)
			)
			(layer "F.SilkS")
		)
		(fp_line
			(start -0.508 -0.9398)
			(end -0.508 0.9398)
			(stroke
				(width 0.1524)
				(type default)
			)
			(layer "F.SilkS")
		)
		(fp_rect
			(start -0.508 0.9398)
			(end 0.508 -0.9398)
			(stroke
				(width 0)
				(type default)
			)
			(fill no)
			(layer "F.CrtYd")
		)
		(fp_rect
			(start -0.508 0.9398)
			(end 0.508 -0.9398)
			(stroke
				(width 0)
				(type default)
			)
			(fill no)
			(layer "F.Fab")
		)
		(pad "1" smd custom
			(at 0 -0.4445 90)
			(size 0.1397 0.1397)
			(layers "F.Cu" "F.Mask" "F.Paste")
			(net "TEMP_1_A0")
			(options
				(clearance outline)
				(anchor circle)
			)
			(primitives
				(gr_poly
					(pts
						(arc
							(start -0.1778 -0.2794)
							(mid -0.249642 -0.249642)
							(end -0.2794 -0.1778)
						)
						(arc
							(start -0.2794 0.1778)
							(mid -0.249642 0.249642)
							(end -0.1778 0.2794)
						)
						(arc
							(start 0.1778 0.2794)
							(mid 0.249642 0.249642)
							(end 0.2794 0.1778)
						)
						(arc
							(start 0.2794 -0.1778)
							(mid 0.249642 -0.249642)
							(end 0.1778 -0.2794)
						)
					)
					(width 0)
					(fill yes)
				)
			)
		)
		(pad "2" smd custom
			(at 0 0.4445 90)
			(size 0.1397 0.1397)
			(layers "F.Cu" "F.Mask" "F.Paste")
			(net "GND")
			(options
				(clearance outline)
				(anchor circle)
			)
			(primitives
				(gr_poly
					(pts
						(arc
							(start -0.1778 -0.2794)
							(mid -0.249642 -0.249642)
							(end -0.2794 -0.1778)
						)
						(arc
							(start -0.2794 0.1778)
							(mid -0.249642 0.249642)
							(end -0.1778 0.2794)
						)
						(arc
							(start 0.1778 0.2794)
							(mid 0.249642 0.249642)
							(end 0.2794 0.1778)
						)
						(arc
							(start 0.2794 -0.1778)
							(mid 0.249642 -0.249642)
							(end 0.1778 -0.2794)
						)
					)
					(width 0)
					(fill yes)
				)
			)
		)
	)
	(footprint ""
		(layer "F.Cu")
		(at 19.431 -13.4366)
		(property "Reference" "R1"
			(at 0 0 0)
			(layer "F.SilkS")
			(hide yes)
			(effects
				(font
					(size 1.27 1.27)
				)
			)
		)
		(property "Value" "10KR2F-2-GP"
			(at 0.064008 -4.679696 0)
			(unlocked yes)
			(layer "F.Fab")
			(hide yes)
			(effects
				(font
					(size 2.54 2.54)
					(thickness 0.381)
				)
			)
		)
		(property "Device Type" "R402H16"
			(at 0.064008 -6.203696 0)
			(unlocked yes)
			(layer "F.Fab")
			(hide yes)
			(effects
				(font
					(size 2.54 2.54)
					(thickness 0.381)
				)
			)
		)
		(duplicate_pad_numbers_are_jumpers no)
		(fp_line
			(start -0.508 -0.9398)
			(end -0.508 0.9398)
			(stroke
				(width 0.1524)
				(type default)
			)
			(layer "F.SilkS")
		)
		(fp_line
			(start 0.508 -0.9398)
			(end -0.508 -0.9398)
			(stroke
				(width 0.1524)
				(type default)
			)
			(layer "F.SilkS")
		)
		(fp_rect
			(start -0.508 0.9398)
			(end 0.508 -0.9398)
			(stroke
				(width 0)
				(type default)
			)
			(fill no)
			(layer "F.CrtYd")
		)
		(fp_rect
			(start -0.508 0.9398)
			(end 0.508 -0.9398)
			(stroke
				(width 0)
				(type default)
			)
			(fill no)
			(layer "F.Fab")
		)
		(pad "1" smd custom
			(at 0 -0.4445)
			(size 0.1397 0.1397)
			(layers "F.Cu" "F.Mask" "F.Paste")
			(net "P3V3_STBY_A")
			(options
				(clearance outline)
				(anchor circle)
			)
			(primitives
				(gr_poly
					(pts
						(arc
							(start -0.1778 -0.2794)
							(mid -0.249642 -0.249642)
							(end -0.2794 -0.1778)
						)
						(arc
							(start -0.2794 0.1778)
							(mid -0.249642 0.249642)
							(end -0.1778 0.2794)
						)
						(arc
							(start 0.1778 0.2794)
							(mid 0.249642 0.249642)
							(end 0.2794 0.1778)
						)
						(arc
							(start 0.2794 -0.1778)
							(mid 0.249642 -0.249642)
							(end 0.1778 -0.2794)
						)
					)
					(width 0)
					(fill yes)
				)
			)
		)
		(pad "2" smd custom
			(at 0 0.4445)
			(size 0.1397 0.1397)
			(layers "F.Cu" "F.Mask" "F.Paste")
			(net "UART_SEL_A_MUX_R")
			(options
				(clearance outline)
				(anchor circle)
			)
			(primitives
				(gr_poly
					(pts
						(arc
							(start -0.1778 -0.2794)
							(mid -0.249642 -0.249642)
							(end -0.2794 -0.1778)
						)
						(arc
							(start -0.2794 0.1778)
							(mid -0.249642 0.249642)
							(end -0.1778 0.2794)
						)
						(arc
							(start 0.1778 0.2794)
							(mid 0.249642 0.249642)
							(end 0.2794 0.1778)
						)
						(arc
							(start 0.2794 -0.1778)
							(mid 0.249642 -0.249642)
							(end 0.1778 -0.2794)
						)
					)
					(width 0)
					(fill yes)
				)
			)
		)
	)
	(footprint ""
		(layer "F.Cu")
		(at 14.097 -30.0482 90)
		(property "Reference" "C27"
			(at 0 0 90)
			(layer "F.SilkS")
			(hide yes)
			(effects
				(font
					(size 1.27 1.27)
				)
			)
		)
		(property "Value" "SCD1U16V2KX-3GP"
			(at 1.1811 -2.7051 90)
			(unlocked yes)
			(layer "F.Fab")
			(hide yes)
			(effects
				(font
					(size 1.016 1.016)
					(thickness 0.1524)
				)
			)
		)
		(property "Device Type" "C402H22"
			(at 1.1811 -4.2291 90)
			(unlocked yes)
			(layer "F.Fab")
			(hide yes)
			(effects
				(font
					(size 1.016 1.016)
					(thickness 0.1524)
				)
			)
		)
		(duplicate_pad_numbers_are_jumpers no)
		(fp_rect
			(start -0.4318 0.9525)
			(end 0.4318 -0.9525)
			(stroke
				(width 0)
				(type default)
			)
			(fill no)
			(layer "F.CrtYd")
		)
		(fp_rect
			(start -0.4318 0.9525)
			(end 0.4318 -0.9525)
			(stroke
				(width 0)
				(type default)
			)
			(fill no)
			(layer "F.Fab")
		)
		(pad "1" smd custom
			(at 0 -0.4445 90)
			(size 0.1524 0.1524)
			(layers "F.Cu" "F.Mask" "F.Paste")
			(net "P3V3_STBY_A")
			(options
				(clearance outline)
				(anchor circle)
			)
			(primitives
				(gr_poly
					(pts
						(arc
							(start 0.3048 -0.2032)
							(mid 0.275042 -0.275042)
							(end 0.2032 -0.3048)
						)
						(arc
							(start -0.2032 -0.3048)
							(mid -0.275042 -0.275042)
							(end -0.3048 -0.2032)
						)
						(arc
							(start -0.3048 0.2032)
							(mid -0.275042 0.275042)
							(end -0.2032 0.3048)
						)
						(arc
							(start 0.2032 0.3048)
							(mid 0.275042 0.275042)
							(end 0.3048 0.2032)
						)
					)
					(width 0)
					(fill yes)
				)
			)
		)
		(pad "2" smd custom
			(at 0 0.4445 90)
			(size 0.1524 0.1524)
			(layers "F.Cu" "F.Mask" "F.Paste")
			(net "GND")
			(options
				(clearance outline)
				(anchor circle)
			)
			(primitives
				(gr_poly
					(pts
						(arc
							(start 0.3048 -0.2032)
							(mid 0.275042 -0.275042)
							(end 0.2032 -0.3048)
						)
						(arc
							(start -0.2032 -0.3048)
							(mid -0.275042 -0.275042)
							(end -0.3048 -0.2032)
						)
						(arc
							(start -0.3048 0.2032)
							(mid -0.275042 0.275042)
							(end -0.2032 0.3048)
						)
						(arc
							(start 0.2032 0.3048)
							(mid 0.275042 0.275042)
							(end 0.3048 0.2032)
						)
					)
					(width 0)
					(fill yes)
				)
			)
		)
	)
	(footprint ""
		(layer "F.Cu")
		(at 56.6928 -47.5107 180)
		(property "Reference" "R41"
			(at 0 0 180)
			(layer "F.SilkS")
			(hide yes)
			(effects
				(font
					(size 1.27 1.27)
				)
			)
		)
		(property "Value" "4K7R2F-GP"
			(at 0.064008 -4.679696 180)
			(unlocked yes)
			(layer "F.Fab")
			(hide yes)
			(effects
				(font
					(size 2.54 2.54)
					(thickness 0.381)
				)
			)
		)
		(property "Device Type" "R402H16"
			(at 0.064008 -6.203696 180)
			(unlocked yes)
			(layer "F.Fab")
			(hide yes)
			(effects
				(font
					(size 2.54 2.54)
					(thickness 0.381)
				)
			)
		)
		(duplicate_pad_numbers_are_jumpers no)
		(fp_line
			(start 0.508 -0.9398)
			(end -0.508 -0.9398)
			(stroke
				(width 0.1524)
				(type default)
			)
			(layer "F.SilkS")
		)
		(fp_line
			(start -0.508 -0.9398)
			(end -0.508 0.9398)
			(stroke
				(width 0.1524)
				(type default)
			)
			(layer "F.SilkS")
		)
		(fp_rect
			(start -0.508 0.9398)
			(end 0.508 -0.9398)
			(stroke
				(width 0)
				(type default)
			)
			(fill no)
			(layer "F.CrtYd")
		)
		(fp_rect
			(start -0.508 0.9398)
			(end 0.508 -0.9398)
			(stroke
				(width 0)
				(type default)
			)
			(fill no)
			(layer "F.Fab")
		)
		(pad "1" smd custom
			(at 0 -0.4445 180)
			(size 0.1397 0.1397)
			(layers "F.Cu" "F.Mask" "F.Paste")
			(net "P3V3_STBY_B")
			(options
				(clearance outline)
				(anchor circle)
			)
			(primitives
				(gr_poly
					(pts
						(arc
							(start -0.1778 -0.2794)
							(mid -0.249642 -0.249642)
							(end -0.2794 -0.1778)
						)
						(arc
							(start -0.2794 0.1778)
							(mid -0.249642 0.249642)
							(end -0.1778 0.2794)
						)
						(arc
							(start 0.1778 0.2794)
							(mid 0.249642 0.249642)
							(end 0.2794 0.1778)
						)
						(arc
							(start 0.2794 -0.1778)
							(mid 0.249642 -0.249642)
							(end 0.1778 -0.2794)
						)
					)
					(width 0)
					(fill yes)
				)
			)
		)
		(pad "2" smd custom
			(at 0 0.4445 180)
			(size 0.1397 0.1397)
			(layers "F.Cu" "F.Mask" "F.Paste")
			(net "TEMP_2_A1")
			(options
				(clearance outline)
				(anchor circle)
			)
			(primitives
				(gr_poly
					(pts
						(arc
							(start -0.1778 -0.2794)
							(mid -0.249642 -0.249642)
							(end -0.2794 -0.1778)
						)
						(arc
							(start -0.2794 0.1778)
							(mid -0.249642 0.249642)
							(end -0.1778 0.2794)
						)
						(arc
							(start 0.1778 0.2794)
							(mid 0.249642 0.249642)
							(end 0.2794 0.1778)
						)
						(arc
							(start 0.2794 -0.1778)
							(mid 0.249642 -0.249642)
							(end 0.1778 -0.2794)
						)
					)
					(width 0)
					(fill yes)
				)
			)
		)
	)
	(footprint ""
		(layer "F.Cu")
		(at 25.6286 -10.7696 180)
		(property "Reference" "C29"
			(at 0 0 180)
			(layer "F.SilkS")
			(hide yes)
			(effects
				(font
					(size 1.27 1.27)
				)
			)
		)
		(property "Value" "SCD1U16V2KX-3GP"
			(at 1.1811 -2.7051 180)
			(unlocked yes)
			(layer "F.Fab")
			(hide yes)
			(effects
				(font
					(size 1.016 1.016)
					(thickness 0.1524)
				)
			)
		)
		(property "Device Type" "C402H22"
			(at 1.1811 -4.2291 180)
			(unlocked yes)
			(layer "F.Fab")
			(hide yes)
			(effects
				(font
					(size 1.016 1.016)
					(thickness 0.1524)
				)
			)
		)
		(duplicate_pad_numbers_are_jumpers no)
		(fp_rect
			(start -0.4318 0.9525)
			(end 0.4318 -0.9525)
			(stroke
				(width 0)
				(type default)
			)
			(fill no)
			(layer "F.CrtYd")
		)
		(fp_rect
			(start -0.4318 0.9525)
			(end 0.4318 -0.9525)
			(stroke
				(width 0)
				(type default)
			)
			(fill no)
			(layer "F.Fab")
		)
		(pad "1" smd custom
			(at 0 -0.4445 180)
			(size 0.1524 0.1524)
			(layers "F.Cu" "F.Mask" "F.Paste")
			(net "P3V3_STBY_A")
			(options
				(clearance outline)
				(anchor circle)
			)
			(primitives
				(gr_poly
					(pts
						(arc
							(start 0.3048 -0.2032)
							(mid 0.275042 -0.275042)
							(end 0.2032 -0.3048)
						)
						(arc
							(start -0.2032 -0.3048)
							(mid -0.275042 -0.275042)
							(end -0.3048 -0.2032)
						)
						(arc
							(start -0.3048 0.2032)
							(mid -0.275042 0.275042)
							(end -0.2032 0.3048)
						)
						(arc
							(start 0.2032 0.3048)
							(mid 0.275042 0.275042)
							(end 0.3048 0.2032)
						)
					)
					(width 0)
					(fill yes)
				)
			)
		)
		(pad "2" smd custom
			(at 0 0.4445 180)
			(size 0.1524 0.1524)
			(layers "F.Cu" "F.Mask" "F.Paste")
			(net "GND")
			(options
				(clearance outline)
				(anchor circle)
			)
			(primitives
				(gr_poly
					(pts
						(arc
							(start 0.3048 -0.2032)
							(mid 0.275042 -0.275042)
							(end 0.2032 -0.3048)
						)
						(arc
							(start -0.2032 -0.3048)
							(mid -0.275042 -0.275042)
							(end -0.3048 -0.2032)
						)
						(arc
							(start -0.3048 0.2032)
							(mid -0.275042 0.275042)
							(end -0.2032 0.3048)
						)
						(arc
							(start 0.2032 0.3048)
							(mid 0.275042 0.275042)
							(end 0.3048 0.2032)
						)
					)
					(width 0)
					(fill yes)
				)
			)
		)
	)
	(footprint ""
		(layer "F.Cu")
		(at 7.1628 -30.3784)
		(property "Reference" "R49"
			(at 0 0 0)
			(layer "F.SilkS")
			(hide yes)
			(effects
				(font
					(size 1.27 1.27)
				)
			)
		)
		(property "Value" "1KR2F-3-GP"
			(at 0.064008 -4.679696 0)
			(unlocked yes)
			(layer "F.Fab")
			(hide yes)
			(effects
				(font
					(size 2.54 2.54)
					(thickness 0.381)
				)
			)
		)
		(property "Device Type" "R402H16"
			(at 0.064008 -6.203696 0)
			(unlocked yes)
			(layer "F.Fab")
			(hide yes)
			(effects
				(font
					(size 2.54 2.54)
					(thickness 0.381)
				)
			)
		)
		(duplicate_pad_numbers_are_jumpers no)
		(fp_line
			(start -0.508 -0.9398)
			(end -0.508 0.9398)
			(stroke
				(width 0.1524)
				(type default)
			)
			(layer "F.SilkS")
		)
		(fp_line
			(start 0.508 -0.9398)
			(end -0.508 -0.9398)
			(stroke
				(width 0.1524)
				(type default)
			)
			(layer "F.SilkS")
		)
		(fp_rect
			(start -0.508 0.9398)
			(end 0.508 -0.9398)
			(stroke
				(width 0)
				(type default)
			)
			(fill no)
			(layer "F.CrtYd")
		)
		(fp_rect
			(start -0.508 0.9398)
			(end 0.508 -0.9398)
			(stroke
				(width 0)
				(type default)
			)
			(fill no)
			(layer "F.Fab")
		)
		(pad "1" smd custom
			(at 0 -0.4445)
			(size 0.1397 0.1397)
			(layers "F.Cu" "F.Mask" "F.Paste")
			(net "P3V3_STBY_A")
			(options
				(clearance outline)
				(anchor circle)
			)
			(primitives
				(gr_poly
					(pts
						(arc
							(start -0.1778 -0.2794)
							(mid -0.249642 -0.249642)
							(end -0.2794 -0.1778)
						)
						(arc
							(start -0.2794 0.1778)
							(mid -0.249642 0.249642)
							(end -0.1778 0.2794)
						)
						(arc
							(start 0.1778 0.2794)
							(mid 0.249642 0.249642)
							(end 0.2794 0.1778)
						)
						(arc
							(start 0.2794 -0.1778)
							(mid 0.249642 -0.249642)
							(end 0.1778 -0.2794)
						)
					)
					(width 0)
					(fill yes)
				)
			)
		)
		(pad "2" smd custom
			(at 0 0.4445)
			(size 0.1397 0.1397)
			(layers "F.Cu" "F.Mask" "F.Paste")
			(net "SYS_RESET_BTN_A_N_R")
			(options
				(clearance outline)
				(anchor circle)
			)
			(primitives
				(gr_poly
					(pts
						(arc
							(start -0.1778 -0.2794)
							(mid -0.249642 -0.249642)
							(end -0.2794 -0.1778)
						)
						(arc
							(start -0.2794 0.1778)
							(mid -0.249642 0.249642)
							(end -0.1778 0.2794)
						)
						(arc
							(start 0.1778 0.2794)
							(mid 0.249642 0.249642)
							(end 0.2794 0.1778)
						)
						(arc
							(start 0.2794 -0.1778)
							(mid 0.249642 -0.249642)
							(end 0.1778 -0.2794)
						)
					)
					(width 0)
					(fill yes)
				)
			)
		)
	)
	(footprint ""
		(layer "F.Cu")
		(at 18.2372 -15.367 -90)
		(property "Reference" "R61"
			(at 0 0 270)
			(layer "F.SilkS")
			(hide yes)
			(effects
				(font
					(size 1.27 1.27)
				)
			)
		)
		(property "Value" "4K7R2F-GP"
			(at 0.064008 -3.993896 270)
			(unlocked yes)
			(layer "F.Fab")
			(hide yes)
			(effects
				(font
					(size 1.016 1.016)
					(thickness 0.1524)
				)
			)
		)
		(property "Device Type" "R402H16"
			(at 0.064008 -5.517896 270)
			(unlocked yes)
			(layer "F.Fab")
			(hide yes)
			(effects
				(font
					(size 1.016 1.016)
					(thickness 0.1524)
				)
			)
		)
		(duplicate_pad_numbers_are_jumpers no)
		(fp_line
			(start -0.508 -0.9398)
			(end -0.508 0.9398)
			(stroke
				(width 0.1524)
				(type default)
			)
			(layer "F.SilkS")
		)
		(fp_line
			(start 0.508 -0.9398)
			(end -0.508 -0.9398)
			(stroke
				(width 0.1524)
				(type default)
			)
			(layer "F.SilkS")
		)
		(fp_rect
			(start -0.508 0.9398)
			(end 0.508 -0.9398)
			(stroke
				(width 0)
				(type default)
			)
			(fill no)
			(layer "F.CrtYd")
		)
		(fp_rect
			(start -0.508 0.9398)
			(end 0.508 -0.9398)
			(stroke
				(width 0)
				(type default)
			)
			(fill no)
			(layer "F.Fab")
		)
		(pad "1" smd custom
			(at 0 -0.4445 270)
			(size 0.1397 0.1397)
			(layers "F.Cu" "F.Mask" "F.Paste")
			(net "P3V3_STBY_A")
			(options
				(clearance outline)
				(anchor circle)
			)
			(primitives
				(gr_poly
					(pts
						(arc
							(start -0.1778 -0.2794)
							(mid -0.249642 -0.249642)
							(end -0.2794 -0.1778)
						)
						(arc
							(start -0.2794 0.1778)
							(mid -0.249642 0.249642)
							(end -0.1778 0.2794)
						)
						(arc
							(start 0.1778 0.2794)
							(mid 0.249642 0.249642)
							(end 0.2794 0.1778)
						)
						(arc
							(start 0.2794 -0.1778)
							(mid 0.249642 -0.249642)
							(end 0.1778 -0.2794)
						)
					)
					(width 0)
					(fill yes)
				)
			)
		)
		(pad "2" smd custom
			(at 0 0.4445 270)
			(size 0.1397 0.1397)
			(layers "F.Cu" "F.Mask" "F.Paste")
			(net "IO_EXP_A_RESET#_FLT")
			(options
				(clearance outline)
				(anchor circle)
			)
			(primitives
				(gr_poly
					(pts
						(arc
							(start -0.1778 -0.2794)
							(mid -0.249642 -0.249642)
							(end -0.2794 -0.1778)
						)
						(arc
							(start -0.2794 0.1778)
							(mid -0.249642 0.249642)
							(end -0.1778 0.2794)
						)
						(arc
							(start 0.1778 0.2794)
							(mid 0.249642 0.249642)
							(end 0.2794 0.1778)
						)
						(arc
							(start 0.2794 -0.1778)
							(mid 0.249642 -0.249642)
							(end 0.1778 -0.2794)
						)
					)
					(width 0)
					(fill yes)
				)
			)
		)
	)
	(footprint ""
		(layer "F.Cu")
		(at 2.437638 -64.790066 -90)
		(property "Reference" "C2"
			(at 0 0 270)
			(layer "F.SilkS")
			(hide yes)
			(effects
				(font
					(size 1.27 1.27)
				)
			)
		)
		(property "Value" "SC1U16V3KX-5GP"
			(at 0 -3.5052 270)
			(unlocked yes)
			(layer "F.Fab")
			(hide yes)
			(effects
				(font
					(size 2.54 2.54)
					(thickness 0.381)
				)
			)
		)
		(property "Device Type" "C603H36"
			(at 0 -5.0292 270)
			(unlocked yes)
			(layer "F.Fab")
			(hide yes)
			(effects
				(font
					(size 2.54 2.54)
					(thickness 0.381)
				)
			)
		)
		(duplicate_pad_numbers_are_jumpers no)
		(fp_line
			(start 0.508 0)
			(end -0.508 0)
			(stroke
				(width 0.2032)
				(type default)
			)
			(layer "F.SilkS")
		)
		(fp_rect
			(start -0.5842 1.3335)
			(end 0.5842 -1.3335)
			(stroke
				(width 0)
				(type default)
			)
			(fill no)
			(layer "F.CrtYd")
		)
		(fp_rect
			(start -0.5842 1.3335)
			(end 0.5842 -1.3335)
			(stroke
				(width 0)
				(type default)
			)
			(fill no)
			(layer "F.Fab")
		)
		(pad "1" smd custom
			(at 0 -0.762 270)
			(size 0.2159 0.2159)
			(layers "F.Cu" "F.Mask" "F.Paste")
			(net "P5V_USB_A")
			(options
				(clearance outline)
				(anchor circle)
			)
			(primitives
				(gr_poly
					(pts
						(arc
							(start -0.3302 -0.4318)
							(mid -0.402042 -0.402042)
							(end -0.4318 -0.3302)
						)
						(arc
							(start -0.4318 0.3302)
							(mid -0.402042 0.402042)
							(end -0.3302 0.4318)
						)
						(arc
							(start 0.3302 0.4318)
							(mid 0.402042 0.402042)
							(end 0.4318 0.3302)
						)
						(arc
							(start 0.4318 -0.3302)
							(mid 0.402042 -0.402042)
							(end 0.3302 -0.4318)
						)
					)
					(width 0)
					(fill yes)
				)
			)
		)
		(pad "2" smd custom
			(at 0 0.762 270)
			(size 0.2159 0.2159)
			(layers "F.Cu" "F.Mask" "F.Paste")
			(net "GND")
			(options
				(clearance outline)
				(anchor circle)
			)
			(primitives
				(gr_poly
					(pts
						(arc
							(start -0.3302 -0.4318)
							(mid -0.402042 -0.402042)
							(end -0.4318 -0.3302)
						)
						(arc
							(start -0.4318 0.3302)
							(mid -0.402042 0.402042)
							(end -0.3302 0.4318)
						)
						(arc
							(start 0.3302 0.4318)
							(mid 0.402042 0.402042)
							(end 0.4318 0.3302)
						)
						(arc
							(start 0.4318 -0.3302)
							(mid 0.402042 -0.402042)
							(end 0.3302 -0.4318)
						)
					)
					(width 0)
					(fill yes)
				)
			)
		)
	)
	(footprint ""
		(layer "F.Cu")
		(at 44.7802 -10.7188 180)
		(property "Reference" "C25"
			(at 0 0 180)
			(layer "F.SilkS")
			(hide yes)
			(effects
				(font
					(size 1.27 1.27)
				)
			)
		)
		(property "Value" "SCD1U16V2KX-3GP"
			(at 1.1811 -2.7051 180)
			(unlocked yes)
			(layer "F.Fab")
			(hide yes)
			(effects
				(font
					(size 1.016 1.016)
					(thickness 0.1524)
				)
			)
		)
		(property "Device Type" "C402H22"
			(at 1.1811 -4.2291 180)
			(unlocked yes)
			(layer "F.Fab")
			(hide yes)
			(effects
				(font
					(size 1.016 1.016)
					(thickness 0.1524)
				)
			)
		)
		(duplicate_pad_numbers_are_jumpers no)
		(fp_rect
			(start -0.4318 0.9525)
			(end 0.4318 -0.9525)
			(stroke
				(width 0)
				(type default)
			)
			(fill no)
			(layer "F.CrtYd")
		)
		(fp_rect
			(start -0.4318 0.9525)
			(end 0.4318 -0.9525)
			(stroke
				(width 0)
				(type default)
			)
			(fill no)
			(layer "F.Fab")
		)
		(pad "1" smd custom
			(at 0 -0.4445 180)
			(size 0.1524 0.1524)
			(layers "F.Cu" "F.Mask" "F.Paste")
			(net "P3V3_STBY_B")
			(options
				(clearance outline)
				(anchor circle)
			)
			(primitives
				(gr_poly
					(pts
						(arc
							(start 0.3048 -0.2032)
							(mid 0.275042 -0.275042)
							(end 0.2032 -0.3048)
						)
						(arc
							(start -0.2032 -0.3048)
							(mid -0.275042 -0.275042)
							(end -0.3048 -0.2032)
						)
						(arc
							(start -0.3048 0.2032)
							(mid -0.275042 0.275042)
							(end -0.2032 0.3048)
						)
						(arc
							(start 0.2032 0.3048)
							(mid 0.275042 0.275042)
							(end 0.3048 0.2032)
						)
					)
					(width 0)
					(fill yes)
				)
			)
		)
		(pad "2" smd custom
			(at 0 0.4445 180)
			(size 0.1524 0.1524)
			(layers "F.Cu" "F.Mask" "F.Paste")
			(net "GND")
			(options
				(clearance outline)
				(anchor circle)
			)
			(primitives
				(gr_poly
					(pts
						(arc
							(start 0.3048 -0.2032)
							(mid 0.275042 -0.275042)
							(end 0.2032 -0.3048)
						)
						(arc
							(start -0.2032 -0.3048)
							(mid -0.275042 -0.275042)
							(end -0.3048 -0.2032)
						)
						(arc
							(start -0.3048 0.2032)
							(mid -0.275042 0.275042)
							(end -0.2032 0.3048)
						)
						(arc
							(start 0.2032 0.3048)
							(mid 0.275042 0.275042)
							(end 0.3048 0.2032)
						)
					)
					(width 0)
					(fill yes)
				)
			)
		)
	)
	(footprint ""
		(layer "F.Cu")
		(at 43.481498 -17.814544 -90)
		(property "Reference" "R11"
			(at 0 0 270)
			(layer "F.SilkS")
			(hide yes)
			(effects
				(font
					(size 1.27 1.27)
				)
			)
		)
		(property "Value" "4K7R2F-GP"
			(at 0.064008 -4.679696 270)
			(unlocked yes)
			(layer "F.Fab")
			(hide yes)
			(effects
				(font
					(size 2.54 2.54)
					(thickness 0.381)
				)
			)
		)
		(property "Device Type" "R402H16"
			(at 0.064008 -6.203696 270)
			(unlocked yes)
			(layer "F.Fab")
			(hide yes)
			(effects
				(font
					(size 2.54 2.54)
					(thickness 0.381)
				)
			)
		)
		(duplicate_pad_numbers_are_jumpers no)
		(fp_line
			(start -0.508 -0.9398)
			(end -0.508 0.9398)
			(stroke
				(width 0.1524)
				(type default)
			)
			(layer "F.SilkS")
		)
		(fp_line
			(start 0.508 -0.9398)
			(end -0.508 -0.9398)
			(stroke
				(width 0.1524)
				(type default)
			)
			(layer "F.SilkS")
		)
		(fp_rect
			(start -0.508 0.9398)
			(end 0.508 -0.9398)
			(stroke
				(width 0)
				(type default)
			)
			(fill no)
			(layer "F.CrtYd")
		)
		(fp_rect
			(start -0.508 0.9398)
			(end 0.508 -0.9398)
			(stroke
				(width 0)
				(type default)
			)
			(fill no)
			(layer "F.Fab")
		)
		(pad "1" smd custom
			(at 0 -0.4445 270)
			(size 0.1397 0.1397)
			(layers "F.Cu" "F.Mask" "F.Paste")
			(net "P3V3_STBY_B")
			(options
				(clearance outline)
				(anchor circle)
			)
			(primitives
				(gr_poly
					(pts
						(arc
							(start -0.1778 -0.2794)
							(mid -0.249642 -0.249642)
							(end -0.2794 -0.1778)
						)
						(arc
							(start -0.2794 0.1778)
							(mid -0.249642 0.249642)
							(end -0.1778 0.2794)
						)
						(arc
							(start 0.1778 0.2794)
							(mid 0.249642 0.249642)
							(end 0.2794 0.1778)
						)
						(arc
							(start 0.2794 -0.1778)
							(mid 0.249642 -0.249642)
							(end 0.1778 -0.2794)
						)
					)
					(width 0)
					(fill yes)
				)
			)
		)
		(pad "2" smd custom
			(at 0 0.4445 270)
			(size 0.1397 0.1397)
			(layers "F.Cu" "F.Mask" "F.Paste")
			(net "I2C_DEBUG_B_SDA")
			(options
				(clearance outline)
				(anchor circle)
			)
			(primitives
				(gr_poly
					(pts
						(arc
							(start -0.1778 -0.2794)
							(mid -0.249642 -0.249642)
							(end -0.2794 -0.1778)
						)
						(arc
							(start -0.2794 0.1778)
							(mid -0.249642 0.249642)
							(end -0.1778 0.2794)
						)
						(arc
							(start 0.1778 0.2794)
							(mid 0.249642 0.249642)
							(end 0.2794 0.1778)
						)
						(arc
							(start 0.2794 -0.1778)
							(mid 0.249642 -0.249642)
							(end 0.1778 -0.2794)
						)
					)
					(width 0)
					(fill yes)
				)
			)
		)
	)
	(footprint ""
		(layer "F.Cu")
		(at 55.2196 -50.1142 90)
		(property "Reference" "R40"
			(at 0 0 90)
			(layer "F.SilkS")
			(hide yes)
			(effects
				(font
					(size 1.27 1.27)
				)
			)
		)
		(property "Value" "4K7R2F-GP"
			(at 0.064008 -4.679696 90)
			(unlocked yes)
			(layer "F.Fab")
			(hide yes)
			(effects
				(font
					(size 2.54 2.54)
					(thickness 0.381)
				)
			)
		)
		(property "Device Type" "R402H16"
			(at 0.064008 -6.203696 90)
			(unlocked yes)
			(layer "F.Fab")
			(hide yes)
			(effects
				(font
					(size 2.54 2.54)
					(thickness 0.381)
				)
			)
		)
		(duplicate_pad_numbers_are_jumpers no)
		(fp_line
			(start 0.508 -0.9398)
			(end -0.508 -0.9398)
			(stroke
				(width 0.1524)
				(type default)
			)
			(layer "F.SilkS")
		)
		(fp_line
			(start -0.508 -0.9398)
			(end -0.508 0.9398)
			(stroke
				(width 0.1524)
				(type default)
			)
			(layer "F.SilkS")
		)
		(fp_rect
			(start -0.508 0.9398)
			(end 0.508 -0.9398)
			(stroke
				(width 0)
				(type default)
			)
			(fill no)
			(layer "F.CrtYd")
		)
		(fp_rect
			(start -0.508 0.9398)
			(end 0.508 -0.9398)
			(stroke
				(width 0)
				(type default)
			)
			(fill no)
			(layer "F.Fab")
		)
		(pad "1" smd custom
			(at 0 -0.4445 90)
			(size 0.1397 0.1397)
			(layers "F.Cu" "F.Mask" "F.Paste")
			(net "TEMP_2_A0")
			(options
				(clearance outline)
				(anchor circle)
			)
			(primitives
				(gr_poly
					(pts
						(arc
							(start -0.1778 -0.2794)
							(mid -0.249642 -0.249642)
							(end -0.2794 -0.1778)
						)
						(arc
							(start -0.2794 0.1778)
							(mid -0.249642 0.249642)
							(end -0.1778 0.2794)
						)
						(arc
							(start 0.1778 0.2794)
							(mid 0.249642 0.249642)
							(end 0.2794 0.1778)
						)
						(arc
							(start 0.2794 -0.1778)
							(mid 0.249642 -0.249642)
							(end 0.1778 -0.2794)
						)
					)
					(width 0)
					(fill yes)
				)
			)
		)
		(pad "2" smd custom
			(at 0 0.4445 90)
			(size 0.1397 0.1397)
			(layers "F.Cu" "F.Mask" "F.Paste")
			(net "GND")
			(options
				(clearance outline)
				(anchor circle)
			)
			(primitives
				(gr_poly
					(pts
						(arc
							(start -0.1778 -0.2794)
							(mid -0.249642 -0.249642)
							(end -0.2794 -0.1778)
						)
						(arc
							(start -0.2794 0.1778)
							(mid -0.249642 0.249642)
							(end -0.1778 0.2794)
						)
						(arc
							(start 0.1778 0.2794)
							(mid 0.249642 0.249642)
							(end 0.2794 0.1778)
						)
						(arc
							(start 0.2794 -0.1778)
							(mid 0.249642 -0.249642)
							(end 0.1778 -0.2794)
						)
					)
					(width 0)
					(fill yes)
				)
			)
		)
	)
	(footprint ""
		(layer "F.Cu")
		(at 20.4724 -13.4366)
		(property "Reference" "R2"
			(at 0 0 0)
			(layer "F.SilkS")
			(hide yes)
			(effects
				(font
					(size 1.27 1.27)
				)
			)
		)
		(property "Value" "0R2J-2-GP"
			(at 0.064008 -4.679696 0)
			(unlocked yes)
			(layer "F.Fab")
			(hide yes)
			(effects
				(font
					(size 2.54 2.54)
					(thickness 0.381)
				)
			)
		)
		(property "Device Type" "R402H16"
			(at 0.064008 -6.203696 0)
			(unlocked yes)
			(layer "F.Fab")
			(hide yes)
			(effects
				(font
					(size 2.54 2.54)
					(thickness 0.381)
				)
			)
		)
		(duplicate_pad_numbers_are_jumpers no)
		(fp_line
			(start -0.508 -0.9398)
			(end -0.508 0.9398)
			(stroke
				(width 0.1524)
				(type default)
			)
			(layer "F.SilkS")
		)
		(fp_line
			(start 0.508 -0.9398)
			(end -0.508 -0.9398)
			(stroke
				(width 0.1524)
				(type default)
			)
			(layer "F.SilkS")
		)
		(fp_rect
			(start -0.508 0.9398)
			(end 0.508 -0.9398)
			(stroke
				(width 0)
				(type default)
			)
			(fill no)
			(layer "F.CrtYd")
		)
		(fp_rect
			(start -0.508 0.9398)
			(end 0.508 -0.9398)
			(stroke
				(width 0)
				(type default)
			)
			(fill no)
			(layer "F.Fab")
		)
		(pad "1" smd custom
			(at 0 -0.4445)
			(size 0.1397 0.1397)
			(layers "F.Cu" "F.Mask" "F.Paste")
			(net "UART_SEL_A_MUX")
			(options
				(clearance outline)
				(anchor circle)
			)
			(primitives
				(gr_poly
					(pts
						(arc
							(start -0.1778 -0.2794)
							(mid -0.249642 -0.249642)
							(end -0.2794 -0.1778)
						)
						(arc
							(start -0.2794 0.1778)
							(mid -0.249642 0.249642)
							(end -0.1778 0.2794)
						)
						(arc
							(start 0.1778 0.2794)
							(mid 0.249642 0.249642)
							(end 0.2794 0.1778)
						)
						(arc
							(start 0.2794 -0.1778)
							(mid 0.249642 -0.249642)
							(end 0.1778 -0.2794)
						)
					)
					(width 0)
					(fill yes)
				)
			)
		)
		(pad "2" smd custom
			(at 0 0.4445)
			(size 0.1397 0.1397)
			(layers "F.Cu" "F.Mask" "F.Paste")
			(net "UART_SEL_A_MUX_R")
			(options
				(clearance outline)
				(anchor circle)
			)
			(primitives
				(gr_poly
					(pts
						(arc
							(start -0.1778 -0.2794)
							(mid -0.249642 -0.249642)
							(end -0.2794 -0.1778)
						)
						(arc
							(start -0.2794 0.1778)
							(mid -0.249642 0.249642)
							(end -0.1778 0.2794)
						)
						(arc
							(start 0.1778 0.2794)
							(mid 0.249642 0.249642)
							(end 0.2794 0.1778)
						)
						(arc
							(start 0.2794 -0.1778)
							(mid 0.249642 -0.249642)
							(end 0.1778 -0.2794)
						)
					)
					(width 0)
					(fill yes)
				)
			)
		)
	)
	(footprint ""
		(layer "F.Cu")
		(at 27.3812 -13.1572 90)
		(property "Reference" "C33"
			(at 0 0 90)
			(layer "F.SilkS")
			(hide yes)
			(effects
				(font
					(size 1.27 1.27)
				)
			)
		)
		(property "Value" "SCD1U16V2KX-3GP"
			(at 1.1811 -2.7051 90)
			(unlocked yes)
			(layer "F.Fab")
			(hide yes)
			(effects
				(font
					(size 1.016 1.016)
					(thickness 0.1524)
				)
			)
		)
		(property "Device Type" "C402H22"
			(at 1.1811 -4.2291 90)
			(unlocked yes)
			(layer "F.Fab")
			(hide yes)
			(effects
				(font
					(size 1.016 1.016)
					(thickness 0.1524)
				)
			)
		)
		(duplicate_pad_numbers_are_jumpers no)
		(fp_rect
			(start -0.4318 0.9525)
			(end 0.4318 -0.9525)
			(stroke
				(width 0)
				(type default)
			)
			(fill no)
			(layer "F.CrtYd")
		)
		(fp_rect
			(start -0.4318 0.9525)
			(end 0.4318 -0.9525)
			(stroke
				(width 0)
				(type default)
			)
			(fill no)
			(layer "F.Fab")
		)
		(pad "1" smd custom
			(at 0 -0.4445 90)
			(size 0.1524 0.1524)
			(layers "F.Cu" "F.Mask" "F.Paste")
			(net "D_FLIP_CLR_A#")
			(options
				(clearance outline)
				(anchor circle)
			)
			(primitives
				(gr_poly
					(pts
						(arc
							(start 0.3048 -0.2032)
							(mid 0.275042 -0.275042)
							(end 0.2032 -0.3048)
						)
						(arc
							(start -0.2032 -0.3048)
							(mid -0.275042 -0.275042)
							(end -0.3048 -0.2032)
						)
						(arc
							(start -0.3048 0.2032)
							(mid -0.275042 0.275042)
							(end -0.2032 0.3048)
						)
						(arc
							(start 0.2032 0.3048)
							(mid 0.275042 0.275042)
							(end 0.3048 0.2032)
						)
					)
					(width 0)
					(fill yes)
				)
			)
		)
		(pad "2" smd custom
			(at 0 0.4445 90)
			(size 0.1524 0.1524)
			(layers "F.Cu" "F.Mask" "F.Paste")
			(net "GND")
			(options
				(clearance outline)
				(anchor circle)
			)
			(primitives
				(gr_poly
					(pts
						(arc
							(start 0.3048 -0.2032)
							(mid 0.275042 -0.275042)
							(end 0.2032 -0.3048)
						)
						(arc
							(start -0.2032 -0.3048)
							(mid -0.275042 -0.275042)
							(end -0.3048 -0.2032)
						)
						(arc
							(start -0.3048 0.2032)
							(mid -0.275042 0.275042)
							(end -0.2032 0.3048)
						)
						(arc
							(start 0.2032 0.3048)
							(mid 0.275042 0.275042)
							(end 0.3048 0.2032)
						)
					)
					(width 0)
					(fill yes)
				)
			)
		)
	)
	(footprint ""
		(layer "F.Cu")
		(at 8.199882 -79.499968)
		(property "Reference" "SW1"
			(at 0 0 0)
			(layer "F.SilkS")
			(hide yes)
			(effects
				(font
					(size 1.27 1.27)
				)
			)
		)
		(property "Value" "SW-TACT-6P-100-GP"
			(at 6.9088 -7.239 0)
			(unlocked yes)
			(layer "F.Fab")
			(hide yes)
			(effects
				(font
					(size 2.54 2.54)
					(thickness 0.381)
				)
			)
		)
		(property "Device Type" "PS004-L22NPR1KKK3UBXX"
			(at 6.9088 -8.763 0)
			(unlocked yes)
			(layer "F.Fab")
			(hide yes)
			(effects
				(font
					(size 2.54 2.54)
					(thickness 0.381)
				)
			)
		)
		(duplicate_pad_numbers_are_jumpers no)
		(fp_line
			(start -5.7912 -0.7874)
			(end -5.198618 -0.7874)
			(stroke
				(width 0.1524)
				(type default)
			)
			(layer "F.SilkS")
		)
		(fp_line
			(start -5.7912 0.7874)
			(end -5.7912 -0.7874)
			(stroke
				(width 0.1524)
				(type default)
			)
			(layer "F.SilkS")
		)
		(fp_line
			(start -5.198618 0.7874)
			(end -5.7912 0.7874)
			(stroke
				(width 0.1524)
				(type default)
			)
			(layer "F.SilkS")
		)
		(fp_line
			(start -4.7498 -4.7498)
			(end -2.254758 -4.7498)
			(stroke
				(width 0.1524)
				(type default)
			)
			(layer "F.SilkS")
		)
		(fp_line
			(start -4.7498 -2.254758)
			(end -4.7498 -4.7498)
			(stroke
				(width 0.1524)
				(type default)
			)
			(layer "F.SilkS")
		)
		(fp_line
			(start -4.7498 4.7498)
			(end -4.7498 2.254758)
			(stroke
				(width 0.1524)
				(type default)
			)
			(layer "F.SilkS")
		)
		(fp_line
			(start -2.254758 4.7498)
			(end -4.7498 4.7498)
			(stroke
				(width 0.1524)
				(type default)
			)
			(layer "F.SilkS")
		)
		(fp_line
			(start 0 -1.0922)
			(end 0 -0.4572)
			(stroke
				(width 0.1524)
				(type default)
			)
			(layer "F.SilkS")
		)
		(fp_line
			(start 2.254758 -4.7498)
			(end 4.7498 -4.7498)
			(stroke
				(width 0.1524)
				(type default)
			)
			(layer "F.SilkS")
		)
		(fp_line
			(start 4.1402 -4.8387)
			(end 4.8387 -4.8387)
			(stroke
				(width 0.3302)
				(type default)
			)
			(layer "F.SilkS")
		)
		(fp_line
			(start 4.7498 -4.7498)
			(end 4.7498 -2.254758)
			(stroke
				(width 0.1524)
				(type default)
			)
			(layer "F.SilkS")
		)
		(fp_line
			(start 4.7498 2.254758)
			(end 4.7498 4.7498)
			(stroke
				(width 0.1524)
				(type default)
			)
			(layer "F.SilkS")
		)
		(fp_line
			(start 4.7498 4.7498)
			(end 2.254758 4.7498)
			(stroke
				(width 0.1524)
				(type default)
			)
			(layer "F.SilkS")
		)
		(fp_line
			(start 4.8387 -4.8387)
			(end 4.8387 -4.1656)
			(stroke
				(width 0.3302)
				(type default)
			)
			(layer "F.SilkS")
		)
		(fp_line
			(start 5.198618 -0.7874)
			(end 5.7912 -0.7874)
			(stroke
				(width 0.1524)
				(type default)
			)
			(layer "F.SilkS")
		)
		(fp_line
			(start 5.7912 -0.7874)
			(end 5.7912 0.7874)
			(stroke
				(width 0.1524)
				(type default)
			)
			(layer "F.SilkS")
		)
		(fp_line
			(start 5.7912 0.7874)
			(end 5.198618 0.7874)
			(stroke
				(width 0.1524)
				(type default)
			)
			(layer "F.SilkS")
		)
		(fp_arc
			(start -5.198618 -0.7874)
			(mid -5.028041 -1.537546)
			(end -4.7498 -2.254758)
			(stroke
				(width 0.1524)
				(type default)
			)
			(layer "F.SilkS")
		)
		(fp_arc
			(start -4.7498 2.254758)
			(mid -5.02801 1.537536)
			(end -5.198618 0.7874)
			(stroke
				(width 0.1524)
				(type default)
			)
			(layer "F.SilkS")
		)
		(fp_arc
			(start -2.254758 -4.7498)
			(mid 0 -5.257807)
			(end 2.254758 -4.7498)
			(stroke
				(width 0.1524)
				(type default)
			)
			(layer "F.SilkS")
		)
		(fp_arc
			(start 0 1.016)
			(mid -0.938662 0.388806)
			(end -0.718312 -0.718312)
			(stroke
				(width 0.1524)
				(type default)
			)
			(layer "F.SilkS")
		)
		(fp_arc
			(start 0.718312 -0.718312)
			(mid 0.93852 0.388748)
			(end 0 1.016)
			(stroke
				(width 0.1524)
				(type default)
			)
			(layer "F.SilkS")
		)
		(fp_arc
			(start 2.254758 4.7498)
			(mid 0 5.257807)
			(end -2.254758 4.7498)
			(stroke
				(width 0.1524)
				(type default)
			)
			(layer "F.SilkS")
		)
		(fp_arc
			(start 4.7498 -2.254758)
			(mid 5.02801 -1.537536)
			(end 5.198618 -0.7874)
			(stroke
				(width 0.1524)
				(type default)
			)
			(layer "F.SilkS")
		)
		(fp_arc
			(start 5.198618 0.7874)
			(mid 5.028041 1.537546)
			(end 4.7498 2.254758)
			(stroke
				(width 0.1524)
				(type default)
			)
			(layer "F.SilkS")
		)
		(fp_circle
			(center -4.99999 0)
			(end -4.11099 0)
			(stroke
				(width 0.3048)
				(type default)
			)
			(fill no)
			(layer "F.SilkS")
		)
		(fp_circle
			(center -2.500122 -2.500122)
			(end -1.484122 -2.500122)
			(stroke
				(width 0.3048)
				(type default)
			)
			(fill no)
			(layer "F.SilkS")
		)
		(fp_circle
			(center -2.500122 2.500122)
			(end -1.484122 2.500122)
			(stroke
				(width 0.3048)
				(type default)
			)
			(fill no)
			(layer "F.SilkS")
		)
		(fp_circle
			(center 0 -2.500122)
			(end 1.016 -2.500122)
			(stroke
				(width 0.3048)
				(type default)
			)
			(fill no)
			(layer "F.SilkS")
		)
		(fp_circle
			(center 0 2.500122)
			(end 1.016 2.500122)
			(stroke
				(width 0.3048)
				(type default)
			)
			(fill no)
			(layer "F.SilkS")
		)
		(fp_circle
			(center 2.500122 -2.500122)
			(end 3.516122 -2.500122)
			(stroke
				(width 0.3048)
				(type default)
			)
			(fill no)
			(layer "F.SilkS")
		)
		(fp_circle
			(center 2.500122 2.500122)
			(end 3.516122 2.500122)
			(stroke
				(width 0.3048)
				(type default)
			)
			(fill no)
			(layer "F.SilkS")
		)
		(fp_circle
			(center 4.99999 0)
			(end 5.88899 0)
			(stroke
				(width 0.3048)
				(type default)
			)
			(fill no)
			(layer "F.SilkS")
		)
		(fp_poly
			(pts
				(arc
					(start 2.196846 4.4958)
					(mid 0 5.003834)
					(end -2.196846 4.4958)
				)
				(xy -4.4958 4.4958)
				(arc
					(start -4.4958 2.196846)
					(mid -4.845024 1.250828)
					(end -4.99745 0.254)
				)
				(xy -5.1308 0.254) (xy -5.1308 -0.254)
				(arc
					(start -4.99745 -0.254)
					(mid -4.844994 -1.250821)
					(end -4.4958 -2.196846)
				)
				(xy -4.4958 -4.4958)
				(arc
					(start -2.196846 -4.4958)
					(mid 0 -5.003834)
					(end 2.196846 -4.4958)
				)
				(xy 4.4958 -4.4958)
				(arc
					(start 4.4958 -2.196846)
					(mid 4.845024 -1.250828)
					(end 4.99745 -0.254)
				)
				(xy 5.1308 -0.254) (xy 5.1308 0.254)
				(arc
					(start 4.99745 0.254)
					(mid 4.844994 1.250821)
					(end 4.4958 2.196846)
				)
				(xy 4.4958 4.4958)
			)
			(stroke
				(width 0)
				(type default)
			)
			(fill no)
			(layer "F.CrtYd")
		)
		(fp_poly
			(pts
				(arc
					(start 2.3114 5.0038)
					(mid 0 5.511859)
					(end -2.3114 5.0038)
				)
				(xy -5.0038 5.0038)
				(arc
					(start -5.0038 2.3114)
					(mid -5.246729 1.688816)
					(end -5.412486 1.0414)
				)
				(xy -6.0452 1.0414) (xy -6.0452 -1.0414)
				(arc
					(start -5.412486 -1.0414)
					(mid -5.246693 -1.688804)
					(end -5.0038 -2.3114)
				)
				(xy -5.0038 -5.0038)
				(arc
					(start -2.3114 -5.0038)
					(mid 0 -5.511859)
					(end 2.3114 -5.0038)
				)
				(xy 5.0038 -5.0038)
				(arc
					(start 5.0038 -2.3114)
					(mid 5.246729 -1.688816)
					(end 5.412486 -1.0414)
				)
				(xy 6.0452 -1.0414) (xy 6.0452 -0.00635) (xy 5.1308 -0.00635) (xy 5.1308 -0.254)
				(arc
					(start 4.997704 -0.254)
					(mid 4.845133 -1.250792)
					(end 4.496054 -2.196846)
				)
				(xy 4.4958 -4.4958)
				(arc
					(start 2.196846 -4.4958)
					(mid 0 -5.003834)
					(end -2.196846 -4.4958)
				)
				(xy -4.4958 -4.4958)
				(arc
					(start -4.4958 -2.196846)
					(mid -4.84509 -1.250826)
					(end -4.997704 -0.254)
				)
				(xy -5.1308 -0.254) (xy -5.1308 0.254)
				(arc
					(start -4.997704 0.254)
					(mid -4.845193 1.250762)
					(end -4.496308 2.196846)
				)
				(xy -4.4958 4.4958)
				(arc
					(start -2.196846 4.4958)
					(mid 0 5.003834)
					(end 2.196846 4.4958)
				)
				(xy 4.4958 4.4958)
				(arc
					(start 4.4958 2.196846)
					(mid 4.84509 1.250826)
					(end 4.997704 0.254)
				)
				(xy 5.1308 0.254) (xy 5.1308 0.00635) (xy 6.0452 0.00635) (xy 6.0452 1.0414)
				(arc
					(start 5.412486 1.0414)
					(mid 5.246693 1.688804)
					(end 5.0038 2.3114)
				)
				(xy 5.0038 5.0038)
			)
			(stroke
				(width 0)
				(type default)
			)
			(fill no)
			(layer "F.CrtYd")
		)
		(fp_poly
			(pts
				(arc
					(start 2.3114 5.0038)
					(mid 0 5.511859)
					(end -2.3114 5.0038)
				)
				(xy -5.0038 5.0038)
				(arc
					(start -5.0038 2.3114)
					(mid -5.246729 1.688816)
					(end -5.412486 1.0414)
				)
				(xy -6.0452 1.0414) (xy -6.0452 -1.0414)
				(arc
					(start -5.412486 -1.0414)
					(mid -5.246693 -1.688804)
					(end -5.0038 -2.3114)
				)
				(xy -5.0038 -5.0038)
				(arc
					(start -2.3114 -5.0038)
					(mid 0 -5.511859)
					(end 2.3114 -5.0038)
				)
				(xy 5.0038 -5.0038)
				(arc
					(start 5.0038 -2.3114)
					(mid 5.246729 -1.688816)
					(end 5.412486 -1.0414)
				)
				(xy 6.0452 -1.0414) (xy 6.0452 1.0414)
				(arc
					(start 5.412486 1.0414)
					(mid 5.246693 1.688804)
					(end 5.0038 2.3114)
				)
				(xy 5.0038 5.0038)
			)
			(stroke
				(width 0)
				(type default)
			)
			(fill no)
			(layer "F.Fab")
		)
		(pad "1" thru_hole circle
			(at 2.500122 -2.500122)
			(size 1.3208 1.3208)
			(drill 0.9144)
			(layers "*.Cu" "*.Mask")
			(remove_unused_layers no)
			(net "PWR_BTN_A")
			(clearance 0.1524)
			(thermal_gap 0.1524)
		)
		(pad "2" thru_hole circle
			(at 0 -2.500122)
			(size 1.3208 1.3208)
			(drill 0.9144)
			(layers "*.Cu" "*.Mask")
			(remove_unused_layers no)
			(net "PWR_BTN_A_CONN")
			(clearance 0.1524)
			(thermal_gap 0.1524)
		)
		(pad "3" thru_hole circle
			(at -2.500122 -2.500122)
			(size 1.3208 1.3208)
			(drill 0.9144)
			(layers "*.Cu" "*.Mask")
			(remove_unused_layers no)
			(net "Net_117")
			(clearance 0.1524)
			(thermal_gap 0.1524)
		)
		(pad "4" thru_hole circle
			(at 2.500122 2.500122)
			(size 1.3208 1.3208)
			(drill 0.9144)
			(layers "*.Cu" "*.Mask")
			(remove_unused_layers no)
			(net "GND")
			(clearance 0.1524)
			(thermal_gap 0.1524)
		)
		(pad "5" thru_hole circle
			(at 0 2.500122)
			(size 1.3208 1.3208)
			(drill 0.9144)
			(layers "*.Cu" "*.Mask")
			(remove_unused_layers no)
			(net "PWR_BTN_A_CONN")
			(clearance 0.1524)
			(thermal_gap 0.1524)
		)
		(pad "6" thru_hole circle
			(at -2.500122 2.500122)
			(size 1.3208 1.3208)
			(drill 0.9144)
			(layers "*.Cu" "*.Mask")
			(remove_unused_layers no)
			(net "Net_118")
			(clearance 0.1524)
			(thermal_gap 0.1524)
		)
		(pad "L1" thru_hole circle
			(at 4.99999 0)
			(size 1.0668 1.0668)
			(drill 0.7112)
			(layers "*.Cu" "*.Mask")
			(remove_unused_layers no)
			(net "PWR_BTN_LED_A_R")
			(clearance 0.1778)
			(thermal_gap 0.1778)
		)
		(pad "L2" thru_hole circle
			(at -4.99999 0)
			(size 1.0668 1.0668)
			(drill 0.7112)
			(layers "*.Cu" "*.Mask")
			(remove_unused_layers no)
			(net "PWR_LED_A_N")
			(clearance 0.1778)
			(thermal_gap 0.1778)
		)
	)
	(footprint ""
		(layer "F.Cu")
		(at 12.2682 -44.1452)
		(property "Reference" "R29"
			(at 0 0 0)
			(layer "F.SilkS")
			(hide yes)
			(effects
				(font
					(size 1.27 1.27)
				)
			)
		)
		(property "Value" "4K7R2F-GP"
			(at 0.064008 -4.679696 0)
			(unlocked yes)
			(layer "F.Fab")
			(hide yes)
			(effects
				(font
					(size 2.54 2.54)
					(thickness 0.381)
				)
			)
		)
		(property "Device Type" "R402H16"
			(at 0.064008 -6.203696 0)
			(unlocked yes)
			(layer "F.Fab")
			(hide yes)
			(effects
				(font
					(size 2.54 2.54)
					(thickness 0.381)
				)
			)
		)
		(duplicate_pad_numbers_are_jumpers no)
		(fp_line
			(start -0.508 -0.9398)
			(end -0.508 0.9398)
			(stroke
				(width 0.1524)
				(type default)
			)
			(layer "F.SilkS")
		)
		(fp_line
			(start 0.508 -0.9398)
			(end -0.508 -0.9398)
			(stroke
				(width 0.1524)
				(type default)
			)
			(layer "F.SilkS")
		)
		(fp_rect
			(start -0.508 0.9398)
			(end 0.508 -0.9398)
			(stroke
				(width 0)
				(type default)
			)
			(fill no)
			(layer "F.CrtYd")
		)
		(fp_rect
			(start -0.508 0.9398)
			(end 0.508 -0.9398)
			(stroke
				(width 0)
				(type default)
			)
			(fill no)
			(layer "F.Fab")
		)
		(pad "1" smd custom
			(at 0 -0.4445)
			(size 0.1397 0.1397)
			(layers "F.Cu" "F.Mask" "F.Paste")
			(net "TEMP_1_A2")
			(options
				(clearance outline)
				(anchor circle)
			)
			(primitives
				(gr_poly
					(pts
						(arc
							(start -0.1778 -0.2794)
							(mid -0.249642 -0.249642)
							(end -0.2794 -0.1778)
						)
						(arc
							(start -0.2794 0.1778)
							(mid -0.249642 0.249642)
							(end -0.1778 0.2794)
						)
						(arc
							(start 0.1778 0.2794)
							(mid 0.249642 0.249642)
							(end 0.2794 0.1778)
						)
						(arc
							(start 0.2794 -0.1778)
							(mid 0.249642 -0.249642)
							(end 0.1778 -0.2794)
						)
					)
					(width 0)
					(fill yes)
				)
			)
		)
		(pad "2" smd custom
			(at 0 0.4445)
			(size 0.1397 0.1397)
			(layers "F.Cu" "F.Mask" "F.Paste")
			(net "GND")
			(options
				(clearance outline)
				(anchor circle)
			)
			(primitives
				(gr_poly
					(pts
						(arc
							(start -0.1778 -0.2794)
							(mid -0.249642 -0.249642)
							(end -0.2794 -0.1778)
						)
						(arc
							(start -0.2794 0.1778)
							(mid -0.249642 0.249642)
							(end -0.1778 0.2794)
						)
						(arc
							(start 0.1778 0.2794)
							(mid 0.249642 0.249642)
							(end 0.2794 0.1778)
						)
						(arc
							(start 0.2794 -0.1778)
							(mid 0.249642 -0.249642)
							(end 0.1778 -0.2794)
						)
					)
					(width 0)
					(fill yes)
				)
			)
		)
	)
	(footprint ""
		(layer "F.Cu")
		(at 47.371 -17.8308 -90)
		(property "Reference" "R57"
			(at 0 0 270)
			(layer "F.SilkS")
			(hide yes)
			(effects
				(font
					(size 1.27 1.27)
				)
			)
		)
		(property "Value" "20KR2F-L-GP"
			(at 0.064008 -3.993896 270)
			(unlocked yes)
			(layer "F.Fab")
			(hide yes)
			(effects
				(font
					(size 1.016 1.016)
					(thickness 0.1524)
				)
			)
		)
		(property "Device Type" "R402H16"
			(at 0.064008 -5.517896 270)
			(unlocked yes)
			(layer "F.Fab")
			(hide yes)
			(effects
				(font
					(size 1.016 1.016)
					(thickness 0.1524)
				)
			)
		)
		(duplicate_pad_numbers_are_jumpers no)
		(fp_line
			(start -0.508 -0.9398)
			(end -0.508 0.9398)
			(stroke
				(width 0.1524)
				(type default)
			)
			(layer "F.SilkS")
		)
		(fp_line
			(start 0.508 -0.9398)
			(end -0.508 -0.9398)
			(stroke
				(width 0.1524)
				(type default)
			)
			(layer "F.SilkS")
		)
		(fp_rect
			(start -0.508 0.9398)
			(end 0.508 -0.9398)
			(stroke
				(width 0)
				(type default)
			)
			(fill no)
			(layer "F.CrtYd")
		)
		(fp_rect
			(start -0.508 0.9398)
			(end 0.508 -0.9398)
			(stroke
				(width 0)
				(type default)
			)
			(fill no)
			(layer "F.Fab")
		)
		(pad "1" smd custom
			(at 0 -0.4445 270)
			(size 0.1397 0.1397)
			(layers "F.Cu" "F.Mask" "F.Paste")
			(net "P3V3_STBY_B")
			(options
				(clearance outline)
				(anchor circle)
			)
			(primitives
				(gr_poly
					(pts
						(arc
							(start -0.1778 -0.2794)
							(mid -0.249642 -0.249642)
							(end -0.2794 -0.1778)
						)
						(arc
							(start -0.2794 0.1778)
							(mid -0.249642 0.249642)
							(end -0.1778 0.2794)
						)
						(arc
							(start 0.1778 0.2794)
							(mid 0.249642 0.249642)
							(end 0.2794 0.1778)
						)
						(arc
							(start 0.2794 -0.1778)
							(mid 0.249642 -0.249642)
							(end 0.1778 -0.2794)
						)
					)
					(width 0)
					(fill yes)
				)
			)
		)
		(pad "2" smd custom
			(at 0 0.4445 270)
			(size 0.1397 0.1397)
			(layers "F.Cu" "F.Mask" "F.Paste")
			(net "I2C_DEBUG_B_SDA_L")
			(options
				(clearance outline)
				(anchor circle)
			)
			(primitives
				(gr_poly
					(pts
						(arc
							(start -0.1778 -0.2794)
							(mid -0.249642 -0.249642)
							(end -0.2794 -0.1778)
						)
						(arc
							(start -0.2794 0.1778)
							(mid -0.249642 0.249642)
							(end -0.1778 0.2794)
						)
						(arc
							(start 0.1778 0.2794)
							(mid 0.249642 0.249642)
							(end 0.2794 0.1778)
						)
						(arc
							(start 0.2794 -0.1778)
							(mid 0.249642 -0.249642)
							(end 0.1778 -0.2794)
						)
					)
					(width 0)
					(fill yes)
				)
			)
		)
	)
	(footprint ""
		(layer "F.Cu")
		(at 54.0258 -51.2826 -90)
		(property "Reference" "C15"
			(at 0 0 270)
			(layer "F.SilkS")
			(hide yes)
			(effects
				(font
					(size 1.27 1.27)
				)
			)
		)
		(property "Value" "SCD1U16V2KX-3GP"
			(at 1.1811 -3.3909 270)
			(unlocked yes)
			(layer "F.Fab")
			(hide yes)
			(effects
				(font
					(size 2.54 2.54)
					(thickness 0.381)
				)
			)
		)
		(property "Device Type" "C402H22"
			(at 1.1811 -4.9149 270)
			(unlocked yes)
			(layer "F.Fab")
			(hide yes)
			(effects
				(font
					(size 2.54 2.54)
					(thickness 0.381)
				)
			)
		)
		(duplicate_pad_numbers_are_jumpers no)
		(fp_rect
			(start -0.4318 0.9525)
			(end 0.4318 -0.9525)
			(stroke
				(width 0)
				(type default)
			)
			(fill no)
			(layer "F.CrtYd")
		)
		(fp_rect
			(start -0.4318 0.9525)
			(end 0.4318 -0.9525)
			(stroke
				(width 0)
				(type default)
			)
			(fill no)
			(layer "F.Fab")
		)
		(pad "1" smd custom
			(at 0 -0.4445 270)
			(size 0.1524 0.1524)
			(layers "F.Cu" "F.Mask" "F.Paste")
			(net "P3V3_STBY_B")
			(options
				(clearance outline)
				(anchor circle)
			)
			(primitives
				(gr_poly
					(pts
						(arc
							(start 0.3048 -0.2032)
							(mid 0.275042 -0.275042)
							(end 0.2032 -0.3048)
						)
						(arc
							(start -0.2032 -0.3048)
							(mid -0.275042 -0.275042)
							(end -0.3048 -0.2032)
						)
						(arc
							(start -0.3048 0.2032)
							(mid -0.275042 0.275042)
							(end -0.2032 0.3048)
						)
						(arc
							(start 0.2032 0.3048)
							(mid 0.275042 0.275042)
							(end 0.3048 0.2032)
						)
					)
					(width 0)
					(fill yes)
				)
			)
		)
		(pad "2" smd custom
			(at 0 0.4445 270)
			(size 0.1524 0.1524)
			(layers "F.Cu" "F.Mask" "F.Paste")
			(net "GND")
			(options
				(clearance outline)
				(anchor circle)
			)
			(primitives
				(gr_poly
					(pts
						(arc
							(start 0.3048 -0.2032)
							(mid 0.275042 -0.275042)
							(end 0.2032 -0.3048)
						)
						(arc
							(start -0.2032 -0.3048)
							(mid -0.275042 -0.275042)
							(end -0.3048 -0.2032)
						)
						(arc
							(start -0.3048 0.2032)
							(mid -0.275042 0.275042)
							(end -0.2032 0.3048)
						)
						(arc
							(start 0.2032 0.3048)
							(mid 0.275042 0.275042)
							(end 0.3048 0.2032)
						)
					)
					(width 0)
					(fill yes)
				)
			)
		)
	)
	(footprint ""
		(layer "F.Cu")
		(at 54.8894 -52.5018 90)
		(property "Reference" "R35"
			(at 0 0 90)
			(layer "F.SilkS")
			(hide yes)
			(effects
				(font
					(size 1.27 1.27)
				)
			)
		)
		(property "Value" "4K7R2F-GP"
			(at 0.064008 -4.679696 90)
			(unlocked yes)
			(layer "F.Fab")
			(hide yes)
			(effects
				(font
					(size 2.54 2.54)
					(thickness 0.381)
				)
			)
		)
		(property "Device Type" "R402H16"
			(at 0.064008 -6.203696 90)
			(unlocked yes)
			(layer "F.Fab")
			(hide yes)
			(effects
				(font
					(size 2.54 2.54)
					(thickness 0.381)
				)
			)
		)
		(duplicate_pad_numbers_are_jumpers no)
		(fp_line
			(start 0.508 -0.9398)
			(end -0.508 -0.9398)
			(stroke
				(width 0.1524)
				(type default)
			)
			(layer "F.SilkS")
		)
		(fp_line
			(start -0.508 -0.9398)
			(end -0.508 0.9398)
			(stroke
				(width 0.1524)
				(type default)
			)
			(layer "F.SilkS")
		)
		(fp_rect
			(start -0.508 0.9398)
			(end 0.508 -0.9398)
			(stroke
				(width 0)
				(type default)
			)
			(fill no)
			(layer "F.CrtYd")
		)
		(fp_rect
			(start -0.508 0.9398)
			(end 0.508 -0.9398)
			(stroke
				(width 0)
				(type default)
			)
			(fill no)
			(layer "F.Fab")
		)
		(pad "1" smd custom
			(at 0 -0.4445 90)
			(size 0.1397 0.1397)
			(layers "F.Cu" "F.Mask" "F.Paste")
			(net "P3V3_STBY_B")
			(options
				(clearance outline)
				(anchor circle)
			)
			(primitives
				(gr_poly
					(pts
						(arc
							(start -0.1778 -0.2794)
							(mid -0.249642 -0.249642)
							(end -0.2794 -0.1778)
						)
						(arc
							(start -0.2794 0.1778)
							(mid -0.249642 0.249642)
							(end -0.1778 0.2794)
						)
						(arc
							(start 0.1778 0.2794)
							(mid 0.249642 0.249642)
							(end 0.2794 0.1778)
						)
						(arc
							(start 0.2794 -0.1778)
							(mid 0.249642 -0.249642)
							(end 0.1778 -0.2794)
						)
					)
					(width 0)
					(fill yes)
				)
			)
		)
		(pad "2" smd custom
			(at 0 0.4445 90)
			(size 0.1397 0.1397)
			(layers "F.Cu" "F.Mask" "F.Paste")
			(net "TEMP_2_A0")
			(options
				(clearance outline)
				(anchor circle)
			)
			(primitives
				(gr_poly
					(pts
						(arc
							(start -0.1778 -0.2794)
							(mid -0.249642 -0.249642)
							(end -0.2794 -0.1778)
						)
						(arc
							(start -0.2794 0.1778)
							(mid -0.249642 0.249642)
							(end -0.1778 0.2794)
						)
						(arc
							(start 0.1778 0.2794)
							(mid 0.249642 0.249642)
							(end 0.2794 0.1778)
						)
						(arc
							(start 0.2794 -0.1778)
							(mid 0.249642 -0.249642)
							(end 0.1778 -0.2794)
						)
					)
					(width 0)
					(fill yes)
				)
			)
		)
	)
	(footprint ""
		(layer "F.Cu")
		(at 56.063642 -73.56983 180)
		(property "Reference" "R18"
			(at 0 0 180)
			(layer "F.SilkS")
			(hide yes)
			(effects
				(font
					(size 1.27 1.27)
				)
			)
		)
		(property "Value" "200R2J-L1-GP"
			(at 0.064008 -4.679696 180)
			(unlocked yes)
			(layer "F.Fab")
			(hide yes)
			(effects
				(font
					(size 2.54 2.54)
					(thickness 0.381)
				)
			)
		)
		(property "Device Type" "R402H16"
			(at 0.064008 -6.203696 180)
			(unlocked yes)
			(layer "F.Fab")
			(hide yes)
			(effects
				(font
					(size 2.54 2.54)
					(thickness 0.381)
				)
			)
		)
		(duplicate_pad_numbers_are_jumpers no)
		(fp_line
			(start 0.508 -0.9398)
			(end -0.508 -0.9398)
			(stroke
				(width 0.1524)
				(type default)
			)
			(layer "F.SilkS")
		)
		(fp_line
			(start -0.508 -0.9398)
			(end -0.508 0.9398)
			(stroke
				(width 0.1524)
				(type default)
			)
			(layer "F.SilkS")
		)
		(fp_rect
			(start -0.508 0.9398)
			(end 0.508 -0.9398)
			(stroke
				(width 0)
				(type default)
			)
			(fill no)
			(layer "F.CrtYd")
		)
		(fp_rect
			(start -0.508 0.9398)
			(end 0.508 -0.9398)
			(stroke
				(width 0)
				(type default)
			)
			(fill no)
			(layer "F.Fab")
		)
		(pad "1" smd custom
			(at 0 -0.4445 180)
			(size 0.1397 0.1397)
			(layers "F.Cu" "F.Mask" "F.Paste")
			(net "P5V_USB_B")
			(options
				(clearance outline)
				(anchor circle)
			)
			(primitives
				(gr_poly
					(pts
						(arc
							(start -0.1778 -0.2794)
							(mid -0.249642 -0.249642)
							(end -0.2794 -0.1778)
						)
						(arc
							(start -0.2794 0.1778)
							(mid -0.249642 0.249642)
							(end -0.1778 0.2794)
						)
						(arc
							(start 0.1778 0.2794)
							(mid 0.249642 0.249642)
							(end 0.2794 0.1778)
						)
						(arc
							(start 0.2794 -0.1778)
							(mid 0.249642 -0.249642)
							(end 0.1778 -0.2794)
						)
					)
					(width 0)
					(fill yes)
				)
			)
		)
		(pad "2" smd custom
			(at 0 0.4445 180)
			(size 0.1397 0.1397)
			(layers "F.Cu" "F.Mask" "F.Paste")
			(net "PWR_BTN_LED_B_R")
			(options
				(clearance outline)
				(anchor circle)
			)
			(primitives
				(gr_poly
					(pts
						(arc
							(start -0.1778 -0.2794)
							(mid -0.249642 -0.249642)
							(end -0.2794 -0.1778)
						)
						(arc
							(start -0.2794 0.1778)
							(mid -0.249642 0.249642)
							(end -0.1778 0.2794)
						)
						(arc
							(start 0.1778 0.2794)
							(mid 0.249642 0.249642)
							(end 0.2794 0.1778)
						)
						(arc
							(start 0.2794 -0.1778)
							(mid 0.249642 -0.249642)
							(end 0.1778 -0.2794)
						)
					)
					(width 0)
					(fill yes)
				)
			)
		)
	)
	(footprint ""
		(layer "F.Cu")
		(at 12.907772 -50.643536 90)
		(property "Reference" "C14"
			(at 0 0 90)
			(layer "F.SilkS")
			(hide yes)
			(effects
				(font
					(size 1.27 1.27)
				)
			)
		)
		(property "Value" "SCD1U16V2KX-3GP"
			(at 1.1811 -3.3909 90)
			(unlocked yes)
			(layer "F.Fab")
			(hide yes)
			(effects
				(font
					(size 2.54 2.54)
					(thickness 0.381)
				)
			)
		)
		(property "Device Type" "C402H22"
			(at 1.1811 -4.9149 90)
			(unlocked yes)
			(layer "F.Fab")
			(hide yes)
			(effects
				(font
					(size 2.54 2.54)
					(thickness 0.381)
				)
			)
		)
		(duplicate_pad_numbers_are_jumpers no)
		(fp_rect
			(start -0.4318 0.9525)
			(end 0.4318 -0.9525)
			(stroke
				(width 0)
				(type default)
			)
			(fill no)
			(layer "F.CrtYd")
		)
		(fp_rect
			(start -0.4318 0.9525)
			(end 0.4318 -0.9525)
			(stroke
				(width 0)
				(type default)
			)
			(fill no)
			(layer "F.Fab")
		)
		(pad "1" smd custom
			(at 0 -0.4445 90)
			(size 0.1524 0.1524)
			(layers "F.Cu" "F.Mask" "F.Paste")
			(net "P3V3_STBY_A")
			(options
				(clearance outline)
				(anchor circle)
			)
			(primitives
				(gr_poly
					(pts
						(arc
							(start 0.3048 -0.2032)
							(mid 0.275042 -0.275042)
							(end 0.2032 -0.3048)
						)
						(arc
							(start -0.2032 -0.3048)
							(mid -0.275042 -0.275042)
							(end -0.3048 -0.2032)
						)
						(arc
							(start -0.3048 0.2032)
							(mid -0.275042 0.275042)
							(end -0.2032 0.3048)
						)
						(arc
							(start 0.2032 0.3048)
							(mid 0.275042 0.275042)
							(end 0.3048 0.2032)
						)
					)
					(width 0)
					(fill yes)
				)
			)
		)
		(pad "2" smd custom
			(at 0 0.4445 90)
			(size 0.1524 0.1524)
			(layers "F.Cu" "F.Mask" "F.Paste")
			(net "GND")
			(options
				(clearance outline)
				(anchor circle)
			)
			(primitives
				(gr_poly
					(pts
						(arc
							(start 0.3048 -0.2032)
							(mid 0.275042 -0.275042)
							(end 0.2032 -0.3048)
						)
						(arc
							(start -0.2032 -0.3048)
							(mid -0.275042 -0.275042)
							(end -0.3048 -0.2032)
						)
						(arc
							(start -0.3048 0.2032)
							(mid -0.275042 0.275042)
							(end -0.2032 0.3048)
						)
						(arc
							(start 0.2032 0.3048)
							(mid 0.275042 0.275042)
							(end 0.3048 0.2032)
						)
					)
					(width 0)
					(fill yes)
				)
			)
		)
	)
	(footprint ""
		(layer "F.Cu")
		(at 54.8132 -26.87574)
		(property "Reference" "C28"
			(at 0 0 0)
			(layer "F.SilkS")
			(hide yes)
			(effects
				(font
					(size 1.27 1.27)
				)
			)
		)
		(property "Value" "SCD1U16V2KX-3GP"
			(at 1.1811 -2.7051 0)
			(unlocked yes)
			(layer "F.Fab")
			(hide yes)
			(effects
				(font
					(size 1.016 1.016)
					(thickness 0.1524)
				)
			)
		)
		(property "Device Type" "C402H22"
			(at 1.1811 -4.2291 0)
			(unlocked yes)
			(layer "F.Fab")
			(hide yes)
			(effects
				(font
					(size 1.016 1.016)
					(thickness 0.1524)
				)
			)
		)
		(duplicate_pad_numbers_are_jumpers no)
		(fp_rect
			(start -0.4318 0.9525)
			(end 0.4318 -0.9525)
			(stroke
				(width 0)
				(type default)
			)
			(fill no)
			(layer "F.CrtYd")
		)
		(fp_rect
			(start -0.4318 0.9525)
			(end 0.4318 -0.9525)
			(stroke
				(width 0)
				(type default)
			)
			(fill no)
			(layer "F.Fab")
		)
		(pad "1" smd custom
			(at 0 -0.4445)
			(size 0.1524 0.1524)
			(layers "F.Cu" "F.Mask" "F.Paste")
			(net "P3V3_STBY_B")
			(options
				(clearance outline)
				(anchor circle)
			)
			(primitives
				(gr_poly
					(pts
						(arc
							(start 0.3048 -0.2032)
							(mid 0.275042 -0.275042)
							(end 0.2032 -0.3048)
						)
						(arc
							(start -0.2032 -0.3048)
							(mid -0.275042 -0.275042)
							(end -0.3048 -0.2032)
						)
						(arc
							(start -0.3048 0.2032)
							(mid -0.275042 0.275042)
							(end -0.2032 0.3048)
						)
						(arc
							(start 0.2032 0.3048)
							(mid 0.275042 0.275042)
							(end 0.3048 0.2032)
						)
					)
					(width 0)
					(fill yes)
				)
			)
		)
		(pad "2" smd custom
			(at 0 0.4445)
			(size 0.1524 0.1524)
			(layers "F.Cu" "F.Mask" "F.Paste")
			(net "GND")
			(options
				(clearance outline)
				(anchor circle)
			)
			(primitives
				(gr_poly
					(pts
						(arc
							(start 0.3048 -0.2032)
							(mid 0.275042 -0.275042)
							(end 0.2032 -0.3048)
						)
						(arc
							(start -0.2032 -0.3048)
							(mid -0.275042 -0.275042)
							(end -0.3048 -0.2032)
						)
						(arc
							(start -0.3048 0.2032)
							(mid -0.275042 0.275042)
							(end -0.2032 0.3048)
						)
						(arc
							(start 0.2032 0.3048)
							(mid 0.275042 0.275042)
							(end 0.3048 0.2032)
						)
					)
					(width 0)
					(fill yes)
				)
			)
		)
	)
	(footprint ""
		(layer "F.Cu")
		(at 45.9232 -27.0764 180)
		(property "Reference" "R76"
			(at 0 0 180)
			(layer "F.SilkS")
			(hide yes)
			(effects
				(font
					(size 1.27 1.27)
				)
			)
		)
		(property "Value" "0R2J-2-GP"
			(at 0.064008 -3.993896 180)
			(unlocked yes)
			(layer "F.Fab")
			(hide yes)
			(effects
				(font
					(size 1.016 1.016)
					(thickness 0.1524)
				)
			)
		)
		(property "Device Type" "R402H16"
			(at 0.064008 -5.517896 180)
			(unlocked yes)
			(layer "F.Fab")
			(hide yes)
			(effects
				(font
					(size 1.016 1.016)
					(thickness 0.1524)
				)
			)
		)
		(duplicate_pad_numbers_are_jumpers no)
		(fp_line
			(start 0.508 -0.9398)
			(end -0.508 -0.9398)
			(stroke
				(width 0.1524)
				(type default)
			)
			(layer "F.SilkS")
		)
		(fp_line
			(start -0.508 -0.9398)
			(end -0.508 0.9398)
			(stroke
				(width 0.1524)
				(type default)
			)
			(layer "F.SilkS")
		)
		(fp_rect
			(start -0.508 0.9398)
			(end 0.508 -0.9398)
			(stroke
				(width 0)
				(type default)
			)
			(fill no)
			(layer "F.CrtYd")
		)
		(fp_rect
			(start -0.508 0.9398)
			(end 0.508 -0.9398)
			(stroke
				(width 0)
				(type default)
			)
			(fill no)
			(layer "F.Fab")
		)
		(pad "1" smd custom
			(at 0 -0.4445 180)
			(size 0.1397 0.1397)
			(layers "F.Cu" "F.Mask" "F.Paste")
			(net "SYS_RESET_BTN_B_N")
			(options
				(clearance outline)
				(anchor circle)
			)
			(primitives
				(gr_poly
					(pts
						(arc
							(start -0.1778 -0.2794)
							(mid -0.249642 -0.249642)
							(end -0.2794 -0.1778)
						)
						(arc
							(start -0.2794 0.1778)
							(mid -0.249642 0.249642)
							(end -0.1778 0.2794)
						)
						(arc
							(start 0.1778 0.2794)
							(mid 0.249642 0.249642)
							(end 0.2794 0.1778)
						)
						(arc
							(start 0.2794 -0.1778)
							(mid 0.249642 -0.249642)
							(end 0.1778 -0.2794)
						)
					)
					(width 0)
					(fill yes)
				)
			)
		)
		(pad "2" smd custom
			(at 0 0.4445 180)
			(size 0.1397 0.1397)
			(layers "F.Cu" "F.Mask" "F.Paste")
			(net "SYS_RESET_BTN_B_N_R")
			(options
				(clearance outline)
				(anchor circle)
			)
			(primitives
				(gr_poly
					(pts
						(arc
							(start -0.1778 -0.2794)
							(mid -0.249642 -0.249642)
							(end -0.2794 -0.1778)
						)
						(arc
							(start -0.2794 0.1778)
							(mid -0.249642 0.249642)
							(end -0.1778 0.2794)
						)
						(arc
							(start 0.1778 0.2794)
							(mid 0.249642 0.249642)
							(end 0.2794 0.1778)
						)
						(arc
							(start 0.2794 -0.1778)
							(mid 0.249642 -0.249642)
							(end 0.1778 -0.2794)
						)
					)
					(width 0)
					(fill yes)
				)
			)
		)
	)
	(footprint ""
		(layer "F.Cu")
		(at 26.4922 -6.7818)
		(property "Reference" "C31"
			(at 0 0 0)
			(layer "F.SilkS")
			(hide yes)
			(effects
				(font
					(size 1.27 1.27)
				)
			)
		)
		(property "Value" "SCD1U16V2KX-3GP"
			(at 1.1811 -2.7051 0)
			(unlocked yes)
			(layer "F.Fab")
			(hide yes)
			(effects
				(font
					(size 1.016 1.016)
					(thickness 0.1524)
				)
			)
		)
		(property "Device Type" "C402H22"
			(at 1.1811 -4.2291 0)
			(unlocked yes)
			(layer "F.Fab")
			(hide yes)
			(effects
				(font
					(size 1.016 1.016)
					(thickness 0.1524)
				)
			)
		)
		(duplicate_pad_numbers_are_jumpers no)
		(fp_rect
			(start -0.4318 0.9525)
			(end 0.4318 -0.9525)
			(stroke
				(width 0)
				(type default)
			)
			(fill no)
			(layer "F.CrtYd")
		)
		(fp_rect
			(start -0.4318 0.9525)
			(end 0.4318 -0.9525)
			(stroke
				(width 0)
				(type default)
			)
			(fill no)
			(layer "F.Fab")
		)
		(pad "1" smd custom
			(at 0 -0.4445)
			(size 0.1524 0.1524)
			(layers "F.Cu" "F.Mask" "F.Paste")
			(net "DEBUG_HDR_A_UART_SEL")
			(options
				(clearance outline)
				(anchor circle)
			)
			(primitives
				(gr_poly
					(pts
						(arc
							(start 0.3048 -0.2032)
							(mid 0.275042 -0.275042)
							(end 0.2032 -0.3048)
						)
						(arc
							(start -0.2032 -0.3048)
							(mid -0.275042 -0.275042)
							(end -0.3048 -0.2032)
						)
						(arc
							(start -0.3048 0.2032)
							(mid -0.275042 0.275042)
							(end -0.2032 0.3048)
						)
						(arc
							(start 0.2032 0.3048)
							(mid 0.275042 0.275042)
							(end 0.3048 0.2032)
						)
					)
					(width 0)
					(fill yes)
				)
			)
		)
		(pad "2" smd custom
			(at 0 0.4445)
			(size 0.1524 0.1524)
			(layers "F.Cu" "F.Mask" "F.Paste")
			(net "GND")
			(options
				(clearance outline)
				(anchor circle)
			)
			(primitives
				(gr_poly
					(pts
						(arc
							(start 0.3048 -0.2032)
							(mid 0.275042 -0.275042)
							(end 0.2032 -0.3048)
						)
						(arc
							(start -0.2032 -0.3048)
							(mid -0.275042 -0.275042)
							(end -0.3048 -0.2032)
						)
						(arc
							(start -0.3048 0.2032)
							(mid -0.275042 0.275042)
							(end -0.2032 0.3048)
						)
						(arc
							(start 0.2032 0.3048)
							(mid 0.275042 0.275042)
							(end 0.3048 0.2032)
						)
					)
					(width 0)
					(fill yes)
				)
			)
		)
	)
	(footprint ""
		(layer "F.Cu")
		(at 50.85588 -28.8544 -90)
		(property "Reference" "R51"
			(at 0 0 270)
			(layer "F.SilkS")
			(hide yes)
			(effects
				(font
					(size 1.27 1.27)
				)
			)
		)
		(property "Value" "100KR2F-L1-GP"
			(at 0.064008 -4.679696 270)
			(unlocked yes)
			(layer "F.Fab")
			(hide yes)
			(effects
				(font
					(size 2.54 2.54)
					(thickness 0.381)
				)
			)
		)
		(property "Device Type" "R402H16"
			(at 0.064008 -6.203696 270)
			(unlocked yes)
			(layer "F.Fab")
			(hide yes)
			(effects
				(font
					(size 2.54 2.54)
					(thickness 0.381)
				)
			)
		)
		(duplicate_pad_numbers_are_jumpers no)
		(fp_line
			(start -0.508 -0.9398)
			(end -0.508 0.9398)
			(stroke
				(width 0.1524)
				(type default)
			)
			(layer "F.SilkS")
		)
		(fp_line
			(start 0.508 -0.9398)
			(end -0.508 -0.9398)
			(stroke
				(width 0.1524)
				(type default)
			)
			(layer "F.SilkS")
		)
		(fp_rect
			(start -0.508 0.9398)
			(end 0.508 -0.9398)
			(stroke
				(width 0)
				(type default)
			)
			(fill no)
			(layer "F.CrtYd")
		)
		(fp_rect
			(start -0.508 0.9398)
			(end 0.508 -0.9398)
			(stroke
				(width 0)
				(type default)
			)
			(fill no)
			(layer "F.Fab")
		)
		(pad "1" smd custom
			(at 0 -0.4445 270)
			(size 0.1397 0.1397)
			(layers "F.Cu" "F.Mask" "F.Paste")
			(net "P3V3_STBY_B")
			(options
				(clearance outline)
				(anchor circle)
			)
			(primitives
				(gr_poly
					(pts
						(arc
							(start -0.1778 -0.2794)
							(mid -0.249642 -0.249642)
							(end -0.2794 -0.1778)
						)
						(arc
							(start -0.2794 0.1778)
							(mid -0.249642 0.249642)
							(end -0.1778 0.2794)
						)
						(arc
							(start 0.1778 0.2794)
							(mid 0.249642 0.249642)
							(end 0.2794 0.1778)
						)
						(arc
							(start 0.2794 -0.1778)
							(mid 0.249642 -0.249642)
							(end 0.1778 -0.2794)
						)
					)
					(width 0)
					(fill yes)
				)
			)
		)
		(pad "2" smd custom
			(at 0 0.4445 270)
			(size 0.1397 0.1397)
			(layers "F.Cu" "F.Mask" "F.Paste")
			(net "SYS_RESET_BTN_B")
			(options
				(clearance outline)
				(anchor circle)
			)
			(primitives
				(gr_poly
					(pts
						(arc
							(start -0.1778 -0.2794)
							(mid -0.249642 -0.249642)
							(end -0.2794 -0.1778)
						)
						(arc
							(start -0.2794 0.1778)
							(mid -0.249642 0.249642)
							(end -0.1778 0.2794)
						)
						(arc
							(start 0.1778 0.2794)
							(mid 0.249642 0.249642)
							(end 0.2794 0.1778)
						)
						(arc
							(start 0.2794 -0.1778)
							(mid 0.249642 -0.249642)
							(end 0.1778 -0.2794)
						)
					)
					(width 0)
					(fill yes)
				)
			)
		)
	)
	(footprint ""
		(layer "F.Cu")
		(at 4.4958 -27.7495)
		(property "Reference" "D9"
			(at 0 0 0)
			(layer "F.SilkS")
			(hide yes)
			(effects
				(font
					(size 1.27 1.27)
				)
			)
		)
		(property "Value" "PESD5V0X1UAB-GP"
			(at 0 -4.690618 0)
			(unlocked yes)
			(layer "F.Fab")
			(hide yes)
			(effects
				(font
					(size 1.016 1.016)
					(thickness 0.1524)
				)
			)
		)
		(property "Device Type" "SOD523AKH26"
			(at 0 -6.214618 0)
			(unlocked yes)
			(layer "F.Fab")
			(hide yes)
			(effects
				(font
					(size 1.016 1.016)
					(thickness 0.1524)
				)
			)
		)
		(duplicate_pad_numbers_are_jumpers no)
		(fp_line
			(start -0.5334 -1.4478)
			(end 0.5334 -1.4478)
			(stroke
				(width 0.1524)
				(type default)
			)
			(layer "F.SilkS")
		)
		(fp_line
			(start -0.5334 1.524)
			(end -0.5334 -1.4478)
			(stroke
				(width 0.1524)
				(type default)
			)
			(layer "F.SilkS")
		)
		(fp_line
			(start 0.4064 1.651)
			(end -0.4064 1.651)
			(stroke
				(width 0.4064)
				(type default)
			)
			(layer "F.SilkS")
		)
		(fp_line
			(start 0.5334 -1.4478)
			(end 0.5334 1.524)
			(stroke
				(width 0.1524)
				(type default)
			)
			(layer "F.SilkS")
		)
		(fp_line
			(start 0.5334 1.524)
			(end -0.5334 1.524)
			(stroke
				(width 0.1524)
				(type default)
			)
			(layer "F.SilkS")
		)
		(fp_rect
			(start -0.6096 1.8542)
			(end 0.6096 -1.524)
			(stroke
				(width 0)
				(type default)
			)
			(fill no)
			(layer "F.CrtYd")
		)
		(fp_poly
			(pts
				(xy -0.6096 -1.524) (xy 0.6096 -1.524) (xy 0.6096 1.8542) (xy -0.6096 1.8542)
			)
			(stroke
				(width 0)
				(type default)
			)
			(fill no)
			(layer "F.Fab")
		)
		(pad "A" smd rect
			(at 0 -0.762)
			(size 0.5588 1.016)
			(layers "F.Cu" "F.Mask" "F.Paste")
			(net "GND")
		)
		(pad "K" smd rect
			(at 0 0.762)
			(size 0.5588 1.016)
			(layers "F.Cu" "F.Mask" "F.Paste")
			(net "SYS_RESET_BTN_A")
		)
	)
	(footprint ""
		(layer "F.Cu")
		(at 51.181 -12.827)
		(property "Reference" "R12"
			(at 0 0 0)
			(layer "F.SilkS")
			(hide yes)
			(effects
				(font
					(size 1.27 1.27)
				)
			)
		)
		(property "Value" "0R2J-2-GP"
			(at 0.064008 -4.679696 0)
			(unlocked yes)
			(layer "F.Fab")
			(hide yes)
			(effects
				(font
					(size 2.54 2.54)
					(thickness 0.381)
				)
			)
		)
		(property "Device Type" "R402H16"
			(at 0.064008 -6.203696 0)
			(unlocked yes)
			(layer "F.Fab")
			(hide yes)
			(effects
				(font
					(size 2.54 2.54)
					(thickness 0.381)
				)
			)
		)
		(duplicate_pad_numbers_are_jumpers no)
		(fp_line
			(start -0.508 -0.9398)
			(end -0.508 0.9398)
			(stroke
				(width 0.1524)
				(type default)
			)
			(layer "F.SilkS")
		)
		(fp_line
			(start 0.508 -0.9398)
			(end -0.508 -0.9398)
			(stroke
				(width 0.1524)
				(type default)
			)
			(layer "F.SilkS")
		)
		(fp_rect
			(start -0.508 0.9398)
			(end 0.508 -0.9398)
			(stroke
				(width 0)
				(type default)
			)
			(fill no)
			(layer "F.CrtYd")
		)
		(fp_rect
			(start -0.508 0.9398)
			(end 0.508 -0.9398)
			(stroke
				(width 0)
				(type default)
			)
			(fill no)
			(layer "F.Fab")
		)
		(pad "1" smd custom
			(at 0 -0.4445)
			(size 0.1397 0.1397)
			(layers "F.Cu" "F.Mask" "F.Paste")
			(net "I2C_DEBUG_B_SDA_R")
			(options
				(clearance outline)
				(anchor circle)
			)
			(primitives
				(gr_poly
					(pts
						(arc
							(start -0.1778 -0.2794)
							(mid -0.249642 -0.249642)
							(end -0.2794 -0.1778)
						)
						(arc
							(start -0.2794 0.1778)
							(mid -0.249642 0.249642)
							(end -0.1778 0.2794)
						)
						(arc
							(start 0.1778 0.2794)
							(mid 0.249642 0.249642)
							(end 0.2794 0.1778)
						)
						(arc
							(start 0.2794 -0.1778)
							(mid 0.249642 -0.249642)
							(end 0.1778 -0.2794)
						)
					)
					(width 0)
					(fill yes)
				)
			)
		)
		(pad "2" smd custom
			(at 0 0.4445)
			(size 0.1397 0.1397)
			(layers "F.Cu" "F.Mask" "F.Paste")
			(net "I2C_DEBUG_B_SDA_L")
			(options
				(clearance outline)
				(anchor circle)
			)
			(primitives
				(gr_poly
					(pts
						(arc
							(start -0.1778 -0.2794)
							(mid -0.249642 -0.249642)
							(end -0.2794 -0.1778)
						)
						(arc
							(start -0.2794 0.1778)
							(mid -0.249642 0.249642)
							(end -0.1778 0.2794)
						)
						(arc
							(start 0.1778 0.2794)
							(mid 0.249642 0.249642)
							(end 0.2794 0.1778)
						)
						(arc
							(start 0.2794 -0.1778)
							(mid 0.249642 -0.249642)
							(end 0.1778 -0.2794)
						)
					)
					(width 0)
					(fill yes)
				)
			)
		)
	)
	(footprint ""
		(layer "F.Cu")
		(at 47.359316 -72.650096 180)
		(property "Reference" "C9"
			(at 0 0 180)
			(layer "F.SilkS")
			(hide yes)
			(effects
				(font
					(size 1.27 1.27)
				)
			)
		)
		(property "Value" "SC1U16V3KX-5GP"
			(at 0 -3.5052 180)
			(unlocked yes)
			(layer "F.Fab")
			(hide yes)
			(effects
				(font
					(size 2.54 2.54)
					(thickness 0.381)
				)
			)
		)
		(property "Device Type" "C603H36"
			(at 0 -5.0292 180)
			(unlocked yes)
			(layer "F.Fab")
			(hide yes)
			(effects
				(font
					(size 2.54 2.54)
					(thickness 0.381)
				)
			)
		)
		(duplicate_pad_numbers_are_jumpers no)
		(fp_line
			(start 0.508 0)
			(end -0.508 0)
			(stroke
				(width 0.2032)
				(type default)
			)
			(layer "F.SilkS")
		)
		(fp_rect
			(start -0.5842 1.3335)
			(end 0.5842 -1.3335)
			(stroke
				(width 0)
				(type default)
			)
			(fill no)
			(layer "F.CrtYd")
		)
		(fp_rect
			(start -0.5842 1.3335)
			(end 0.5842 -1.3335)
			(stroke
				(width 0)
				(type default)
			)
			(fill no)
			(layer "F.Fab")
		)
		(pad "1" smd custom
			(at 0 -0.762 180)
			(size 0.2159 0.2159)
			(layers "F.Cu" "F.Mask" "F.Paste")
			(net "P5V_USB_B")
			(options
				(clearance outline)
				(anchor circle)
			)
			(primitives
				(gr_poly
					(pts
						(arc
							(start -0.3302 -0.4318)
							(mid -0.402042 -0.402042)
							(end -0.4318 -0.3302)
						)
						(arc
							(start -0.4318 0.3302)
							(mid -0.402042 0.402042)
							(end -0.3302 0.4318)
						)
						(arc
							(start 0.3302 0.4318)
							(mid 0.402042 0.402042)
							(end 0.4318 0.3302)
						)
						(arc
							(start 0.4318 -0.3302)
							(mid 0.402042 -0.402042)
							(end 0.3302 -0.4318)
						)
					)
					(width 0)
					(fill yes)
				)
			)
		)
		(pad "2" smd custom
			(at 0 0.762 180)
			(size 0.2159 0.2159)
			(layers "F.Cu" "F.Mask" "F.Paste")
			(net "GND")
			(options
				(clearance outline)
				(anchor circle)
			)
			(primitives
				(gr_poly
					(pts
						(arc
							(start -0.3302 -0.4318)
							(mid -0.402042 -0.402042)
							(end -0.4318 -0.3302)
						)
						(arc
							(start -0.4318 0.3302)
							(mid -0.402042 0.402042)
							(end -0.3302 0.4318)
						)
						(arc
							(start 0.3302 0.4318)
							(mid 0.402042 0.402042)
							(end 0.4318 0.3302)
						)
						(arc
							(start 0.4318 -0.3302)
							(mid 0.402042 -0.402042)
							(end 0.3302 -0.4318)
						)
					)
					(width 0)
					(fill yes)
				)
			)
		)
	)
	(footprint ""
		(layer "F.Cu")
		(at 7.9756 -17.9832 -90)
		(property "Reference" "R55"
			(at 0 0 270)
			(layer "F.SilkS")
			(hide yes)
			(effects
				(font
					(size 1.27 1.27)
				)
			)
		)
		(property "Value" "20KR2F-L-GP"
			(at 0.064008 -3.993896 270)
			(unlocked yes)
			(layer "F.Fab")
			(hide yes)
			(effects
				(font
					(size 1.016 1.016)
					(thickness 0.1524)
				)
			)
		)
		(property "Device Type" "R402H16"
			(at 0.064008 -5.517896 270)
			(unlocked yes)
			(layer "F.Fab")
			(hide yes)
			(effects
				(font
					(size 1.016 1.016)
					(thickness 0.1524)
				)
			)
		)
		(duplicate_pad_numbers_are_jumpers no)
		(fp_line
			(start -0.508 -0.9398)
			(end -0.508 0.9398)
			(stroke
				(width 0.1524)
				(type default)
			)
			(layer "F.SilkS")
		)
		(fp_line
			(start 0.508 -0.9398)
			(end -0.508 -0.9398)
			(stroke
				(width 0.1524)
				(type default)
			)
			(layer "F.SilkS")
		)
		(fp_rect
			(start -0.508 0.9398)
			(end 0.508 -0.9398)
			(stroke
				(width 0)
				(type default)
			)
			(fill no)
			(layer "F.CrtYd")
		)
		(fp_rect
			(start -0.508 0.9398)
			(end 0.508 -0.9398)
			(stroke
				(width 0)
				(type default)
			)
			(fill no)
			(layer "F.Fab")
		)
		(pad "1" smd custom
			(at 0 -0.4445 270)
			(size 0.1397 0.1397)
			(layers "F.Cu" "F.Mask" "F.Paste")
			(net "P3V3_STBY_A")
			(options
				(clearance outline)
				(anchor circle)
			)
			(primitives
				(gr_poly
					(pts
						(arc
							(start -0.1778 -0.2794)
							(mid -0.249642 -0.249642)
							(end -0.2794 -0.1778)
						)
						(arc
							(start -0.2794 0.1778)
							(mid -0.249642 0.249642)
							(end -0.1778 0.2794)
						)
						(arc
							(start 0.1778 0.2794)
							(mid 0.249642 0.249642)
							(end 0.2794 0.1778)
						)
						(arc
							(start 0.2794 -0.1778)
							(mid 0.249642 -0.249642)
							(end 0.1778 -0.2794)
						)
					)
					(width 0)
					(fill yes)
				)
			)
		)
		(pad "2" smd custom
			(at 0 0.4445 270)
			(size 0.1397 0.1397)
			(layers "F.Cu" "F.Mask" "F.Paste")
			(net "I2C_DEBUG_A_SDA_L")
			(options
				(clearance outline)
				(anchor circle)
			)
			(primitives
				(gr_poly
					(pts
						(arc
							(start -0.1778 -0.2794)
							(mid -0.249642 -0.249642)
							(end -0.2794 -0.1778)
						)
						(arc
							(start -0.2794 0.1778)
							(mid -0.249642 0.249642)
							(end -0.1778 0.2794)
						)
						(arc
							(start 0.1778 0.2794)
							(mid 0.249642 0.249642)
							(end 0.2794 0.1778)
						)
						(arc
							(start 0.2794 -0.1778)
							(mid 0.249642 -0.249642)
							(end 0.1778 -0.2794)
						)
					)
					(width 0)
					(fill yes)
				)
			)
		)
	)
	(footprint ""
		(layer "F.Cu")
		(at 7.112 -20.447 -90)
		(property "Reference" "U9"
			(at 0 0 270)
			(layer "F.SilkS")
			(hide yes)
			(effects
				(font
					(size 1.27 1.27)
				)
			)
		)
		(property "Value" "PCA9306DCTT-GP"
			(at 0 -11.6332 270)
			(unlocked yes)
			(layer "F.Fab")
			(hide yes)
			(effects
				(font
					(size 1.016 1.016)
					(thickness 0.1524)
				)
			)
		)
		(property "Device Type" "SSOIC8H52"
			(at 0 -13.1572 270)
			(unlocked yes)
			(layer "F.Fab")
			(hide yes)
			(effects
				(font
					(size 1.016 1.016)
					(thickness 0.1524)
				)
			)
		)
		(duplicate_pad_numbers_are_jumpers no)
		(fp_line
			(start -1.524 0.5842)
			(end -1.524 2.286)
			(stroke
				(width 0.508)
				(type default)
			)
			(layer "F.SilkS")
		)
		(fp_line
			(start 1.0668 0.5842)
			(end -1.524 0.5842)
			(stroke
				(width 0.1524)
				(type default)
			)
			(layer "F.SilkS")
		)
		(fp_line
			(start -1.397 0)
			(end -1.7018 0.3048)
			(stroke
				(width 0.1524)
				(type default)
			)
			(layer "F.SilkS")
		)
		(fp_line
			(start -1.397 0)
			(end -1.7018 -0.3048)
			(stroke
				(width 0.1524)
				(type default)
			)
			(layer "F.SilkS")
		)
		(fp_line
			(start -1.7018 -0.5842)
			(end -1.7018 2.286)
			(stroke
				(width 0.1524)
				(type default)
			)
			(layer "F.SilkS")
		)
		(fp_line
			(start -1.7018 -0.5842)
			(end 1.0668 -0.5842)
			(stroke
				(width 0.1524)
				(type default)
			)
			(layer "F.SilkS")
		)
		(fp_line
			(start 1.0668 -0.5842)
			(end 1.0668 0.5842)
			(stroke
				(width 0.1524)
				(type default)
			)
			(layer "F.SilkS")
		)
		(fp_poly
			(pts
				(xy -1.1684 -0.5842) (xy 1.0668 -0.5842) (xy 1.0668 0.5842) (xy -1.1684 0.5842)
			)
			(stroke
				(width 0)
				(type default)
			)
			(fill yes)
			(layer "F.SilkS")
		)
		(fp_poly
			(pts
				(xy -1.778 2.54) (xy 1.778 2.54) (xy 1.778 -2.54) (xy -1.778 -2.54)
			)
			(stroke
				(width 0)
				(type default)
			)
			(fill no)
			(layer "F.CrtYd")
		)
		(fp_poly
			(pts
				(xy -1.778 -2.54) (xy 1.778 -2.54) (xy 1.778 2.54) (xy -1.778 2.54)
			)
			(stroke
				(width 0)
				(type default)
			)
			(fill no)
			(layer "F.Fab")
		)
		(pad "1" smd rect
			(at -0.97536 1.6256 270)
			(size 0.3556 1.524)
			(layers "F.Cu" "F.Mask" "F.Paste")
			(net "GND")
		)
		(pad "2" smd rect
			(at -0.32512 1.6256 270)
			(size 0.3556 1.524)
			(layers "F.Cu" "F.Mask" "F.Paste")
			(net "P3V3_STBY_A")
		)
		(pad "3" smd rect
			(at 0.32512 1.6256 270)
			(size 0.3556 1.524)
			(layers "F.Cu" "F.Mask" "F.Paste")
			(net "I2C_DEBUG_A_SCL")
		)
		(pad "4" smd rect
			(at 0.97536 1.6256 270)
			(size 0.3556 1.524)
			(layers "F.Cu" "F.Mask" "F.Paste")
			(net "I2C_DEBUG_A_SDA")
		)
		(pad "5" smd rect
			(at 0.97536 -1.6256 270)
			(size 0.3556 1.524)
			(layers "F.Cu" "F.Mask" "F.Paste")
			(net "I2C_DEBUG_A_SDA_L")
		)
		(pad "6" smd rect
			(at 0.32512 -1.6256 270)
			(size 0.3556 1.524)
			(layers "F.Cu" "F.Mask" "F.Paste")
			(net "I2C_DEBUG_A_SCL_L")
		)
		(pad "7" smd rect
			(at -0.32512 -1.6256 270)
			(size 0.3556 1.524)
			(layers "F.Cu" "F.Mask" "F.Paste")
			(net "P3V3_STBY_A")
		)
		(pad "8" smd rect
			(at -0.97536 -1.6256 270)
			(size 0.3556 1.524)
			(layers "F.Cu" "F.Mask" "F.Paste")
			(net "DEBUG_CARD_A_PRSNT")
		)
	)
	(footprint ""
		(layer "F.Cu")
		(at 13.3096 -44.1452 180)
		(property "Reference" "R34"
			(at 0 0 180)
			(layer "F.SilkS")
			(hide yes)
			(effects
				(font
					(size 1.27 1.27)
				)
			)
		)
		(property "Value" "4K7R2F-GP"
			(at 0.064008 -4.679696 180)
			(unlocked yes)
			(layer "F.Fab")
			(hide yes)
			(effects
				(font
					(size 2.54 2.54)
					(thickness 0.381)
				)
			)
		)
		(property "Device Type" "R402H16"
			(at 0.064008 -6.203696 180)
			(unlocked yes)
			(layer "F.Fab")
			(hide yes)
			(effects
				(font
					(size 2.54 2.54)
					(thickness 0.381)
				)
			)
		)
		(duplicate_pad_numbers_are_jumpers no)
		(fp_line
			(start 0.508 -0.9398)
			(end -0.508 -0.9398)
			(stroke
				(width 0.1524)
				(type default)
			)
			(layer "F.SilkS")
		)
		(fp_line
			(start -0.508 -0.9398)
			(end -0.508 0.9398)
			(stroke
				(width 0.1524)
				(type default)
			)
			(layer "F.SilkS")
		)
		(fp_rect
			(start -0.508 0.9398)
			(end 0.508 -0.9398)
			(stroke
				(width 0)
				(type default)
			)
			(fill no)
			(layer "F.CrtYd")
		)
		(fp_rect
			(start -0.508 0.9398)
			(end 0.508 -0.9398)
			(stroke
				(width 0)
				(type default)
			)
			(fill no)
			(layer "F.Fab")
		)
		(pad "1" smd custom
			(at 0 -0.4445 180)
			(size 0.1397 0.1397)
			(layers "F.Cu" "F.Mask" "F.Paste")
			(net "P3V3_STBY_A")
			(options
				(clearance outline)
				(anchor circle)
			)
			(primitives
				(gr_poly
					(pts
						(arc
							(start -0.1778 -0.2794)
							(mid -0.249642 -0.249642)
							(end -0.2794 -0.1778)
						)
						(arc
							(start -0.2794 0.1778)
							(mid -0.249642 0.249642)
							(end -0.1778 0.2794)
						)
						(arc
							(start 0.1778 0.2794)
							(mid 0.249642 0.249642)
							(end 0.2794 0.1778)
						)
						(arc
							(start 0.2794 -0.1778)
							(mid 0.249642 -0.249642)
							(end 0.1778 -0.2794)
						)
					)
					(width 0)
					(fill yes)
				)
			)
		)
		(pad "2" smd custom
			(at 0 0.4445 180)
			(size 0.1397 0.1397)
			(layers "F.Cu" "F.Mask" "F.Paste")
			(net "TEMP_1_A2")
			(options
				(clearance outline)
				(anchor circle)
			)
			(primitives
				(gr_poly
					(pts
						(arc
							(start -0.1778 -0.2794)
							(mid -0.249642 -0.249642)
							(end -0.2794 -0.1778)
						)
						(arc
							(start -0.2794 0.1778)
							(mid -0.249642 0.249642)
							(end -0.1778 0.2794)
						)
						(arc
							(start 0.1778 0.2794)
							(mid 0.249642 0.249642)
							(end 0.2794 0.1778)
						)
						(arc
							(start 0.2794 -0.1778)
							(mid 0.249642 -0.249642)
							(end 0.1778 -0.2794)
						)
					)
					(width 0)
					(fill yes)
				)
			)
		)
	)
	(footprint ""
		(layer "F.Cu")
		(at 42.545 -14.478 -90)
		(property "Reference" "U14"
			(at 0 0 270)
			(layer "F.SilkS")
			(hide yes)
			(effects
				(font
					(size 1.27 1.27)
				)
			)
		)
		(property "Value" "SNLVC1G126DCKR-GP"
			(at -2.3368 -8.6868 270)
			(unlocked yes)
			(layer "F.Fab")
			(hide yes)
			(effects
				(font
					(size 1.016 1.016)
					(thickness 0.1524)
				)
			)
		)
		(property "Device Type" "SC70-5H44"
			(at -2.3114 -10.414 270)
			(unlocked yes)
			(layer "F.Fab")
			(hide yes)
			(effects
				(font
					(size 1.016 1.016)
					(thickness 0.1524)
				)
			)
		)
		(duplicate_pad_numbers_are_jumpers no)
		(fp_line
			(start -1.27 1.7018)
			(end -1.27 -1.7018)
			(stroke
				(width 0.1524)
				(type default)
			)
			(layer "F.SilkS")
		)
		(fp_line
			(start 1.27 1.7018)
			(end -1.27 1.7018)
			(stroke
				(width 0.1524)
				(type default)
			)
			(layer "F.SilkS")
		)
		(fp_line
			(start -1.27 -1.7018)
			(end 1.27 -1.7018)
			(stroke
				(width 0.1524)
				(type default)
			)
			(layer "F.SilkS")
		)
		(fp_line
			(start 1.27 -1.7018)
			(end 1.27 1.7018)
			(stroke
				(width 0.1524)
				(type default)
			)
			(layer "F.SilkS")
		)
		(fp_line
			(start 0.6604 -1.8034)
			(end 1.3843 -1.8034)
			(stroke
				(width 0.3302)
				(type default)
			)
			(layer "F.SilkS")
		)
		(fp_line
			(start 1.3843 -1.8034)
			(end 1.3843 -1.1176)
			(stroke
				(width 0.3302)
				(type default)
			)
			(layer "F.SilkS")
		)
		(fp_rect
			(start -1.524 1.9558)
			(end 1.524 -1.9558)
			(stroke
				(width 0)
				(type default)
			)
			(fill no)
			(layer "F.CrtYd")
		)
		(fp_poly
			(pts
				(xy -1.524 -1.9558) (xy 1.524 -1.9558) (xy 1.524 1.9558) (xy -1.524 1.9558)
			)
			(stroke
				(width 0)
				(type default)
			)
			(fill no)
			(layer "F.Fab")
		)
		(pad "1" smd rect
			(at 0.65024 -0.8255 270)
			(size 0.4064 1.2192)
			(layers "F.Cu" "F.Mask" "F.Paste")
			(net "DEBUG_CARD_B_PRSNT")
		)
		(pad "2" smd rect
			(at 0 -0.8255 270)
			(size 0.4064 1.2192)
			(layers "F.Cu" "F.Mask" "F.Paste")
			(net "UART_DEBUG_B_RX")
		)
		(pad "3" smd rect
			(at -0.65024 -0.8255 270)
			(size 0.4064 1.2192)
			(layers "F.Cu" "F.Mask" "F.Paste")
			(net "GND")
		)
		(pad "4" smd rect
			(at -0.65024 0.8255 270)
			(size 0.4064 1.2192)
			(layers "F.Cu" "F.Mask" "F.Paste")
			(net "UART_B_RX")
		)
		(pad "5" smd rect
			(at 0.65024 0.8255 270)
			(size 0.4064 1.2192)
			(layers "F.Cu" "F.Mask" "F.Paste")
			(net "P3V3_STBY_B")
		)
	)
	(footprint ""
		(layer "F.Cu")
		(at 52.4002 -26.797 90)
		(property "Reference" "U16"
			(at 0 0 90)
			(layer "F.SilkS")
			(hide yes)
			(effects
				(font
					(size 1.27 1.27)
				)
			)
		)
		(property "Value" "SN74LVC1G08DCKR-GP"
			(at -2.3368 -8.6868 90)
			(unlocked yes)
			(layer "F.Fab")
			(hide yes)
			(effects
				(font
					(size 1.016 1.016)
					(thickness 0.1524)
				)
			)
		)
		(property "Device Type" "SC70-5H44"
			(at -2.3114 -10.414 90)
			(unlocked yes)
			(layer "F.Fab")
			(hide yes)
			(effects
				(font
					(size 1.016 1.016)
					(thickness 0.1524)
				)
			)
		)
		(duplicate_pad_numbers_are_jumpers no)
		(fp_line
			(start 1.3843 -1.8034)
			(end 1.3843 -1.1176)
			(stroke
				(width 0.3302)
				(type default)
			)
			(layer "F.SilkS")
		)
		(fp_line
			(start 0.6604 -1.8034)
			(end 1.3843 -1.8034)
			(stroke
				(width 0.3302)
				(type default)
			)
			(layer "F.SilkS")
		)
		(fp_line
			(start 1.27 -1.7018)
			(end 1.27 1.7018)
			(stroke
				(width 0.1524)
				(type default)
			)
			(layer "F.SilkS")
		)
		(fp_line
			(start -1.27 -1.7018)
			(end 1.27 -1.7018)
			(stroke
				(width 0.1524)
				(type default)
			)
			(layer "F.SilkS")
		)
		(fp_line
			(start 1.27 1.7018)
			(end -1.27 1.7018)
			(stroke
				(width 0.1524)
				(type default)
			)
			(layer "F.SilkS")
		)
		(fp_line
			(start -1.27 1.7018)
			(end -1.27 -1.7018)
			(stroke
				(width 0.1524)
				(type default)
			)
			(layer "F.SilkS")
		)
		(fp_rect
			(start -1.524 1.9558)
			(end 1.524 -1.9558)
			(stroke
				(width 0)
				(type default)
			)
			(fill no)
			(layer "F.CrtYd")
		)
		(fp_poly
			(pts
				(xy -1.524 -1.9558) (xy 1.524 -1.9558) (xy 1.524 1.9558) (xy -1.524 1.9558)
			)
			(stroke
				(width 0)
				(type default)
			)
			(fill no)
			(layer "F.Fab")
		)
		(pad "1" smd rect
			(at 0.65024 -0.8255 90)
			(size 0.4064 1.2192)
			(layers "F.Cu" "F.Mask" "F.Paste")
			(net "SYS_RESET_BTN_B_N_R")
		)
		(pad "2" smd rect
			(at 0 -0.8255 90)
			(size 0.4064 1.2192)
			(layers "F.Cu" "F.Mask" "F.Paste")
			(net "DEBUG_RST_B_BTN_N")
		)
		(pad "3" smd rect
			(at -0.65024 -0.8255 90)
			(size 0.4064 1.2192)
			(layers "F.Cu" "F.Mask" "F.Paste")
			(net "GND")
		)
		(pad "4" smd rect
			(at -0.65024 0.8255 90)
			(size 0.4064 1.2192)
			(layers "F.Cu" "F.Mask" "F.Paste")
			(net "SYS_RESET_BTN_B_N")
		)
		(pad "5" smd rect
			(at 0.65024 0.8255 90)
			(size 0.4064 1.2192)
			(layers "F.Cu" "F.Mask" "F.Paste")
			(net "P3V3_STBY_B")
		)
	)
	(footprint ""
		(layer "F.Cu")
		(at 2.671826 -55.22849 90)
		(property "Reference" "TP1"
			(at 0 0 90)
			(layer "F.SilkS")
			(hide yes)
			(effects
				(font
					(size 1.27 1.27)
				)
			)
		)
		(property "Value" "TPAD28-2-GP"
			(at -0.0127 -2.3495 90)
			(unlocked yes)
			(layer "F.Fab")
			(hide yes)
			(effects
				(font
					(size 2.54 2.54)
					(thickness 0.381)
				)
			)
		)
		(property "Device Type" "TPAD28"
			(at -0.0127 -3.8735 90)
			(unlocked yes)
			(layer "F.Fab")
			(hide yes)
			(effects
				(font
					(size 2.54 2.54)
					(thickness 0.381)
				)
			)
		)
		(duplicate_pad_numbers_are_jumpers no)
		(fp_poly
			(pts
				(arc
					(start 0 0.3556)
					(mid 0 -0.3556)
					(end 0 0.3556)
				)
			)
			(stroke
				(width 0)
				(type default)
			)
			(fill no)
			(layer "F.CrtYd")
		)
		(fp_poly
			(pts
				(arc
					(start 0 0.6096)
					(mid 0 -0.6096)
					(end 0 0.6096)
				)
			)
			(stroke
				(width 0)
				(type default)
			)
			(fill no)
			(layer "F.Fab")
		)
		(pad "1" smd circle
			(at 0 0 90)
			(size 0.7112 0.7112)
			(layers "F.Cu" "F.Mask" "F.Paste")
			(net "DEBUG_USB_A_DN")
		)
	)
	(footprint ""
		(layer "F.Cu")
		(at 12.769088 -72.840088 180)
		(property "Reference" "R15"
			(at 0 0 180)
			(layer "F.SilkS")
			(hide yes)
			(effects
				(font
					(size 1.27 1.27)
				)
			)
		)
		(property "Value" "200R2J-L1-GP"
			(at 0.064008 -4.679696 180)
			(unlocked yes)
			(layer "F.Fab")
			(hide yes)
			(effects
				(font
					(size 2.54 2.54)
					(thickness 0.381)
				)
			)
		)
		(property "Device Type" "R402H16"
			(at 0.064008 -6.203696 180)
			(unlocked yes)
			(layer "F.Fab")
			(hide yes)
			(effects
				(font
					(size 2.54 2.54)
					(thickness 0.381)
				)
			)
		)
		(duplicate_pad_numbers_are_jumpers no)
		(fp_line
			(start 0.508 -0.9398)
			(end -0.508 -0.9398)
			(stroke
				(width 0.1524)
				(type default)
			)
			(layer "F.SilkS")
		)
		(fp_line
			(start -0.508 -0.9398)
			(end -0.508 0.9398)
			(stroke
				(width 0.1524)
				(type default)
			)
			(layer "F.SilkS")
		)
		(fp_rect
			(start -0.508 0.9398)
			(end 0.508 -0.9398)
			(stroke
				(width 0)
				(type default)
			)
			(fill no)
			(layer "F.CrtYd")
		)
		(fp_rect
			(start -0.508 0.9398)
			(end 0.508 -0.9398)
			(stroke
				(width 0)
				(type default)
			)
			(fill no)
			(layer "F.Fab")
		)
		(pad "1" smd custom
			(at 0 -0.4445 180)
			(size 0.1397 0.1397)
			(layers "F.Cu" "F.Mask" "F.Paste")
			(net "P5V_USB_A")
			(options
				(clearance outline)
				(anchor circle)
			)
			(primitives
				(gr_poly
					(pts
						(arc
							(start -0.1778 -0.2794)
							(mid -0.249642 -0.249642)
							(end -0.2794 -0.1778)
						)
						(arc
							(start -0.2794 0.1778)
							(mid -0.249642 0.249642)
							(end -0.1778 0.2794)
						)
						(arc
							(start 0.1778 0.2794)
							(mid 0.249642 0.249642)
							(end 0.2794 0.1778)
						)
						(arc
							(start 0.2794 -0.1778)
							(mid 0.249642 -0.249642)
							(end 0.1778 -0.2794)
						)
					)
					(width 0)
					(fill yes)
				)
			)
		)
		(pad "2" smd custom
			(at 0 0.4445 180)
			(size 0.1397 0.1397)
			(layers "F.Cu" "F.Mask" "F.Paste")
			(net "PWR_BTN_LED_A_R")
			(options
				(clearance outline)
				(anchor circle)
			)
			(primitives
				(gr_poly
					(pts
						(arc
							(start -0.1778 -0.2794)
							(mid -0.249642 -0.249642)
							(end -0.2794 -0.1778)
						)
						(arc
							(start -0.2794 0.1778)
							(mid -0.249642 0.249642)
							(end -0.1778 0.2794)
						)
						(arc
							(start 0.1778 0.2794)
							(mid 0.249642 0.249642)
							(end 0.2794 0.1778)
						)
						(arc
							(start 0.2794 -0.1778)
							(mid 0.249642 -0.249642)
							(end 0.1778 -0.2794)
						)
					)
					(width 0)
					(fill yes)
				)
			)
		)
	)
	(footprint ""
		(layer "F.Cu")
		(at 48.387 -22.86 90)
		(property "Reference" "R78"
			(at 0 0 90)
			(layer "F.SilkS")
			(hide yes)
			(effects
				(font
					(size 1.27 1.27)
				)
			)
		)
		(property "Value" "4K7R2F-GP"
			(at 0.064008 -3.993896 90)
			(unlocked yes)
			(layer "F.Fab")
			(hide yes)
			(effects
				(font
					(size 1.016 1.016)
					(thickness 0.1524)
				)
			)
		)
		(property "Device Type" "R402H16"
			(at 0.064008 -5.517896 90)
			(unlocked yes)
			(layer "F.Fab")
			(hide yes)
			(effects
				(font
					(size 1.016 1.016)
					(thickness 0.1524)
				)
			)
		)
		(duplicate_pad_numbers_are_jumpers no)
		(fp_line
			(start 0.508 -0.9398)
			(end -0.508 -0.9398)
			(stroke
				(width 0.1524)
				(type default)
			)
			(layer "F.SilkS")
		)
		(fp_line
			(start -0.508 -0.9398)
			(end -0.508 0.9398)
			(stroke
				(width 0.1524)
				(type default)
			)
			(layer "F.SilkS")
		)
		(fp_rect
			(start -0.508 0.9398)
			(end 0.508 -0.9398)
			(stroke
				(width 0)
				(type default)
			)
			(fill no)
			(layer "F.CrtYd")
		)
		(fp_rect
			(start -0.508 0.9398)
			(end 0.508 -0.9398)
			(stroke
				(width 0)
				(type default)
			)
			(fill no)
			(layer "F.Fab")
		)
		(pad "1" smd custom
			(at 0 -0.4445 90)
			(size 0.1397 0.1397)
			(layers "F.Cu" "F.Mask" "F.Paste")
			(net "P3V3_STBY_B")
			(options
				(clearance outline)
				(anchor circle)
			)
			(primitives
				(gr_poly
					(pts
						(arc
							(start -0.1778 -0.2794)
							(mid -0.249642 -0.249642)
							(end -0.2794 -0.1778)
						)
						(arc
							(start -0.2794 0.1778)
							(mid -0.249642 0.249642)
							(end -0.1778 0.2794)
						)
						(arc
							(start 0.1778 0.2794)
							(mid 0.249642 0.249642)
							(end 0.2794 0.1778)
						)
						(arc
							(start 0.2794 -0.1778)
							(mid 0.249642 -0.249642)
							(end 0.1778 -0.2794)
						)
					)
					(width 0)
					(fill yes)
				)
			)
		)
		(pad "2" smd custom
			(at 0 0.4445 90)
			(size 0.1397 0.1397)
			(layers "F.Cu" "F.Mask" "F.Paste")
			(net "DEBUG_RST_B_BTN_N")
			(options
				(clearance outline)
				(anchor circle)
			)
			(primitives
				(gr_poly
					(pts
						(arc
							(start -0.1778 -0.2794)
							(mid -0.249642 -0.249642)
							(end -0.2794 -0.1778)
						)
						(arc
							(start -0.2794 0.1778)
							(mid -0.249642 0.249642)
							(end -0.1778 0.2794)
						)
						(arc
							(start 0.1778 0.2794)
							(mid 0.249642 0.249642)
							(end 0.2794 0.1778)
						)
						(arc
							(start 0.2794 -0.1778)
							(mid 0.249642 -0.249642)
							(end 0.1778 -0.2794)
						)
					)
					(width 0)
					(fill yes)
				)
			)
		)
	)
	(footprint ""
		(layer "F.Cu")
		(at 47.900082 -43.999912 90)
		(property "Reference" "LED2"
			(at 0 0 90)
			(layer "F.SilkS")
			(hide yes)
			(effects
				(font
					(size 1.27 1.27)
				)
			)
		)
		(property "Value" "LED-Y-167-GP"
			(at 3.3274 -0.4572 90)
			(unlocked yes)
			(layer "F.Fab")
			(hide yes)
			(effects
				(font
					(size 1.016 1.016)
					(thickness 0.1524)
				)
			)
		)
		(property "Device Type" "LED-100-4035-1A2KH274"
			(at 3.3274 -1.9812 90)
			(unlocked yes)
			(layer "F.Fab")
			(hide yes)
			(effects
				(font
					(size 1.016 1.016)
					(thickness 0.1524)
				)
			)
		)
		(duplicate_pad_numbers_are_jumpers no)
		(fp_line
			(start 1.905 -0.254)
			(end 1.397 0.254)
			(stroke
				(width 0.1524)
				(type default)
			)
			(layer "F.SilkS")
		)
		(fp_line
			(start 1.397 -0.254)
			(end 1.397 -0.762)
			(stroke
				(width 0.1524)
				(type default)
			)
			(layer "F.SilkS")
		)
		(fp_line
			(start 0.889 -0.254)
			(end 1.905 -0.254)
			(stroke
				(width 0.1524)
				(type default)
			)
			(layer "F.SilkS")
		)
		(fp_line
			(start 1.397 0.254)
			(end 0.889 -0.254)
			(stroke
				(width 0.1524)
				(type default)
			)
			(layer "F.SilkS")
		)
		(fp_line
			(start 1.397 0.254)
			(end 1.397 0.762)
			(stroke
				(width 0.1524)
				(type default)
			)
			(layer "F.SilkS")
		)
		(fp_line
			(start 0.889 0.254)
			(end 1.905 0.254)
			(stroke
				(width 0.1524)
				(type default)
			)
			(layer "F.SilkS")
		)
		(fp_line
			(start 1.427988 1.7526)
			(end 0.685546 1.7526)
			(stroke
				(width 0.1524)
				(type default)
			)
			(layer "F.SilkS")
		)
		(fp_line
			(start -0.685546 1.7526)
			(end -1.427988 1.7526)
			(stroke
				(width 0.1524)
				(type default)
			)
			(layer "F.SilkS")
		)
		(fp_arc
			(start 0.685546 1.7526)
			(mid 0 2.108377)
			(end -0.685546 1.7526)
			(stroke
				(width 0.1524)
				(type default)
			)
			(layer "F.SilkS")
		)
		(fp_arc
			(start -1.427988 1.7526)
			(mid 0 -2.260698)
			(end 1.427988 1.7526)
			(stroke
				(width 0.1524)
				(type default)
			)
			(layer "F.SilkS")
		)
		(fp_circle
			(center 0 -1.27)
			(end 0 -0.3302)
			(stroke
				(width 0.3048)
				(type default)
			)
			(fill no)
			(layer "F.SilkS")
		)
		(fp_circle
			(center 0 1.27)
			(end 0 2.2098)
			(stroke
				(width 0.3048)
				(type default)
			)
			(fill no)
			(layer "F.SilkS")
		)
		(fp_poly
			(pts
				(arc
					(start -1.334516 1.4986)
					(mid 0 -2.006673)
					(end 1.334516 1.4986)
				)
			)
			(stroke
				(width 0)
				(type default)
			)
			(fill no)
			(layer "F.CrtYd")
		)
		(fp_poly
			(pts
				(arc
					(start 0.806704 2.0066)
					(mid 0 2.362406)
					(end -0.806704 2.0066)
				)
				(arc
					(start -1.515618 2.0066)
					(mid -1.123616 -2.249673)
					(end 2.5146 -0.00635)
				)
				(arc
					(start 2.006854 -0.00635)
					(mid -0.824269 -1.829777)
					(end -1.334516 1.498854)
				)
				(arc
					(start 1.334516 1.498854)
					(mid 1.829775 0.824269)
					(end 2.006854 0.00635)
				)
				(arc
					(start 2.5146 0.00635)
					(mid 2.249622 1.12359)
					(end 1.515618 2.0066)
				)
			)
			(stroke
				(width 0)
				(type default)
			)
			(fill no)
			(layer "F.CrtYd")
		)
		(fp_poly
			(pts
				(arc
					(start 0.806704 2.0066)
					(mid 0 2.362406)
					(end -0.806704 2.0066)
				)
				(arc
					(start -1.515618 2.0066)
					(mid 0 -2.514665)
					(end 1.515618 2.0066)
				)
			)
			(stroke
				(width 0)
				(type default)
			)
			(fill no)
			(layer "F.Fab")
		)
		(pad "1A" thru_hole circle
			(at 0 -1.27 90)
			(size 1.1684 1.1684)
			(drill 0.8128)
			(layers "*.Cu" "*.Mask")
			(remove_unused_layers no)
			(net "SYS_FAULT_B_R")
			(clearance 0.1778)
			(thermal_gap 0.1778)
		)
		(pad "2K" thru_hole circle
			(at 0 1.27 90)
			(size 1.1684 1.1684)
			(drill 0.8128)
			(layers "*.Cu" "*.Mask")
			(remove_unused_layers no)
			(net "FAULT_LED_B")
			(clearance 0.1778)
			(thermal_gap 0.1778)
		)
	)
	(footprint ""
		(layer "F.Cu")
		(at 14.8336 -20.193 90)
		(property "Reference" "U2"
			(at 0 0 90)
			(layer "F.SilkS")
			(hide yes)
			(effects
				(font
					(size 1.27 1.27)
				)
			)
		)
		(property "Value" "TCA9555PWR-GP"
			(at 0 -6.9342 90)
			(unlocked yes)
			(layer "F.Fab")
			(hide yes)
			(effects
				(font
					(size 1.016 1.016)
					(thickness 0.1524)
				)
			)
		)
		(property "Device Type" "TSOIC24H48"
			(at 0 -8.5852 90)
			(unlocked yes)
			(layer "F.Fab")
			(hide yes)
			(effects
				(font
					(size 1.016 1.016)
					(thickness 0.1524)
				)
			)
		)
		(duplicate_pad_numbers_are_jumpers no)
		(fp_line
			(start 3.81 -1.397)
			(end 3.81 1.397)
			(stroke
				(width 0.1524)
				(type default)
			)
			(layer "F.SilkS")
		)
		(fp_line
			(start -4.2291 -1.397)
			(end 3.81 -1.397)
			(stroke
				(width 0.1524)
				(type default)
			)
			(layer "F.SilkS")
		)
		(fp_line
			(start -4.2291 -0.8001)
			(end -3.429 0)
			(stroke
				(width 0.1524)
				(type default)
			)
			(layer "F.SilkS")
		)
		(fp_line
			(start -3.429 0)
			(end -4.2291 0.8001)
			(stroke
				(width 0.1524)
				(type default)
			)
			(layer "F.SilkS")
		)
		(fp_line
			(start 3.81 1.397)
			(end -4.2291 1.397)
			(stroke
				(width 0.1524)
				(type default)
			)
			(layer "F.SilkS")
		)
		(fp_line
			(start -4.22656 3.81)
			(end -4.2291 1.397)
			(stroke
				(width 0.508)
				(type default)
			)
			(layer "F.SilkS")
		)
		(fp_line
			(start -4.2291 3.937)
			(end -4.2291 -1.397)
			(stroke
				(width 0.1524)
				(type default)
			)
			(layer "F.SilkS")
		)
		(fp_poly
			(pts
				(xy -3.90652 -1.8542) (xy 3.90652 -1.8542) (xy 3.90652 1.8542) (xy -3.90652 1.8542)
			)
			(stroke
				(width 0)
				(type default)
			)
			(fill yes)
			(layer "F.SilkS")
		)
		(fp_poly
			(pts
				(xy -4.2164 3.81) (xy 4.2164 3.81) (xy 4.22656 -3.81) (xy -4.2164 -3.81)
			)
			(stroke
				(width 0)
				(type default)
			)
			(fill no)
			(layer "F.CrtYd")
		)
		(fp_poly
			(pts
				(xy -4.22656 -3.81) (xy 4.22656 -3.81) (xy 4.22656 3.81) (xy -4.22656 3.81)
			)
			(stroke
				(width 0)
				(type default)
			)
			(fill no)
			(layer "F.Fab")
		)
		(pad "1" smd rect
			(at -3.57632 2.8194 90)
			(size 0.3556 1.524)
			(layers "F.Cu" "F.Mask" "F.Paste")
			(net "IO_EXP_A_RESET#_FLT")
		)
		(pad "2" smd rect
			(at -2.92608 2.8194 90)
			(size 0.3556 1.524)
			(layers "F.Cu" "F.Mask" "F.Paste")
			(net "TCA9555_A_A1")
		)
		(pad "3" smd rect
			(at -2.27584 2.8194 90)
			(size 0.3556 1.524)
			(layers "F.Cu" "F.Mask" "F.Paste")
			(net "TCA9555_A_A2")
		)
		(pad "4" smd rect
			(at -1.6256 2.8194 90)
			(size 0.3556 1.524)
			(layers "F.Cu" "F.Mask" "F.Paste")
			(net "Net_67")
		)
		(pad "5" smd rect
			(at -0.97536 2.8194 90)
			(size 0.3556 1.524)
			(layers "F.Cu" "F.Mask" "F.Paste")
			(net "Net_66")
		)
		(pad "6" smd rect
			(at -0.32512 2.8194 90)
			(size 0.3556 1.524)
			(layers "F.Cu" "F.Mask" "F.Paste")
			(net "Net_65")
		)
		(pad "7" smd rect
			(at 0.32512 2.8194 90)
			(size 0.3556 1.524)
			(layers "F.Cu" "F.Mask" "F.Paste")
			(net "Net_64")
		)
		(pad "8" smd rect
			(at 0.97536 2.8194 90)
			(size 0.3556 1.524)
			(layers "F.Cu" "F.Mask" "F.Paste")
			(net "Net_63")
		)
		(pad "9" smd rect
			(at 1.6256 2.8194 90)
			(size 0.3556 1.524)
			(layers "F.Cu" "F.Mask" "F.Paste")
			(net "Net_62")
		)
		(pad "10" smd rect
			(at 2.27584 2.8194 90)
			(size 0.3556 1.524)
			(layers "F.Cu" "F.Mask" "F.Paste")
			(net "Net_61")
		)
		(pad "11" smd rect
			(at 2.92608 2.8194 90)
			(size 0.3556 1.524)
			(layers "F.Cu" "F.Mask" "F.Paste")
			(net "Net_60")
		)
		(pad "12" smd rect
			(at 3.57632 2.8194 90)
			(size 0.3556 1.524)
			(layers "F.Cu" "F.Mask" "F.Paste")
			(net "GND")
		)
		(pad "13" smd rect
			(at 3.57632 -2.8194 90)
			(size 0.3556 1.524)
			(layers "F.Cu" "F.Mask" "F.Paste")
			(net "DEBUG_RST_A_BTN_N")
		)
		(pad "14" smd rect
			(at 2.92608 -2.8194 90)
			(size 0.3556 1.524)
			(layers "F.Cu" "F.Mask" "F.Paste")
			(net "Net_59")
		)
		(pad "15" smd rect
			(at 2.27584 -2.8194 90)
			(size 0.3556 1.524)
			(layers "F.Cu" "F.Mask" "F.Paste")
			(net "Net_58")
		)
		(pad "16" smd rect
			(at 1.6256 -2.8194 90)
			(size 0.3556 1.524)
			(layers "F.Cu" "F.Mask" "F.Paste")
			(net "Net_57")
		)
		(pad "17" smd rect
			(at 0.97536 -2.8194 90)
			(size 0.3556 1.524)
			(layers "F.Cu" "F.Mask" "F.Paste")
			(net "Net_56")
		)
		(pad "18" smd rect
			(at 0.32512 -2.8194 90)
			(size 0.3556 1.524)
			(layers "F.Cu" "F.Mask" "F.Paste")
			(net "Net_55")
		)
		(pad "19" smd rect
			(at -0.32512 -2.8194 90)
			(size 0.3556 1.524)
			(layers "F.Cu" "F.Mask" "F.Paste")
			(net "Net_54")
		)
		(pad "20" smd rect
			(at -0.97536 -2.8194 90)
			(size 0.3556 1.524)
			(layers "F.Cu" "F.Mask" "F.Paste")
			(net "DEBUG_HDR_A_UART_SEL")
		)
		(pad "21" smd rect
			(at -1.6256 -2.8194 90)
			(size 0.3556 1.524)
			(layers "F.Cu" "F.Mask" "F.Paste")
			(net "TCA9555_A_A0")
		)
		(pad "22" smd rect
			(at -2.27584 -2.8194 90)
			(size 0.3556 1.524)
			(layers "F.Cu" "F.Mask" "F.Paste")
			(net "I2C_DEBUG_A_SCL_R")
		)
		(pad "23" smd rect
			(at -2.92608 -2.8194 90)
			(size 0.3556 1.524)
			(layers "F.Cu" "F.Mask" "F.Paste")
			(net "I2C_DEBUG_A_SDA_R")
		)
		(pad "24" smd rect
			(at -3.57632 -2.8194 90)
			(size 0.3556 1.524)
			(layers "F.Cu" "F.Mask" "F.Paste")
			(net "P3V3_STBY_A")
		)
	)
	(footprint ""
		(layer "F.Cu")
		(at 6.0706 -17.9832 90)
		(property "Reference" "R56"
			(at 0 0 90)
			(layer "F.SilkS")
			(hide yes)
			(effects
				(font
					(size 1.27 1.27)
				)
			)
		)
		(property "Value" "20KR2F-L-GP"
			(at 0.064008 -3.993896 90)
			(unlocked yes)
			(layer "F.Fab")
			(hide yes)
			(effects
				(font
					(size 1.016 1.016)
					(thickness 0.1524)
				)
			)
		)
		(property "Device Type" "R402H16"
			(at 0.064008 -5.517896 90)
			(unlocked yes)
			(layer "F.Fab")
			(hide yes)
			(effects
				(font
					(size 1.016 1.016)
					(thickness 0.1524)
				)
			)
		)
		(duplicate_pad_numbers_are_jumpers no)
		(fp_line
			(start 0.508 -0.9398)
			(end -0.508 -0.9398)
			(stroke
				(width 0.1524)
				(type default)
			)
			(layer "F.SilkS")
		)
		(fp_line
			(start -0.508 -0.9398)
			(end -0.508 0.9398)
			(stroke
				(width 0.1524)
				(type default)
			)
			(layer "F.SilkS")
		)
		(fp_rect
			(start -0.508 0.9398)
			(end 0.508 -0.9398)
			(stroke
				(width 0)
				(type default)
			)
			(fill no)
			(layer "F.CrtYd")
		)
		(fp_rect
			(start -0.508 0.9398)
			(end 0.508 -0.9398)
			(stroke
				(width 0)
				(type default)
			)
			(fill no)
			(layer "F.Fab")
		)
		(pad "1" smd custom
			(at 0 -0.4445 90)
			(size 0.1397 0.1397)
			(layers "F.Cu" "F.Mask" "F.Paste")
			(net "P3V3_STBY_A")
			(options
				(clearance outline)
				(anchor circle)
			)
			(primitives
				(gr_poly
					(pts
						(arc
							(start -0.1778 -0.2794)
							(mid -0.249642 -0.249642)
							(end -0.2794 -0.1778)
						)
						(arc
							(start -0.2794 0.1778)
							(mid -0.249642 0.249642)
							(end -0.1778 0.2794)
						)
						(arc
							(start 0.1778 0.2794)
							(mid 0.249642 0.249642)
							(end 0.2794 0.1778)
						)
						(arc
							(start 0.2794 -0.1778)
							(mid 0.249642 -0.249642)
							(end 0.1778 -0.2794)
						)
					)
					(width 0)
					(fill yes)
				)
			)
		)
		(pad "2" smd custom
			(at 0 0.4445 90)
			(size 0.1397 0.1397)
			(layers "F.Cu" "F.Mask" "F.Paste")
			(net "I2C_DEBUG_A_SCL_L")
			(options
				(clearance outline)
				(anchor circle)
			)
			(primitives
				(gr_poly
					(pts
						(arc
							(start -0.1778 -0.2794)
							(mid -0.249642 -0.249642)
							(end -0.2794 -0.1778)
						)
						(arc
							(start -0.2794 0.1778)
							(mid -0.249642 0.249642)
							(end -0.1778 0.2794)
						)
						(arc
							(start 0.1778 0.2794)
							(mid 0.249642 0.249642)
							(end 0.2794 0.1778)
						)
						(arc
							(start 0.2794 -0.1778)
							(mid 0.249642 -0.249642)
							(end 0.1778 -0.2794)
						)
					)
					(width 0)
					(fill yes)
				)
			)
		)
	)
	(footprint ""
		(layer "F.Cu")
		(at 53.052218 -71.995792 90)
		(property "Reference" "R46"
			(at 0 0 90)
			(layer "F.SilkS")
			(hide yes)
			(effects
				(font
					(size 1.27 1.27)
				)
			)
		)
		(property "Value" "1MR2F-GP"
			(at 0.064008 -4.679696 90)
			(unlocked yes)
			(layer "F.Fab")
			(hide yes)
			(effects
				(font
					(size 2.54 2.54)
					(thickness 0.381)
				)
			)
		)
		(property "Device Type" "R402H16"
			(at 0.064008 -6.203696 90)
			(unlocked yes)
			(layer "F.Fab")
			(hide yes)
			(effects
				(font
					(size 2.54 2.54)
					(thickness 0.381)
				)
			)
		)
		(duplicate_pad_numbers_are_jumpers no)
		(fp_line
			(start 0.508 -0.9398)
			(end -0.508 -0.9398)
			(stroke
				(width 0.1524)
				(type default)
			)
			(layer "F.SilkS")
		)
		(fp_line
			(start -0.508 -0.9398)
			(end -0.508 0.9398)
			(stroke
				(width 0.1524)
				(type default)
			)
			(layer "F.SilkS")
		)
		(fp_rect
			(start -0.508 0.9398)
			(end 0.508 -0.9398)
			(stroke
				(width 0)
				(type default)
			)
			(fill no)
			(layer "F.CrtYd")
		)
		(fp_rect
			(start -0.508 0.9398)
			(end 0.508 -0.9398)
			(stroke
				(width 0)
				(type default)
			)
			(fill no)
			(layer "F.Fab")
		)
		(pad "1" smd custom
			(at 0 -0.4445 90)
			(size 0.1397 0.1397)
			(layers "F.Cu" "F.Mask" "F.Paste")
			(net "USB_CONN_B_GND")
			(options
				(clearance outline)
				(anchor circle)
			)
			(primitives
				(gr_poly
					(pts
						(arc
							(start -0.1778 -0.2794)
							(mid -0.249642 -0.249642)
							(end -0.2794 -0.1778)
						)
						(arc
							(start -0.2794 0.1778)
							(mid -0.249642 0.249642)
							(end -0.1778 0.2794)
						)
						(arc
							(start 0.1778 0.2794)
							(mid 0.249642 0.249642)
							(end 0.2794 0.1778)
						)
						(arc
							(start 0.2794 -0.1778)
							(mid 0.249642 -0.249642)
							(end 0.1778 -0.2794)
						)
					)
					(width 0)
					(fill yes)
				)
			)
		)
		(pad "2" smd custom
			(at 0 0.4445 90)
			(size 0.1397 0.1397)
			(layers "F.Cu" "F.Mask" "F.Paste")
			(net "GND")
			(options
				(clearance outline)
				(anchor circle)
			)
			(primitives
				(gr_poly
					(pts
						(arc
							(start -0.1778 -0.2794)
							(mid -0.249642 -0.249642)
							(end -0.2794 -0.1778)
						)
						(arc
							(start -0.2794 0.1778)
							(mid -0.249642 0.249642)
							(end -0.1778 0.2794)
						)
						(arc
							(start 0.1778 0.2794)
							(mid 0.249642 0.249642)
							(end 0.2794 0.1778)
						)
						(arc
							(start 0.2794 -0.1778)
							(mid 0.249642 -0.249642)
							(end 0.1778 -0.2794)
						)
					)
					(width 0)
					(fill yes)
				)
			)
		)
	)
	(footprint ""
		(layer "F.Cu")
		(at 8.199882 -59.99988 90)
		(property "Reference" "USB1"
			(at 0 0 90)
			(layer "F.SilkS")
			(hide yes)
			(effects
				(font
					(size 1.27 1.27)
				)
			)
		)
		(property "Value" "SKT-USB13-208-GP"
			(at -9.1821 -7.5692 90)
			(unlocked yes)
			(layer "F.Fab")
			(hide yes)
			(effects
				(font
					(size 1.016 1.016)
					(thickness 0.1524)
				)
			)
		)
		(property "Device Type" "SKT-USB13-148074-5"
			(at -9.1821 -9.0932 90)
			(unlocked yes)
			(layer "F.Fab")
			(hide yes)
			(effects
				(font
					(size 1.016 1.016)
					(thickness 0.1524)
				)
			)
		)
		(duplicate_pad_numbers_are_jumpers no)
		(fp_line
			(start 8.0137 -3.9497)
			(end 8.0137 3.9497)
			(stroke
				(width 0.1524)
				(type default)
			)
			(layer "F.SilkS")
		)
		(fp_line
			(start -8.0137 -3.9497)
			(end 8.0137 -3.9497)
			(stroke
				(width 0.1524)
				(type default)
			)
			(layer "F.SilkS")
		)
		(fp_line
			(start 8.0137 3.9497)
			(end -8.0137 3.9497)
			(stroke
				(width 0.1524)
				(type default)
			)
			(layer "F.SilkS")
		)
		(fp_line
			(start -8.0137 3.9497)
			(end -8.0137 -3.9497)
			(stroke
				(width 0.1524)
				(type default)
			)
			(layer "F.SilkS")
		)
		(fp_arc
			(start 4.854956 1.256792)
			(mid 8.078491 2.349096)
			(end 4.686808 2.064512)
			(stroke
				(width 0.3048)
				(type default)
			)
			(layer "F.SilkS")
		)
		(fp_arc
			(start -4.854956 1.256792)
			(mid -3.12974 1.318917)
			(end -4.686808 2.064512)
			(stroke
				(width 0.3048)
				(type default)
			)
			(layer "F.SilkS")
		)
		(fp_arc
			(start 4.686808 2.064512)
			(mid 3.129699 1.318908)
			(end 4.854956 1.256792)
			(stroke
				(width 0.3048)
				(type default)
			)
			(layer "F.SilkS")
		)
		(fp_arc
			(start -4.686808 2.064512)
			(mid -8.078519 2.349102)
			(end -4.854956 1.256792)
			(stroke
				(width 0.3048)
				(type default)
			)
			(layer "F.SilkS")
		)
		(fp_circle
			(center 6.400038 -1.999996)
			(end 6.400038 -0.285496)
			(stroke
				(width 0.3048)
				(type default)
			)
			(fill no)
			(layer "F.SilkS")
		)
		(fp_circle
			(center -6.400038 -1.999996)
			(end -6.400038 -0.285496)
			(stroke
				(width 0.3048)
				(type default)
			)
			(fill no)
			(layer "F.SilkS")
		)
		(fp_circle
			(center 3.50012 -0.999998)
			(end 3.50012 -0.110998)
			(stroke
				(width 0.3048)
				(type default)
			)
			(fill no)
			(layer "F.SilkS")
		)
		(fp_circle
			(center 0.999998 -0.999998)
			(end 0.999998 -0.110998)
			(stroke
				(width 0.3048)
				(type default)
			)
			(fill no)
			(layer "F.SilkS")
		)
		(fp_circle
			(center -0.999998 -0.999998)
			(end -0.999998 -0.110998)
			(stroke
				(width 0.3048)
				(type default)
			)
			(fill no)
			(layer "F.SilkS")
		)
		(fp_circle
			(center -3.50012 -0.999998)
			(end -3.50012 -0.110998)
			(stroke
				(width 0.3048)
				(type default)
			)
			(fill no)
			(layer "F.SilkS")
		)
		(fp_circle
			(center 1.999996 1.500124)
			(end 1.999996 2.389124)
			(stroke
				(width 0.3048)
				(type default)
			)
			(fill no)
			(layer "F.SilkS")
		)
		(fp_circle
			(center 0 1.500124)
			(end 0 2.389124)
			(stroke
				(width 0.3048)
				(type default)
			)
			(fill no)
			(layer "F.SilkS")
		)
		(fp_circle
			(center -1.999996 1.500124)
			(end -1.999996 2.389124)
			(stroke
				(width 0.3048)
				(type default)
			)
			(fill no)
			(layer "F.SilkS")
		)
		(fp_rect
			(start -7.4041 3.6957)
			(end 7.4041 -3.6957)
			(stroke
				(width 0)
				(type default)
			)
			(fill no)
			(layer "F.CrtYd")
		)
		(fp_poly
			(pts
				(xy -8.2677 4.2037) (xy -8.2677 -4.2037) (xy 8.2677 -4.2037) (xy 8.2677 -0.00635) (xy 7.4041 -0.00635)
				(xy 7.4041 -3.6957) (xy -7.4041 -3.6957) (xy -7.4041 3.6957) (xy 7.4041 3.6957) (xy 7.4041 0.00635)
				(xy 8.2677 0.00635) (xy 8.2677 4.2037)
			)
			(stroke
				(width 0)
				(type default)
			)
			(fill no)
			(layer "F.CrtYd")
		)
		(fp_rect
			(start -8.2677 4.2037)
			(end 8.2677 -4.2037)
			(stroke
				(width 0)
				(type default)
			)
			(fill no)
			(layer "F.Fab")
		)
		(pad "1" thru_hole circle
			(at 3.50012 -0.999998 90)
			(size 1.0668 1.0668)
			(drill 0.7112)
			(layers "*.Cu" "*.Mask")
			(remove_unused_layers no)
			(net "P5V_VBUS_A")
			(clearance 0.1778)
			(thermal_gap 0.1778)
		)
		(pad "2" thru_hole circle
			(at 0.999998 -0.999998 90)
			(size 1.0668 1.0668)
			(drill 0.7112)
			(layers "*.Cu" "*.Mask")
			(remove_unused_layers no)
			(net "DEBUG_USB_A_DN")
			(clearance 0.1778)
			(thermal_gap 0.1778)
		)
		(pad "3" thru_hole circle
			(at -0.999998 -0.999998 90)
			(size 1.0668 1.0668)
			(drill 0.7112)
			(layers "*.Cu" "*.Mask")
			(remove_unused_layers no)
			(net "DEBUG_USB_A_DP")
			(clearance 0.1778)
			(thermal_gap 0.1778)
		)
		(pad "4" thru_hole circle
			(at -3.50012 -0.999998 90)
			(size 1.0668 1.0668)
			(drill 0.7112)
			(layers "*.Cu" "*.Mask")
			(remove_unused_layers no)
			(net "GND")
			(clearance 0.1778)
			(thermal_gap 0.1778)
		)
		(pad "5" thru_hole circle
			(at -3.999992 1.500124 90)
			(size 1.0668 1.0668)
			(drill 0.7112)
			(layers "*.Cu" "*.Mask")
			(remove_unused_layers no)
			(net "I2C_DEBUG_A_SCL")
			(clearance 0.1778)
			(thermal_gap 0.1778)
		)
		(pad "6" thru_hole circle
			(at -1.999996 1.500124 90)
			(size 1.0668 1.0668)
			(drill 0.7112)
			(layers "*.Cu" "*.Mask")
			(remove_unused_layers no)
			(net "I2C_DEBUG_A_SDA")
			(clearance 0.1778)
			(thermal_gap 0.1778)
		)
		(pad "7" thru_hole circle
			(at 0 1.500124 90)
			(size 1.0668 1.0668)
			(drill 0.7112)
			(layers "*.Cu" "*.Mask")
			(remove_unused_layers no)
			(net "DEBUG_CARD_A_PRSNT")
			(clearance 0.1778)
			(thermal_gap 0.1778)
		)
		(pad "8" thru_hole circle
			(at 1.999996 1.500124 90)
			(size 1.0668 1.0668)
			(drill 0.7112)
			(layers "*.Cu" "*.Mask")
			(remove_unused_layers no)
			(net "UART_DEBUG_A_TX")
			(clearance 0.1778)
			(thermal_gap 0.1778)
		)
		(pad "9" thru_hole circle
			(at 3.999992 1.500124 90)
			(size 1.0668 1.0668)
			(drill 0.7112)
			(layers "*.Cu" "*.Mask")
			(remove_unused_layers no)
			(net "UART_DEBUG_A_RX")
			(clearance 0.1778)
			(thermal_gap 0.1778)
		)
		(pad "10" thru_hole circle
			(at 6.400038 -1.999996 90)
			(size 2.7178 2.7178)
			(drill 2.3114)
			(layers "*.Cu" "*.Mask")
			(remove_unused_layers no)
			(net "USB_CONN_A_GND")
			(clearance 0.1524)
			(thermal_gap 0.1524)
		)
		(pad "11" thru_hole circle
			(at -6.400038 -1.999996 90)
			(size 2.7178 2.7178)
			(drill 2.3114)
			(layers "*.Cu" "*.Mask")
			(remove_unused_layers no)
			(net "USB_CONN_A_GND")
			(clearance 0.1524)
			(thermal_gap 0.1524)
		)
		(pad "12" thru_hole circle
			(at 6.400038 1.999996 90)
			(size 2.7178 2.7178)
			(drill 2.3114)
			(layers "*.Cu" "*.Mask")
			(remove_unused_layers no)
			(net "USB_CONN_A_GND")
			(clearance 0.1524)
			(thermal_gap 0.1524)
		)
		(pad "13" thru_hole circle
			(at -6.400038 1.999996 90)
			(size 2.7178 2.7178)
			(drill 2.3114)
			(layers "*.Cu" "*.Mask")
			(remove_unused_layers no)
			(net "USB_CONN_A_GND")
			(clearance 0.1524)
			(thermal_gap 0.1524)
		)
		(zone
			(layer "F.Cu")
			(hatch none 0.5)
			(connect_pads
				(clearance 0)
			)
			(min_thickness 0.25)
			(keepout
				(tracks not_allowed)
				(vias allowed)
				(pads allowed)
				(copperpour not_allowed)
				(footprints allowed)
			)
			(placement
				(enabled no)
				(sheetname "")
			)
			(fill
				(thermal_gap 0.5)
				(thermal_bridge_width 0.5)
				(island_removal_mode 0)
			)
			(polygon
				(pts
					(xy 5.359908 -65.099946) (xy 11.039856 -65.099946) (xy 11.039856 -66.199766) (xy 5.359908 -66.199766)
				)
			)
		)
		(zone
			(layer "F.Cu")
			(hatch none 0.5)
			(connect_pads
				(clearance 0)
			)
			(min_thickness 0.25)
			(keepout
				(tracks not_allowed)
				(vias allowed)
				(pads allowed)
				(copperpour not_allowed)
				(footprints allowed)
			)
			(placement
				(enabled no)
				(sheetname "")
			)
			(fill
				(thermal_gap 0.5)
				(thermal_bridge_width 0.5)
				(island_removal_mode 0)
			)
			(polygon
				(pts
					(xy 5.359908 -53.799994) (xy 11.039856 -53.799994) (xy 11.039856 -54.899814) (xy 5.359908 -54.899814)
				)
			)
		)
		(zone
			(layer "F.Cu")
			(hatch none 0.5)
			(connect_pads
				(clearance 0)
			)
			(min_thickness 0.25)
			(keepout
				(tracks allowed)
				(vias not_allowed)
				(pads allowed)
				(copperpour not_allowed)
				(footprints allowed)
			)
			(placement
				(enabled no)
				(sheetname "")
			)
			(fill
				(thermal_gap 0.5)
				(thermal_bridge_width 0.5)
				(island_removal_mode 0)
			)
			(polygon
				(pts
					(xy 11.039856 -65.099946) (xy 11.039856 -66.199766) (xy 5.359908 -66.199766) (xy 5.359908 -65.099946)
				)
			)
		)
		(zone
			(layer "F.Cu")
			(hatch none 0.5)
			(connect_pads
				(clearance 0)
			)
			(min_thickness 0.25)
			(keepout
				(tracks allowed)
				(vias not_allowed)
				(pads allowed)
				(copperpour not_allowed)
				(footprints allowed)
			)
			(placement
				(enabled no)
				(sheetname "")
			)
			(fill
				(thermal_gap 0.5)
				(thermal_bridge_width 0.5)
				(island_removal_mode 0)
			)
			(polygon
				(pts
					(xy 11.039856 -53.799994) (xy 11.039856 -54.899814) (xy 5.359908 -54.899814) (xy 5.359908 -53.799994)
				)
			)
		)
	)
	(footprint ""
		(layer "F.Cu")
		(at 55.753 -13.9446 180)
		(property "Reference" "R68"
			(at 0 0 180)
			(layer "F.SilkS")
			(hide yes)
			(effects
				(font
					(size 1.27 1.27)
				)
			)
		)
		(property "Value" "4K7R2F-GP"
			(at 0.064008 -3.993896 180)
			(unlocked yes)
			(layer "F.Fab")
			(hide yes)
			(effects
				(font
					(size 1.016 1.016)
					(thickness 0.1524)
				)
			)
		)
		(property "Device Type" "R402H16"
			(at 0.064008 -5.517896 180)
			(unlocked yes)
			(layer "F.Fab")
			(hide yes)
			(effects
				(font
					(size 1.016 1.016)
					(thickness 0.1524)
				)
			)
		)
		(duplicate_pad_numbers_are_jumpers no)
		(fp_line
			(start 0.508 -0.9398)
			(end -0.508 -0.9398)
			(stroke
				(width 0.1524)
				(type default)
			)
			(layer "F.SilkS")
		)
		(fp_line
			(start -0.508 -0.9398)
			(end -0.508 0.9398)
			(stroke
				(width 0.1524)
				(type default)
			)
			(layer "F.SilkS")
		)
		(fp_rect
			(start -0.508 0.9398)
			(end 0.508 -0.9398)
			(stroke
				(width 0)
				(type default)
			)
			(fill no)
			(layer "F.CrtYd")
		)
		(fp_rect
			(start -0.508 0.9398)
			(end 0.508 -0.9398)
			(stroke
				(width 0)
				(type default)
			)
			(fill no)
			(layer "F.Fab")
		)
		(pad "1" smd custom
			(at 0 -0.4445 180)
			(size 0.1397 0.1397)
			(layers "F.Cu" "F.Mask" "F.Paste")
			(net "P3V3_STBY_B")
			(options
				(clearance outline)
				(anchor circle)
			)
			(primitives
				(gr_poly
					(pts
						(arc
							(start -0.1778 -0.2794)
							(mid -0.249642 -0.249642)
							(end -0.2794 -0.1778)
						)
						(arc
							(start -0.2794 0.1778)
							(mid -0.249642 0.249642)
							(end -0.1778 0.2794)
						)
						(arc
							(start 0.1778 0.2794)
							(mid 0.249642 0.249642)
							(end 0.2794 0.1778)
						)
						(arc
							(start 0.2794 -0.1778)
							(mid 0.249642 -0.249642)
							(end 0.1778 -0.2794)
						)
					)
					(width 0)
					(fill yes)
				)
			)
		)
		(pad "2" smd custom
			(at 0 0.4445 180)
			(size 0.1397 0.1397)
			(layers "F.Cu" "F.Mask" "F.Paste")
			(net "IO_EXP_B_RESET#_FLT")
			(options
				(clearance outline)
				(anchor circle)
			)
			(primitives
				(gr_poly
					(pts
						(arc
							(start -0.1778 -0.2794)
							(mid -0.249642 -0.249642)
							(end -0.2794 -0.1778)
						)
						(arc
							(start -0.2794 0.1778)
							(mid -0.249642 0.249642)
							(end -0.1778 0.2794)
						)
						(arc
							(start 0.1778 0.2794)
							(mid 0.249642 0.249642)
							(end 0.2794 0.1778)
						)
						(arc
							(start 0.2794 -0.1778)
							(mid 0.249642 -0.249642)
							(end 0.1778 -0.2794)
						)
					)
					(width 0)
					(fill yes)
				)
			)
		)
	)
	(footprint ""
		(layer "F.Cu")
		(at 33.4518 -6.096 90)
		(property "Reference" "R20"
			(at 0 0 90)
			(layer "F.SilkS")
			(hide yes)
			(effects
				(font
					(size 1.27 1.27)
				)
			)
		)
		(property "Value" "0R2J-2-GP"
			(at 0.064008 -3.993896 90)
			(unlocked yes)
			(layer "F.Fab")
			(hide yes)
			(effects
				(font
					(size 1.016 1.016)
					(thickness 0.1524)
				)
			)
		)
		(property "Device Type" "R402H16"
			(at 0.064008 -5.517896 90)
			(unlocked yes)
			(layer "F.Fab")
			(hide yes)
			(effects
				(font
					(size 1.016 1.016)
					(thickness 0.1524)
				)
			)
		)
		(duplicate_pad_numbers_are_jumpers no)
		(fp_line
			(start 0.508 -0.9398)
			(end -0.508 -0.9398)
			(stroke
				(width 0.1524)
				(type default)
			)
			(layer "F.SilkS")
		)
		(fp_line
			(start -0.508 -0.9398)
			(end -0.508 0.9398)
			(stroke
				(width 0.1524)
				(type default)
			)
			(layer "F.SilkS")
		)
		(fp_rect
			(start -0.508 0.9398)
			(end 0.508 -0.9398)
			(stroke
				(width 0)
				(type default)
			)
			(fill no)
			(layer "F.CrtYd")
		)
		(fp_rect
			(start -0.508 0.9398)
			(end 0.508 -0.9398)
			(stroke
				(width 0)
				(type default)
			)
			(fill no)
			(layer "F.Fab")
		)
		(pad "1" smd custom
			(at 0 -0.4445 90)
			(size 0.1397 0.1397)
			(layers "F.Cu" "F.Mask" "F.Paste")
			(net "D_FLIP_PRE_B#")
			(options
				(clearance outline)
				(anchor circle)
			)
			(primitives
				(gr_poly
					(pts
						(arc
							(start -0.1778 -0.2794)
							(mid -0.249642 -0.249642)
							(end -0.2794 -0.1778)
						)
						(arc
							(start -0.2794 0.1778)
							(mid -0.249642 0.249642)
							(end -0.1778 0.2794)
						)
						(arc
							(start 0.1778 0.2794)
							(mid 0.249642 0.249642)
							(end 0.2794 0.1778)
						)
						(arc
							(start 0.2794 -0.1778)
							(mid 0.249642 -0.249642)
							(end 0.1778 -0.2794)
						)
					)
					(width 0)
					(fill yes)
				)
			)
		)
		(pad "2" smd custom
			(at 0 0.4445 90)
			(size 0.1397 0.1397)
			(layers "F.Cu" "F.Mask" "F.Paste")
			(net "P3V3_STBY_B")
			(options
				(clearance outline)
				(anchor circle)
			)
			(primitives
				(gr_poly
					(pts
						(arc
							(start -0.1778 -0.2794)
							(mid -0.249642 -0.249642)
							(end -0.2794 -0.1778)
						)
						(arc
							(start -0.2794 0.1778)
							(mid -0.249642 0.249642)
							(end -0.1778 0.2794)
						)
						(arc
							(start 0.1778 0.2794)
							(mid 0.249642 0.249642)
							(end 0.2794 0.1778)
						)
						(arc
							(start 0.2794 -0.1778)
							(mid 0.249642 -0.249642)
							(end 0.1778 -0.2794)
						)
					)
					(width 0)
					(fill yes)
				)
			)
		)
	)
	(footprint ""
		(layer "F.Cu")
		(at 8.5598 -30.4292)
		(property "Reference" "R75"
			(at 0 0 0)
			(layer "F.SilkS")
			(hide yes)
			(effects
				(font
					(size 1.27 1.27)
				)
			)
		)
		(property "Value" "0R2J-2-GP"
			(at 0.064008 -3.993896 0)
			(unlocked yes)
			(layer "F.Fab")
			(hide yes)
			(effects
				(font
					(size 1.016 1.016)
					(thickness 0.1524)
				)
			)
		)
		(property "Device Type" "R402H16"
			(at 0.064008 -5.517896 0)
			(unlocked yes)
			(layer "F.Fab")
			(hide yes)
			(effects
				(font
					(size 1.016 1.016)
					(thickness 0.1524)
				)
			)
		)
		(duplicate_pad_numbers_are_jumpers no)
		(fp_line
			(start -0.508 -0.9398)
			(end -0.508 0.9398)
			(stroke
				(width 0.1524)
				(type default)
			)
			(layer "F.SilkS")
		)
		(fp_line
			(start 0.508 -0.9398)
			(end -0.508 -0.9398)
			(stroke
				(width 0.1524)
				(type default)
			)
			(layer "F.SilkS")
		)
		(fp_rect
			(start -0.508 0.9398)
			(end 0.508 -0.9398)
			(stroke
				(width 0)
				(type default)
			)
			(fill no)
			(layer "F.CrtYd")
		)
		(fp_rect
			(start -0.508 0.9398)
			(end 0.508 -0.9398)
			(stroke
				(width 0)
				(type default)
			)
			(fill no)
			(layer "F.Fab")
		)
		(pad "1" smd custom
			(at 0 -0.4445)
			(size 0.1397 0.1397)
			(layers "F.Cu" "F.Mask" "F.Paste")
			(net "SYS_RESET_BTN_A_N")
			(options
				(clearance outline)
				(anchor circle)
			)
			(primitives
				(gr_poly
					(pts
						(arc
							(start -0.1778 -0.2794)
							(mid -0.249642 -0.249642)
							(end -0.2794 -0.1778)
						)
						(arc
							(start -0.2794 0.1778)
							(mid -0.249642 0.249642)
							(end -0.1778 0.2794)
						)
						(arc
							(start 0.1778 0.2794)
							(mid 0.249642 0.249642)
							(end 0.2794 0.1778)
						)
						(arc
							(start 0.2794 -0.1778)
							(mid 0.249642 -0.249642)
							(end 0.1778 -0.2794)
						)
					)
					(width 0)
					(fill yes)
				)
			)
		)
		(pad "2" smd custom
			(at 0 0.4445)
			(size 0.1397 0.1397)
			(layers "F.Cu" "F.Mask" "F.Paste")
			(net "SYS_RESET_BTN_A_N_R")
			(options
				(clearance outline)
				(anchor circle)
			)
			(primitives
				(gr_poly
					(pts
						(arc
							(start -0.1778 -0.2794)
							(mid -0.249642 -0.249642)
							(end -0.2794 -0.1778)
						)
						(arc
							(start -0.2794 0.1778)
							(mid -0.249642 0.249642)
							(end -0.1778 0.2794)
						)
						(arc
							(start 0.1778 0.2794)
							(mid 0.249642 0.249642)
							(end 0.2794 0.1778)
						)
						(arc
							(start 0.2794 -0.1778)
							(mid 0.249642 -0.249642)
							(end 0.1778 -0.2794)
						)
					)
					(width 0)
					(fill yes)
				)
			)
		)
	)
	(footprint ""
		(layer "F.Cu")
		(at 10.094468 -27.776932 -90)
		(property "Reference" "R48"
			(at 0 0 270)
			(layer "F.SilkS")
			(hide yes)
			(effects
				(font
					(size 1.27 1.27)
				)
			)
		)
		(property "Value" "4K7R2F-GP"
			(at 0.064008 -4.679696 270)
			(unlocked yes)
			(layer "F.Fab")
			(hide yes)
			(effects
				(font
					(size 2.54 2.54)
					(thickness 0.381)
				)
			)
		)
		(property "Device Type" "R402H16"
			(at 0.064008 -6.203696 270)
			(unlocked yes)
			(layer "F.Fab")
			(hide yes)
			(effects
				(font
					(size 2.54 2.54)
					(thickness 0.381)
				)
			)
		)
		(duplicate_pad_numbers_are_jumpers no)
		(fp_line
			(start -0.508 -0.9398)
			(end -0.508 0.9398)
			(stroke
				(width 0.1524)
				(type default)
			)
			(layer "F.SilkS")
		)
		(fp_line
			(start 0.508 -0.9398)
			(end -0.508 -0.9398)
			(stroke
				(width 0.1524)
				(type default)
			)
			(layer "F.SilkS")
		)
		(fp_rect
			(start -0.508 0.9398)
			(end 0.508 -0.9398)
			(stroke
				(width 0)
				(type default)
			)
			(fill no)
			(layer "F.CrtYd")
		)
		(fp_rect
			(start -0.508 0.9398)
			(end 0.508 -0.9398)
			(stroke
				(width 0)
				(type default)
			)
			(fill no)
			(layer "F.Fab")
		)
		(pad "1" smd custom
			(at 0 -0.4445 270)
			(size 0.1397 0.1397)
			(layers "F.Cu" "F.Mask" "F.Paste")
			(net "P3V3_STBY_A")
			(options
				(clearance outline)
				(anchor circle)
			)
			(primitives
				(gr_poly
					(pts
						(arc
							(start -0.1778 -0.2794)
							(mid -0.249642 -0.249642)
							(end -0.2794 -0.1778)
						)
						(arc
							(start -0.2794 0.1778)
							(mid -0.249642 0.249642)
							(end -0.1778 0.2794)
						)
						(arc
							(start 0.1778 0.2794)
							(mid 0.249642 0.249642)
							(end 0.2794 0.1778)
						)
						(arc
							(start 0.2794 -0.1778)
							(mid 0.249642 -0.249642)
							(end 0.1778 -0.2794)
						)
					)
					(width 0)
					(fill yes)
				)
			)
		)
		(pad "2" smd custom
			(at 0 0.4445 270)
			(size 0.1397 0.1397)
			(layers "F.Cu" "F.Mask" "F.Paste")
			(net "RST_A_TS")
			(options
				(clearance outline)
				(anchor circle)
			)
			(primitives
				(gr_poly
					(pts
						(arc
							(start -0.1778 -0.2794)
							(mid -0.249642 -0.249642)
							(end -0.2794 -0.1778)
						)
						(arc
							(start -0.2794 0.1778)
							(mid -0.249642 0.249642)
							(end -0.1778 0.2794)
						)
						(arc
							(start 0.1778 0.2794)
							(mid 0.249642 0.249642)
							(end 0.2794 0.1778)
						)
						(arc
							(start 0.2794 -0.1778)
							(mid 0.249642 -0.249642)
							(end 0.1778 -0.2794)
						)
					)
					(width 0)
					(fill yes)
				)
			)
		)
	)
	(footprint ""
		(layer "F.Cu")
		(at 3.0734 -19.177 180)
		(property "Reference" "R4"
			(at 0 0 180)
			(layer "F.SilkS")
			(hide yes)
			(effects
				(font
					(size 1.27 1.27)
				)
			)
		)
		(property "Value" "4K7R2F-GP"
			(at 0.064008 -4.679696 180)
			(unlocked yes)
			(layer "F.Fab")
			(hide yes)
			(effects
				(font
					(size 2.54 2.54)
					(thickness 0.381)
				)
			)
		)
		(property "Device Type" "R402H16"
			(at 0.064008 -6.203696 180)
			(unlocked yes)
			(layer "F.Fab")
			(hide yes)
			(effects
				(font
					(size 2.54 2.54)
					(thickness 0.381)
				)
			)
		)
		(duplicate_pad_numbers_are_jumpers no)
		(fp_line
			(start 0.508 -0.9398)
			(end -0.508 -0.9398)
			(stroke
				(width 0.1524)
				(type default)
			)
			(layer "F.SilkS")
		)
		(fp_line
			(start -0.508 -0.9398)
			(end -0.508 0.9398)
			(stroke
				(width 0.1524)
				(type default)
			)
			(layer "F.SilkS")
		)
		(fp_rect
			(start -0.508 0.9398)
			(end 0.508 -0.9398)
			(stroke
				(width 0)
				(type default)
			)
			(fill no)
			(layer "F.CrtYd")
		)
		(fp_rect
			(start -0.508 0.9398)
			(end 0.508 -0.9398)
			(stroke
				(width 0)
				(type default)
			)
			(fill no)
			(layer "F.Fab")
		)
		(pad "1" smd custom
			(at 0 -0.4445 180)
			(size 0.1397 0.1397)
			(layers "F.Cu" "F.Mask" "F.Paste")
			(net "P3V3_STBY_A")
			(options
				(clearance outline)
				(anchor circle)
			)
			(primitives
				(gr_poly
					(pts
						(arc
							(start -0.1778 -0.2794)
							(mid -0.249642 -0.249642)
							(end -0.2794 -0.1778)
						)
						(arc
							(start -0.2794 0.1778)
							(mid -0.249642 0.249642)
							(end -0.1778 0.2794)
						)
						(arc
							(start 0.1778 0.2794)
							(mid 0.249642 0.249642)
							(end 0.2794 0.1778)
						)
						(arc
							(start 0.2794 -0.1778)
							(mid 0.249642 -0.249642)
							(end 0.1778 -0.2794)
						)
					)
					(width 0)
					(fill yes)
				)
			)
		)
		(pad "2" smd custom
			(at 0 0.4445 180)
			(size 0.1397 0.1397)
			(layers "F.Cu" "F.Mask" "F.Paste")
			(net "I2C_DEBUG_A_SDA")
			(options
				(clearance outline)
				(anchor circle)
			)
			(primitives
				(gr_poly
					(pts
						(arc
							(start -0.1778 -0.2794)
							(mid -0.249642 -0.249642)
							(end -0.2794 -0.1778)
						)
						(arc
							(start -0.2794 0.1778)
							(mid -0.249642 0.249642)
							(end -0.1778 0.2794)
						)
						(arc
							(start 0.1778 0.2794)
							(mid 0.249642 0.249642)
							(end 0.2794 0.1778)
						)
						(arc
							(start 0.2794 -0.1778)
							(mid 0.249642 -0.249642)
							(end 0.1778 -0.2794)
						)
					)
					(width 0)
					(fill yes)
				)
			)
		)
	)
	(footprint ""
		(layer "F.Cu")
		(at 48.90008 -34.99993)
		(property "Reference" "SW4"
			(at 0 0 0)
			(layer "F.SilkS")
			(hide yes)
			(effects
				(font
					(size 1.27 1.27)
				)
			)
		)
		(property "Value" "SW-TACT-4P-214-GP"
			(at 5.97154 0.7747 0)
			(unlocked yes)
			(layer "F.Fab")
			(hide yes)
			(effects
				(font
					(size 2.54 2.54)
					(thickness 0.381)
				)
			)
		)
		(property "Device Type" "DTSM-62N-Q-TR"
			(at 5.97154 -0.7493 0)
			(unlocked yes)
			(layer "F.Fab")
			(hide yes)
			(effects
				(font
					(size 2.54 2.54)
					(thickness 0.381)
				)
			)
		)
		(duplicate_pad_numbers_are_jumpers no)
		(fp_line
			(start -5.0927 -2.8956)
			(end -5.0927 -1.6002)
			(stroke
				(width 0.3302)
				(type default)
			)
			(layer "F.SilkS")
		)
		(fp_line
			(start -5.0038 -3.3528)
			(end 5.0038 -3.3528)
			(stroke
				(width 0.1524)
				(type default)
			)
			(layer "F.SilkS")
		)
		(fp_line
			(start -5.0038 -1.3462)
			(end -5.0038 -3.3528)
			(stroke
				(width 0.1524)
				(type default)
			)
			(layer "F.SilkS")
		)
		(fp_line
			(start -5.0038 1.3462)
			(end -3.3528 1.3462)
			(stroke
				(width 0.1524)
				(type default)
			)
			(layer "F.SilkS")
		)
		(fp_line
			(start -5.0038 3.3528)
			(end -5.0038 1.3462)
			(stroke
				(width 0.1524)
				(type default)
			)
			(layer "F.SilkS")
		)
		(fp_line
			(start -3.3528 -1.3462)
			(end -5.0038 -1.3462)
			(stroke
				(width 0.1524)
				(type default)
			)
			(layer "F.SilkS")
		)
		(fp_line
			(start -3.3528 1.3462)
			(end -3.3528 -1.3462)
			(stroke
				(width 0.1524)
				(type default)
			)
			(layer "F.SilkS")
		)
		(fp_line
			(start 3.3528 -1.3462)
			(end 3.3528 1.3462)
			(stroke
				(width 0.1524)
				(type default)
			)
			(layer "F.SilkS")
		)
		(fp_line
			(start 3.3528 1.3462)
			(end 5.0038 1.3462)
			(stroke
				(width 0.1524)
				(type default)
			)
			(layer "F.SilkS")
		)
		(fp_line
			(start 5.0038 -3.3528)
			(end 5.0038 -1.3462)
			(stroke
				(width 0.1524)
				(type default)
			)
			(layer "F.SilkS")
		)
		(fp_line
			(start 5.0038 -1.3462)
			(end 3.3528 -1.3462)
			(stroke
				(width 0.1524)
				(type default)
			)
			(layer "F.SilkS")
		)
		(fp_line
			(start 5.0038 1.3462)
			(end 5.0038 3.3528)
			(stroke
				(width 0.1524)
				(type default)
			)
			(layer "F.SilkS")
		)
		(fp_line
			(start 5.0038 3.3528)
			(end -5.0038 3.3528)
			(stroke
				(width 0.1524)
				(type default)
			)
			(layer "F.SilkS")
		)
		(fp_poly
			(pts
				(xy -5.072888 -2.29108) (xy -5.707888 -1.65608) (xy -5.707888 -2.92608)
			)
			(stroke
				(width 0)
				(type default)
			)
			(fill yes)
			(layer "F.SilkS")
		)
		(fp_poly
			(pts
				(xy -3.0988 3.0988) (xy -3.0988 2.5908) (xy -4.4958 2.5908) (xy -4.4958 1.8796) (xy -3.0988 1.8796)
				(xy -3.0988 -1.8796) (xy -4.4958 -1.8796) (xy -4.4958 -2.5908) (xy -3.0988 -2.5908) (xy -3.0988 -3.0988)
				(xy 3.0988 -3.0988) (xy 3.0988 -2.5908) (xy 4.4958 -2.5908) (xy 4.4958 -1.8796) (xy 3.0988 -1.8796)
				(xy 3.0988 1.8796) (xy 4.4958 1.8796) (xy 4.4958 2.5908) (xy 3.0988 2.5908) (xy 3.0988 3.0988)
			)
			(stroke
				(width 0)
				(type default)
			)
			(fill no)
			(layer "F.CrtYd")
		)
		(fp_poly
			(pts
				(xy -5.2578 3.6068) (xy -5.2578 1.0922) (xy -3.6068 1.0922) (xy -3.6068 -1.0922) (xy -5.2578 -1.0922)
				(xy -5.2578 -3.6068) (xy 5.2578 -3.6068) (xy 5.2578 -1.0922) (xy 3.6068 -1.0922) (xy 3.6068 -0.00635)
				(xy 3.0988 -0.00635) (xy 3.0988 -1.8796) (xy 4.4958 -1.8796) (xy 4.4958 -2.5908) (xy 3.0988 -2.5908)
				(xy 3.0988 -3.0988) (xy -3.0988 -3.0988) (xy -3.0988 -2.5908) (xy -4.4958 -2.5908) (xy -4.4958 -1.8796)
				(xy -3.0988 -1.8796) (xy -3.0988 1.8796) (xy -4.4958 1.8796) (xy -4.4958 2.5908) (xy -3.0988 2.5908)
				(xy -3.0988 3.0988) (xy 3.0988 3.0988) (xy 3.0988 2.5908) (xy 4.4958 2.5908) (xy 4.4958 1.8796)
				(xy 3.0988 1.8796) (xy 3.0988 0.00635) (xy 3.6068 0.00635) (xy 3.6068 1.0922) (xy 5.2578 1.0922)
				(xy 5.2578 3.6068)
			)
			(stroke
				(width 0)
				(type default)
			)
			(fill no)
			(layer "F.CrtYd")
		)
		(fp_poly
			(pts
				(xy -5.2578 3.6068) (xy -5.2578 1.0922) (xy -3.6068 1.0922) (xy -3.6068 -1.0922) (xy -5.2578 -1.0922)
				(xy -5.2578 -3.6068) (xy 5.2578 -3.6068) (xy 5.2578 -1.0922) (xy 3.6068 -1.0922) (xy 3.6068 1.0922)
				(xy 5.2578 1.0922) (xy 5.2578 3.6068)
			)
			(stroke
				(width 0)
				(type default)
			)
			(fill no)
			(layer "F.Fab")
		)
		(pad "T1" smd rect
			(at -3.9751 -2.249932)
			(size 1.5494 1.2954)
			(layers "F.Cu" "F.Mask" "F.Paste")
			(net "SYS_RESET_BTN_B")
		)
		(pad "T2" smd rect
			(at 3.9751 -2.249932)
			(size 1.5494 1.2954)
			(layers "F.Cu" "F.Mask" "F.Paste")
			(net "SYS_RESET_BTN_B")
		)
		(pad "T3" smd rect
			(at -3.9751 2.249932)
			(size 1.5494 1.2954)
			(layers "F.Cu" "F.Mask" "F.Paste")
			(net "GND")
		)
		(pad "T4" smd rect
			(at 3.9751 2.249932)
			(size 1.5494 1.2954)
			(layers "F.Cu" "F.Mask" "F.Paste")
			(net "GND")
		)
	)
	(footprint ""
		(layer "F.Cu")
		(at 24.910034 -12.68095 180)
		(property "Reference" "R79"
			(at 0 0 180)
			(layer "F.SilkS")
			(hide yes)
			(effects
				(font
					(size 1.27 1.27)
				)
			)
		)
		(property "Value" "4K7R2F-GP"
			(at 0.064008 -3.993896 180)
			(unlocked yes)
			(layer "F.Fab")
			(hide yes)
			(effects
				(font
					(size 1.016 1.016)
					(thickness 0.1524)
				)
			)
		)
		(property "Device Type" "R402H16"
			(at 0.064008 -5.517896 180)
			(unlocked yes)
			(layer "F.Fab")
			(hide yes)
			(effects
				(font
					(size 1.016 1.016)
					(thickness 0.1524)
				)
			)
		)
		(duplicate_pad_numbers_are_jumpers no)
		(fp_line
			(start 0.508 -0.9398)
			(end -0.508 -0.9398)
			(stroke
				(width 0.1524)
				(type default)
			)
			(layer "F.SilkS")
		)
		(fp_line
			(start -0.508 -0.9398)
			(end -0.508 0.9398)
			(stroke
				(width 0.1524)
				(type default)
			)
			(layer "F.SilkS")
		)
		(fp_rect
			(start -0.508 0.9398)
			(end 0.508 -0.9398)
			(stroke
				(width 0)
				(type default)
			)
			(fill no)
			(layer "F.CrtYd")
		)
		(fp_rect
			(start -0.508 0.9398)
			(end 0.508 -0.9398)
			(stroke
				(width 0)
				(type default)
			)
			(fill no)
			(layer "F.Fab")
		)
		(pad "1" smd custom
			(at 0 -0.4445 180)
			(size 0.1397 0.1397)
			(layers "F.Cu" "F.Mask" "F.Paste")
			(net "P3V3_STBY_A")
			(options
				(clearance outline)
				(anchor circle)
			)
			(primitives
				(gr_poly
					(pts
						(arc
							(start -0.1778 -0.2794)
							(mid -0.249642 -0.249642)
							(end -0.2794 -0.1778)
						)
						(arc
							(start -0.2794 0.1778)
							(mid -0.249642 0.249642)
							(end -0.1778 0.2794)
						)
						(arc
							(start 0.1778 0.2794)
							(mid 0.249642 0.249642)
							(end 0.2794 0.1778)
						)
						(arc
							(start 0.2794 -0.1778)
							(mid 0.249642 -0.249642)
							(end 0.1778 -0.2794)
						)
					)
					(width 0)
					(fill yes)
				)
			)
		)
		(pad "2" smd custom
			(at 0 0.4445 180)
			(size 0.1397 0.1397)
			(layers "F.Cu" "F.Mask" "F.Paste")
			(net "D_FLIP_CLR_A#")
			(options
				(clearance outline)
				(anchor circle)
			)
			(primitives
				(gr_poly
					(pts
						(arc
							(start -0.1778 -0.2794)
							(mid -0.249642 -0.249642)
							(end -0.2794 -0.1778)
						)
						(arc
							(start -0.2794 0.1778)
							(mid -0.249642 0.249642)
							(end -0.1778 0.2794)
						)
						(arc
							(start 0.1778 0.2794)
							(mid 0.249642 0.249642)
							(end 0.2794 0.1778)
						)
						(arc
							(start 0.2794 -0.1778)
							(mid 0.249642 -0.249642)
							(end 0.1778 -0.2794)
						)
					)
					(width 0)
					(fill yes)
				)
			)
		)
	)
	(footprint ""
		(layer "F.Cu")
		(at 56.515 -10.287)
		(property "Reference" "R71"
			(at 0 0 0)
			(layer "F.SilkS")
			(hide yes)
			(effects
				(font
					(size 1.27 1.27)
				)
			)
		)
		(property "Value" "4K7R2F-GP"
			(at 0.064008 -3.993896 0)
			(unlocked yes)
			(layer "F.Fab")
			(hide yes)
			(effects
				(font
					(size 1.016 1.016)
					(thickness 0.1524)
				)
			)
		)
		(property "Device Type" "R402H16"
			(at 0.064008 -5.517896 0)
			(unlocked yes)
			(layer "F.Fab")
			(hide yes)
			(effects
				(font
					(size 1.016 1.016)
					(thickness 0.1524)
				)
			)
		)
		(duplicate_pad_numbers_are_jumpers no)
		(fp_line
			(start -0.508 -0.9398)
			(end -0.508 0.9398)
			(stroke
				(width 0.1524)
				(type default)
			)
			(layer "F.SilkS")
		)
		(fp_line
			(start 0.508 -0.9398)
			(end -0.508 -0.9398)
			(stroke
				(width 0.1524)
				(type default)
			)
			(layer "F.SilkS")
		)
		(fp_rect
			(start -0.508 0.9398)
			(end 0.508 -0.9398)
			(stroke
				(width 0)
				(type default)
			)
			(fill no)
			(layer "F.CrtYd")
		)
		(fp_rect
			(start -0.508 0.9398)
			(end 0.508 -0.9398)
			(stroke
				(width 0)
				(type default)
			)
			(fill no)
			(layer "F.Fab")
		)
		(pad "1" smd custom
			(at 0 -0.4445)
			(size 0.1397 0.1397)
			(layers "F.Cu" "F.Mask" "F.Paste")
			(net "TCA9555_B_A1")
			(options
				(clearance outline)
				(anchor circle)
			)
			(primitives
				(gr_poly
					(pts
						(arc
							(start -0.1778 -0.2794)
							(mid -0.249642 -0.249642)
							(end -0.2794 -0.1778)
						)
						(arc
							(start -0.2794 0.1778)
							(mid -0.249642 0.249642)
							(end -0.1778 0.2794)
						)
						(arc
							(start 0.1778 0.2794)
							(mid 0.249642 0.249642)
							(end 0.2794 0.1778)
						)
						(arc
							(start 0.2794 -0.1778)
							(mid 0.249642 -0.249642)
							(end 0.1778 -0.2794)
						)
					)
					(width 0)
					(fill yes)
				)
			)
		)
		(pad "2" smd custom
			(at 0 0.4445)
			(size 0.1397 0.1397)
			(layers "F.Cu" "F.Mask" "F.Paste")
			(net "GND")
			(options
				(clearance outline)
				(anchor circle)
			)
			(primitives
				(gr_poly
					(pts
						(arc
							(start -0.1778 -0.2794)
							(mid -0.249642 -0.249642)
							(end -0.2794 -0.1778)
						)
						(arc
							(start -0.2794 0.1778)
							(mid -0.249642 0.249642)
							(end -0.1778 0.2794)
						)
						(arc
							(start 0.1778 0.2794)
							(mid 0.249642 0.249642)
							(end 0.2794 0.1778)
						)
						(arc
							(start 0.2794 -0.1778)
							(mid 0.249642 -0.249642)
							(end 0.1778 -0.2794)
						)
					)
					(width 0)
					(fill yes)
				)
			)
		)
	)
	(footprint ""
		(layer "F.Cu")
		(at 47.8155 -15.442184)
		(property "Reference" "R69"
			(at 0 0 0)
			(layer "F.SilkS")
			(hide yes)
			(effects
				(font
					(size 1.27 1.27)
				)
			)
		)
		(property "Value" "4K7R2F-GP"
			(at 0.064008 -3.993896 0)
			(unlocked yes)
			(layer "F.Fab")
			(hide yes)
			(effects
				(font
					(size 1.016 1.016)
					(thickness 0.1524)
				)
			)
		)
		(property "Device Type" "R402H16"
			(at 0.064008 -5.517896 0)
			(unlocked yes)
			(layer "F.Fab")
			(hide yes)
			(effects
				(font
					(size 1.016 1.016)
					(thickness 0.1524)
				)
			)
		)
		(duplicate_pad_numbers_are_jumpers no)
		(fp_line
			(start -0.508 -0.9398)
			(end -0.508 0.9398)
			(stroke
				(width 0.1524)
				(type default)
			)
			(layer "F.SilkS")
		)
		(fp_line
			(start 0.508 -0.9398)
			(end -0.508 -0.9398)
			(stroke
				(width 0.1524)
				(type default)
			)
			(layer "F.SilkS")
		)
		(fp_rect
			(start -0.508 0.9398)
			(end 0.508 -0.9398)
			(stroke
				(width 0)
				(type default)
			)
			(fill no)
			(layer "F.CrtYd")
		)
		(fp_rect
			(start -0.508 0.9398)
			(end 0.508 -0.9398)
			(stroke
				(width 0)
				(type default)
			)
			(fill no)
			(layer "F.Fab")
		)
		(pad "1" smd custom
			(at 0 -0.4445)
			(size 0.1397 0.1397)
			(layers "F.Cu" "F.Mask" "F.Paste")
			(net "P3V3_STBY_B")
			(options
				(clearance outline)
				(anchor circle)
			)
			(primitives
				(gr_poly
					(pts
						(arc
							(start -0.1778 -0.2794)
							(mid -0.249642 -0.249642)
							(end -0.2794 -0.1778)
						)
						(arc
							(start -0.2794 0.1778)
							(mid -0.249642 0.249642)
							(end -0.1778 0.2794)
						)
						(arc
							(start 0.1778 0.2794)
							(mid 0.249642 0.249642)
							(end 0.2794 0.1778)
						)
						(arc
							(start 0.2794 -0.1778)
							(mid 0.249642 -0.249642)
							(end 0.1778 -0.2794)
						)
					)
					(width 0)
					(fill yes)
				)
			)
		)
		(pad "2" smd custom
			(at 0 0.4445)
			(size 0.1397 0.1397)
			(layers "F.Cu" "F.Mask" "F.Paste")
			(net "TCA9555_B_A0")
			(options
				(clearance outline)
				(anchor circle)
			)
			(primitives
				(gr_poly
					(pts
						(arc
							(start -0.1778 -0.2794)
							(mid -0.249642 -0.249642)
							(end -0.2794 -0.1778)
						)
						(arc
							(start -0.2794 0.1778)
							(mid -0.249642 0.249642)
							(end -0.1778 0.2794)
						)
						(arc
							(start 0.1778 0.2794)
							(mid 0.249642 0.249642)
							(end 0.2794 0.1778)
						)
						(arc
							(start 0.2794 -0.1778)
							(mid 0.249642 -0.249642)
							(end 0.1778 -0.2794)
						)
					)
					(width 0)
					(fill yes)
				)
			)
		)
	)
	(footprint ""
		(layer "F.Cu")
		(at 2.02819 -56.892698)
		(property "Reference" "D3"
			(at 0 0 0)
			(layer "F.SilkS")
			(hide yes)
			(effects
				(font
					(size 1.27 1.27)
				)
			)
		)
		(property "Value" "PESD5V0S1BL-1-GP"
			(at 1.8923 -1.5621 0)
			(unlocked yes)
			(layer "F.Fab")
			(hide yes)
			(effects
				(font
					(size 1.016 1.016)
					(thickness 0.1524)
				)
			)
		)
		(property "Device Type" "SOD882-10D6-1H20"
			(at 1.8923 -3.0861 0)
			(unlocked yes)
			(layer "F.Fab")
			(hide yes)
			(effects
				(font
					(size 1.016 1.016)
					(thickness 0.1524)
				)
			)
		)
		(duplicate_pad_numbers_are_jumpers no)
		(fp_line
			(start -0.3048 -0.9271)
			(end 0.3048 -0.9271)
			(stroke
				(width 0.254)
				(type default)
			)
			(layer "F.SilkS")
		)
		(fp_rect
			(start -0.2921 0.4953)
			(end 0.2921 -0.4953)
			(stroke
				(width 0)
				(type default)
			)
			(fill no)
			(layer "F.CrtYd")
		)
		(fp_poly
			(pts
				(xy -0.4318 0.8001) (xy -0.4318 -0.266192) (xy -0.2921 -0.266192) (xy -0.2921 0.4953) (xy 0.2921 0.4953)
				(xy 0.2921 -0.4953) (xy -0.2921 -0.4953) (xy -0.2921 -0.2667) (xy -0.4318 -0.2667) (xy -0.4318 -0.8001)
				(xy 0.4318 -0.8001) (xy 0.4318 0.8001)
			)
			(stroke
				(width 0)
				(type default)
			)
			(fill no)
			(layer "F.CrtYd")
		)
		(fp_rect
			(start -0.4318 0.8001)
			(end 0.4318 -0.8001)
			(stroke
				(width 0)
				(type default)
			)
			(fill no)
			(layer "F.Fab")
		)
		(pad "1" smd custom
			(at 0 -0.4445)
			(size 0.1143 0.1143)
			(layers "F.Cu" "F.Mask" "F.Paste")
			(net "P5V_VBUS_A")
			(options
				(clearance outline)
				(anchor circle)
			)
			(primitives
				(gr_poly
					(pts
						(arc
							(start -0.2032 0.2286)
							(mid -0.275042 0.198842)
							(end -0.3048 0.127)
						)
						(arc
							(start -0.3048 -0.127)
							(mid -0.275042 -0.198842)
							(end -0.2032 -0.2286)
						)
						(arc
							(start 0.2032 -0.2286)
							(mid 0.275042 -0.198842)
							(end 0.3048 -0.127)
						)
						(arc
							(start 0.3048 0.127)
							(mid 0.275042 0.198842)
							(end 0.2032 0.2286)
						)
					)
					(width 0)
					(fill yes)
				)
			)
		)
		(pad "2" smd custom
			(at 0 0.4445)
			(size 0.1143 0.1143)
			(layers "F.Cu" "F.Mask" "F.Paste")
			(net "GND")
			(options
				(clearance outline)
				(anchor circle)
			)
			(primitives
				(gr_poly
					(pts
						(arc
							(start 0.2032 -0.2286)
							(mid 0.275042 -0.198842)
							(end 0.3048 -0.127)
						)
						(arc
							(start 0.3048 0.127)
							(mid 0.275042 0.198842)
							(end 0.2032 0.2286)
						)
						(arc
							(start -0.2032 0.2286)
							(mid -0.275042 0.198842)
							(end -0.3048 0.127)
						)
						(arc
							(start -0.3048 -0.127)
							(mid -0.275042 -0.198842)
							(end -0.2032 -0.2286)
						)
					)
					(width 0)
					(fill yes)
				)
			)
		)
	)
	(footprint ""
		(layer "F.Cu")
		(at 55.0164 -30.226 90)
		(property "Reference" "R54"
			(at 0 0 90)
			(layer "F.SilkS")
			(hide yes)
			(effects
				(font
					(size 1.27 1.27)
				)
			)
		)
		(property "Value" "4K7R2F-GP"
			(at 0.064008 -4.679696 90)
			(unlocked yes)
			(layer "F.Fab")
			(hide yes)
			(effects
				(font
					(size 2.54 2.54)
					(thickness 0.381)
				)
			)
		)
		(property "Device Type" "R402H16"
			(at 0.064008 -6.203696 90)
			(unlocked yes)
			(layer "F.Fab")
			(hide yes)
			(effects
				(font
					(size 2.54 2.54)
					(thickness 0.381)
				)
			)
		)
		(duplicate_pad_numbers_are_jumpers no)
		(fp_line
			(start 0.508 -0.9398)
			(end -0.508 -0.9398)
			(stroke
				(width 0.1524)
				(type default)
			)
			(layer "F.SilkS")
		)
		(fp_line
			(start -0.508 -0.9398)
			(end -0.508 0.9398)
			(stroke
				(width 0.1524)
				(type default)
			)
			(layer "F.SilkS")
		)
		(fp_rect
			(start -0.508 0.9398)
			(end 0.508 -0.9398)
			(stroke
				(width 0)
				(type default)
			)
			(fill no)
			(layer "F.CrtYd")
		)
		(fp_rect
			(start -0.508 0.9398)
			(end 0.508 -0.9398)
			(stroke
				(width 0)
				(type default)
			)
			(fill no)
			(layer "F.Fab")
		)
		(pad "1" smd custom
			(at 0 -0.4445 90)
			(size 0.1397 0.1397)
			(layers "F.Cu" "F.Mask" "F.Paste")
			(net "RST_B_TS")
			(options
				(clearance outline)
				(anchor circle)
			)
			(primitives
				(gr_poly
					(pts
						(arc
							(start -0.1778 -0.2794)
							(mid -0.249642 -0.249642)
							(end -0.2794 -0.1778)
						)
						(arc
							(start -0.2794 0.1778)
							(mid -0.249642 0.249642)
							(end -0.1778 0.2794)
						)
						(arc
							(start 0.1778 0.2794)
							(mid 0.249642 0.249642)
							(end 0.2794 0.1778)
						)
						(arc
							(start 0.2794 -0.1778)
							(mid 0.249642 -0.249642)
							(end 0.1778 -0.2794)
						)
					)
					(width 0)
					(fill yes)
				)
			)
		)
		(pad "2" smd custom
			(at 0 0.4445 90)
			(size 0.1397 0.1397)
			(layers "F.Cu" "F.Mask" "F.Paste")
			(net "GND")
			(options
				(clearance outline)
				(anchor circle)
			)
			(primitives
				(gr_poly
					(pts
						(arc
							(start -0.1778 -0.2794)
							(mid -0.249642 -0.249642)
							(end -0.2794 -0.1778)
						)
						(arc
							(start -0.2794 0.1778)
							(mid -0.249642 0.249642)
							(end -0.1778 0.2794)
						)
						(arc
							(start 0.1778 0.2794)
							(mid 0.249642 0.249642)
							(end 0.2794 0.1778)
						)
						(arc
							(start 0.2794 -0.1778)
							(mid 0.249642 -0.249642)
							(end 0.1778 -0.2794)
						)
					)
					(width 0)
					(fill yes)
				)
			)
		)
	)
	(footprint ""
		(layer "F.Cu")
		(at 54.741064 -34.05759 180)
		(property "Reference" "R23"
			(at 0 0 180)
			(layer "F.SilkS")
			(hide yes)
			(effects
				(font
					(size 1.27 1.27)
				)
			)
		)
		(property "Value" "22KR2F-GP"
			(at 0.064008 -4.679696 180)
			(unlocked yes)
			(layer "F.Fab")
			(hide yes)
			(effects
				(font
					(size 2.54 2.54)
					(thickness 0.381)
				)
			)
		)
		(property "Device Type" "R402H16"
			(at 0.064008 -6.203696 180)
			(unlocked yes)
			(layer "F.Fab")
			(hide yes)
			(effects
				(font
					(size 2.54 2.54)
					(thickness 0.381)
				)
			)
		)
		(duplicate_pad_numbers_are_jumpers no)
		(fp_line
			(start 0.508 -0.9398)
			(end -0.508 -0.9398)
			(stroke
				(width 0.1524)
				(type default)
			)
			(layer "F.SilkS")
		)
		(fp_line
			(start -0.508 -0.9398)
			(end -0.508 0.9398)
			(stroke
				(width 0.1524)
				(type default)
			)
			(layer "F.SilkS")
		)
		(fp_rect
			(start -0.508 0.9398)
			(end 0.508 -0.9398)
			(stroke
				(width 0)
				(type default)
			)
			(fill no)
			(layer "F.CrtYd")
		)
		(fp_rect
			(start -0.508 0.9398)
			(end 0.508 -0.9398)
			(stroke
				(width 0)
				(type default)
			)
			(fill no)
			(layer "F.Fab")
		)
		(pad "1" smd custom
			(at 0 -0.4445 180)
			(size 0.1397 0.1397)
			(layers "F.Cu" "F.Mask" "F.Paste")
			(net "P3V3_STBY_B")
			(options
				(clearance outline)
				(anchor circle)
			)
			(primitives
				(gr_poly
					(pts
						(arc
							(start -0.1778 -0.2794)
							(mid -0.249642 -0.249642)
							(end -0.2794 -0.1778)
						)
						(arc
							(start -0.2794 0.1778)
							(mid -0.249642 0.249642)
							(end -0.1778 0.2794)
						)
						(arc
							(start 0.1778 0.2794)
							(mid 0.249642 0.249642)
							(end 0.2794 0.1778)
						)
						(arc
							(start 0.2794 -0.1778)
							(mid 0.249642 -0.249642)
							(end 0.1778 -0.2794)
						)
					)
					(width 0)
					(fill yes)
				)
			)
		)
		(pad "2" smd custom
			(at 0 0.4445 180)
			(size 0.1397 0.1397)
			(layers "F.Cu" "F.Mask" "F.Paste")
			(net "SYS_RESET_BTN_B")
			(options
				(clearance outline)
				(anchor circle)
			)
			(primitives
				(gr_poly
					(pts
						(arc
							(start -0.1778 -0.2794)
							(mid -0.249642 -0.249642)
							(end -0.2794 -0.1778)
						)
						(arc
							(start -0.2794 0.1778)
							(mid -0.249642 0.249642)
							(end -0.1778 0.2794)
						)
						(arc
							(start 0.1778 0.2794)
							(mid 0.249642 0.249642)
							(end 0.2794 0.1778)
						)
						(arc
							(start 0.2794 -0.1778)
							(mid 0.249642 -0.249642)
							(end 0.1778 -0.2794)
						)
					)
					(width 0)
					(fill yes)
				)
			)
		)
	)
	(footprint ""
		(layer "F.Cu")
		(at 33.6804 -12.3952 180)
		(property "Reference" "C32"
			(at 0 0 180)
			(layer "F.SilkS")
			(hide yes)
			(effects
				(font
					(size 1.27 1.27)
				)
			)
		)
		(property "Value" "SCD1U16V2KX-3GP"
			(at 1.1811 -2.7051 180)
			(unlocked yes)
			(layer "F.Fab")
			(hide yes)
			(effects
				(font
					(size 1.016 1.016)
					(thickness 0.1524)
				)
			)
		)
		(property "Device Type" "C402H22"
			(at 1.1811 -4.2291 180)
			(unlocked yes)
			(layer "F.Fab")
			(hide yes)
			(effects
				(font
					(size 1.016 1.016)
					(thickness 0.1524)
				)
			)
		)
		(duplicate_pad_numbers_are_jumpers no)
		(fp_rect
			(start -0.4318 0.9525)
			(end 0.4318 -0.9525)
			(stroke
				(width 0)
				(type default)
			)
			(fill no)
			(layer "F.CrtYd")
		)
		(fp_rect
			(start -0.4318 0.9525)
			(end 0.4318 -0.9525)
			(stroke
				(width 0)
				(type default)
			)
			(fill no)
			(layer "F.Fab")
		)
		(pad "1" smd custom
			(at 0 -0.4445 180)
			(size 0.1524 0.1524)
			(layers "F.Cu" "F.Mask" "F.Paste")
			(net "DEBUG_HDR_B_UART_SEL")
			(options
				(clearance outline)
				(anchor circle)
			)
			(primitives
				(gr_poly
					(pts
						(arc
							(start 0.3048 -0.2032)
							(mid 0.275042 -0.275042)
							(end 0.2032 -0.3048)
						)
						(arc
							(start -0.2032 -0.3048)
							(mid -0.275042 -0.275042)
							(end -0.3048 -0.2032)
						)
						(arc
							(start -0.3048 0.2032)
							(mid -0.275042 0.275042)
							(end -0.2032 0.3048)
						)
						(arc
							(start 0.2032 0.3048)
							(mid 0.275042 0.275042)
							(end 0.3048 0.2032)
						)
					)
					(width 0)
					(fill yes)
				)
			)
		)
		(pad "2" smd custom
			(at 0 0.4445 180)
			(size 0.1524 0.1524)
			(layers "F.Cu" "F.Mask" "F.Paste")
			(net "GND")
			(options
				(clearance outline)
				(anchor circle)
			)
			(primitives
				(gr_poly
					(pts
						(arc
							(start 0.3048 -0.2032)
							(mid 0.275042 -0.275042)
							(end 0.2032 -0.3048)
						)
						(arc
							(start -0.2032 -0.3048)
							(mid -0.275042 -0.275042)
							(end -0.3048 -0.2032)
						)
						(arc
							(start -0.3048 0.2032)
							(mid -0.275042 0.275042)
							(end -0.2032 0.3048)
						)
						(arc
							(start 0.2032 0.3048)
							(mid 0.275042 0.275042)
							(end 0.3048 0.2032)
						)
					)
					(width 0)
					(fill yes)
				)
			)
		)
	)
	(footprint ""
		(layer "F.Cu")
		(at 16.51 -7.366 180)
		(property "Reference" "U11"
			(at 0 0 180)
			(layer "F.SilkS")
			(hide yes)
			(effects
				(font
					(size 1.27 1.27)
				)
			)
		)
		(property "Value" "SNLVC1G126DCKR-GP"
			(at -2.3368 -8.6868 180)
			(unlocked yes)
			(layer "F.Fab")
			(hide yes)
			(effects
				(font
					(size 1.016 1.016)
					(thickness 0.1524)
				)
			)
		)
		(property "Device Type" "SC70-5H44"
			(at -2.3114 -10.414 180)
			(unlocked yes)
			(layer "F.Fab")
			(hide yes)
			(effects
				(font
					(size 1.016 1.016)
					(thickness 0.1524)
				)
			)
		)
		(duplicate_pad_numbers_are_jumpers no)
		(fp_line
			(start 1.3843 -1.8034)
			(end 1.3843 -1.1176)
			(stroke
				(width 0.3302)
				(type default)
			)
			(layer "F.SilkS")
		)
		(fp_line
			(start 1.27 1.7018)
			(end -1.27 1.7018)
			(stroke
				(width 0.1524)
				(type default)
			)
			(layer "F.SilkS")
		)
		(fp_line
			(start 1.27 -1.7018)
			(end 1.27 1.7018)
			(stroke
				(width 0.1524)
				(type default)
			)
			(layer "F.SilkS")
		)
		(fp_line
			(start 0.6604 -1.8034)
			(end 1.3843 -1.8034)
			(stroke
				(width 0.3302)
				(type default)
			)
			(layer "F.SilkS")
		)
		(fp_line
			(start -1.27 1.7018)
			(end -1.27 -1.7018)
			(stroke
				(width 0.1524)
				(type default)
			)
			(layer "F.SilkS")
		)
		(fp_line
			(start -1.27 -1.7018)
			(end 1.27 -1.7018)
			(stroke
				(width 0.1524)
				(type default)
			)
			(layer "F.SilkS")
		)
		(fp_rect
			(start -1.524 1.9558)
			(end 1.524 -1.9558)
			(stroke
				(width 0)
				(type default)
			)
			(fill no)
			(layer "F.CrtYd")
		)
		(fp_poly
			(pts
				(xy -1.524 -1.9558) (xy 1.524 -1.9558) (xy 1.524 1.9558) (xy -1.524 1.9558)
			)
			(stroke
				(width 0)
				(type default)
			)
			(fill no)
			(layer "F.Fab")
		)
		(pad "1" smd rect
			(at 0.65024 -0.8255 180)
			(size 0.4064 1.2192)
			(layers "F.Cu" "F.Mask" "F.Paste")
			(net "DEBUG_CARD_A_PRSNT")
		)
		(pad "2" smd rect
			(at 0 -0.8255 180)
			(size 0.4064 1.2192)
			(layers "F.Cu" "F.Mask" "F.Paste")
			(net "UART_DEBUG_A_RX")
		)
		(pad "3" smd rect
			(at -0.65024 -0.8255 180)
			(size 0.4064 1.2192)
			(layers "F.Cu" "F.Mask" "F.Paste")
			(net "GND")
		)
		(pad "4" smd rect
			(at -0.65024 0.8255 180)
			(size 0.4064 1.2192)
			(layers "F.Cu" "F.Mask" "F.Paste")
			(net "UART_A_RX")
		)
		(pad "5" smd rect
			(at 0.65024 0.8255 180)
			(size 0.4064 1.2192)
			(layers "F.Cu" "F.Mask" "F.Paste")
			(net "P3V3_STBY_A")
		)
	)
	(footprint ""
		(layer "F.Cu")
		(at 3.700526 -43.263058)
		(property "Reference" "D1"
			(at 0 0 0)
			(layer "F.SilkS")
			(hide yes)
			(effects
				(font
					(size 1.27 1.27)
				)
			)
		)
		(property "Value" "PESD3V3L4UW-GP"
			(at 2.2606 1.27 0)
			(unlocked yes)
			(layer "F.Fab")
			(hide yes)
			(effects
				(font
					(size 1.016 1.016)
					(thickness 0.1524)
				)
			)
		)
		(property "Device Type" "SOT-23-5-3H24"
			(at 2.2606 -0.254 0)
			(unlocked yes)
			(layer "F.Fab")
			(hide yes)
			(effects
				(font
					(size 1.016 1.016)
					(thickness 0.1524)
				)
			)
		)
		(duplicate_pad_numbers_are_jumpers no)
		(fp_line
			(start -1.143 0.254)
			(end -1.143 1.524)
			(stroke
				(width 0.3302)
				(type default)
			)
			(layer "F.SilkS")
		)
		(fp_line
			(start -1.143 1.524)
			(end 0.127 1.524)
			(stroke
				(width 0.3302)
				(type default)
			)
			(layer "F.SilkS")
		)
		(fp_line
			(start -1.0541 -1.4351)
			(end -1.0541 1.4351)
			(stroke
				(width 0.1524)
				(type default)
			)
			(layer "F.SilkS")
		)
		(fp_line
			(start -1.0541 1.4351)
			(end 1.0541 1.4351)
			(stroke
				(width 0.1524)
				(type default)
			)
			(layer "F.SilkS")
		)
		(fp_line
			(start 1.0541 -1.4351)
			(end -1.0541 -1.4351)
			(stroke
				(width 0.1524)
				(type default)
			)
			(layer "F.SilkS")
		)
		(fp_line
			(start 1.0541 1.4351)
			(end 1.0541 -1.4351)
			(stroke
				(width 0.1524)
				(type default)
			)
			(layer "F.SilkS")
		)
		(fp_poly
			(pts
				(xy -0.508 1.5113) (xy -0.0762 1.9431) (xy -0.9398 1.9431)
			)
			(stroke
				(width 0)
				(type default)
			)
			(fill yes)
			(layer "F.SilkS")
		)
		(fp_rect
			(start -1.3081 1.6891)
			(end 1.3081 -1.6891)
			(stroke
				(width 0)
				(type default)
			)
			(fill no)
			(layer "F.CrtYd")
		)
		(fp_rect
			(start -1.3081 1.6891)
			(end 1.3081 -1.6891)
			(stroke
				(width 0)
				(type default)
			)
			(fill no)
			(layer "F.Fab")
		)
		(pad "1" smd rect
			(at -0.500126 0.7239)
			(size 0.3048 0.9144)
			(layers "F.Cu" "F.Mask" "F.Paste")
			(net "UART_DEBUG_A_RX")
		)
		(pad "2" smd rect
			(at 0 0.7239)
			(size 0.3048 0.9144)
			(layers "F.Cu" "F.Mask" "F.Paste")
			(net "GND")
		)
		(pad "3" smd rect
			(at 0.500126 0.7239)
			(size 0.3048 0.9144)
			(layers "F.Cu" "F.Mask" "F.Paste")
			(net "I2C_DEBUG_A_SDA")
		)
		(pad "4" smd rect
			(at 0.500126 -0.7239)
			(size 0.3048 0.9144)
			(layers "F.Cu" "F.Mask" "F.Paste")
			(net "I2C_DEBUG_A_SCL")
		)
		(pad "5" smd rect
			(at -0.500126 -0.7239)
			(size 0.3048 0.9144)
			(layers "F.Cu" "F.Mask" "F.Paste")
			(net "UART_DEBUG_A_TX")
		)
	)
	(footprint ""
		(layer "F.Cu")
		(at 3.3528 -47.7266 90)
		(property "Reference" "TP7"
			(at 0 0 90)
			(layer "F.SilkS")
			(hide yes)
			(effects
				(font
					(size 1.27 1.27)
				)
			)
		)
		(property "Value" "TPAD32-GP"
			(at -0.0508 -1.6764 90)
			(unlocked yes)
			(layer "F.Fab")
			(hide yes)
			(effects
				(font
					(size 1.016 1.016)
					(thickness 0.1524)
				)
			)
		)
		(property "Device Type" "TPAD32"
			(at -0.0508 -3.2004 90)
			(unlocked yes)
			(layer "F.Fab")
			(hide yes)
			(effects
				(font
					(size 1.016 1.016)
					(thickness 0.1524)
				)
			)
		)
		(duplicate_pad_numbers_are_jumpers no)
		(fp_poly
			(pts
				(arc
					(start 0 0.4064)
					(mid 0 -0.4064)
					(end 0 0.4064)
				)
			)
			(stroke
				(width 0)
				(type default)
			)
			(fill no)
			(layer "F.CrtYd")
		)
		(fp_poly
			(pts
				(arc
					(start 0 0.7112)
					(mid 0 -0.7112)
					(end 0 0.7112)
				)
			)
			(stroke
				(width 0)
				(type default)
			)
			(fill no)
			(layer "F.Fab")
		)
		(pad "1" smd circle
			(at 0 0 90)
			(size 0.8128 0.8128)
			(layers "F.Cu" "F.Mask" "F.Paste")
			(net "TEMP_1_ALERT")
		)
	)
	(footprint ""
		(layer "F.Cu")
		(at 55.4482 -9.525 180)
		(property "Reference" "R72"
			(at 0 0 180)
			(layer "F.SilkS")
			(hide yes)
			(effects
				(font
					(size 1.27 1.27)
				)
			)
		)
		(property "Value" "4K7R2F-GP"
			(at 0.064008 -3.993896 180)
			(unlocked yes)
			(layer "F.Fab")
			(hide yes)
			(effects
				(font
					(size 1.016 1.016)
					(thickness 0.1524)
				)
			)
		)
		(property "Device Type" "R402H16"
			(at 0.064008 -5.517896 180)
			(unlocked yes)
			(layer "F.Fab")
			(hide yes)
			(effects
				(font
					(size 1.016 1.016)
					(thickness 0.1524)
				)
			)
		)
		(duplicate_pad_numbers_are_jumpers no)
		(fp_line
			(start 0.508 -0.9398)
			(end -0.508 -0.9398)
			(stroke
				(width 0.1524)
				(type default)
			)
			(layer "F.SilkS")
		)
		(fp_line
			(start -0.508 -0.9398)
			(end -0.508 0.9398)
			(stroke
				(width 0.1524)
				(type default)
			)
			(layer "F.SilkS")
		)
		(fp_rect
			(start -0.508 0.9398)
			(end 0.508 -0.9398)
			(stroke
				(width 0)
				(type default)
			)
			(fill no)
			(layer "F.CrtYd")
		)
		(fp_rect
			(start -0.508 0.9398)
			(end 0.508 -0.9398)
			(stroke
				(width 0)
				(type default)
			)
			(fill no)
			(layer "F.Fab")
		)
		(pad "1" smd custom
			(at 0 -0.4445 180)
			(size 0.1397 0.1397)
			(layers "F.Cu" "F.Mask" "F.Paste")
			(net "P3V3_STBY_B")
			(options
				(clearance outline)
				(anchor circle)
			)
			(primitives
				(gr_poly
					(pts
						(arc
							(start -0.1778 -0.2794)
							(mid -0.249642 -0.249642)
							(end -0.2794 -0.1778)
						)
						(arc
							(start -0.2794 0.1778)
							(mid -0.249642 0.249642)
							(end -0.1778 0.2794)
						)
						(arc
							(start 0.1778 0.2794)
							(mid 0.249642 0.249642)
							(end 0.2794 0.1778)
						)
						(arc
							(start 0.2794 -0.1778)
							(mid 0.249642 -0.249642)
							(end 0.1778 -0.2794)
						)
					)
					(width 0)
					(fill yes)
				)
			)
		)
		(pad "2" smd custom
			(at 0 0.4445 180)
			(size 0.1397 0.1397)
			(layers "F.Cu" "F.Mask" "F.Paste")
			(net "TCA9555_B_A1")
			(options
				(clearance outline)
				(anchor circle)
			)
			(primitives
				(gr_poly
					(pts
						(arc
							(start -0.1778 -0.2794)
							(mid -0.249642 -0.249642)
							(end -0.2794 -0.1778)
						)
						(arc
							(start -0.2794 0.1778)
							(mid -0.249642 0.249642)
							(end -0.1778 0.2794)
						)
						(arc
							(start 0.1778 0.2794)
							(mid 0.249642 0.249642)
							(end 0.2794 0.1778)
						)
						(arc
							(start 0.2794 -0.1778)
							(mid 0.249642 -0.249642)
							(end 0.1778 -0.2794)
						)
					)
					(width 0)
					(fill yes)
				)
			)
		)
	)
	(footprint ""
		(layer "F.Cu")
		(at 8.199882 -34.99993)
		(property "Reference" "SW3"
			(at 0 0 0)
			(layer "F.SilkS")
			(hide yes)
			(effects
				(font
					(size 1.27 1.27)
				)
			)
		)
		(property "Value" "SW-TACT-4P-214-GP"
			(at 5.97154 0.7747 0)
			(unlocked yes)
			(layer "F.Fab")
			(hide yes)
			(effects
				(font
					(size 2.54 2.54)
					(thickness 0.381)
				)
			)
		)
		(property "Device Type" "DTSM-62N-Q-TR"
			(at 5.97154 -0.7493 0)
			(unlocked yes)
			(layer "F.Fab")
			(hide yes)
			(effects
				(font
					(size 2.54 2.54)
					(thickness 0.381)
				)
			)
		)
		(duplicate_pad_numbers_are_jumpers no)
		(fp_line
			(start -5.0927 -2.8956)
			(end -5.0927 -1.6002)
			(stroke
				(width 0.3302)
				(type default)
			)
			(layer "F.SilkS")
		)
		(fp_line
			(start -5.0038 -3.3528)
			(end 5.0038 -3.3528)
			(stroke
				(width 0.1524)
				(type default)
			)
			(layer "F.SilkS")
		)
		(fp_line
			(start -5.0038 -1.3462)
			(end -5.0038 -3.3528)
			(stroke
				(width 0.1524)
				(type default)
			)
			(layer "F.SilkS")
		)
		(fp_line
			(start -5.0038 1.3462)
			(end -3.3528 1.3462)
			(stroke
				(width 0.1524)
				(type default)
			)
			(layer "F.SilkS")
		)
		(fp_line
			(start -5.0038 3.3528)
			(end -5.0038 1.3462)
			(stroke
				(width 0.1524)
				(type default)
			)
			(layer "F.SilkS")
		)
		(fp_line
			(start -3.3528 -1.3462)
			(end -5.0038 -1.3462)
			(stroke
				(width 0.1524)
				(type default)
			)
			(layer "F.SilkS")
		)
		(fp_line
			(start -3.3528 1.3462)
			(end -3.3528 -1.3462)
			(stroke
				(width 0.1524)
				(type default)
			)
			(layer "F.SilkS")
		)
		(fp_line
			(start 3.3528 -1.3462)
			(end 3.3528 1.3462)
			(stroke
				(width 0.1524)
				(type default)
			)
			(layer "F.SilkS")
		)
		(fp_line
			(start 3.3528 1.3462)
			(end 5.0038 1.3462)
			(stroke
				(width 0.1524)
				(type default)
			)
			(layer "F.SilkS")
		)
		(fp_line
			(start 5.0038 -3.3528)
			(end 5.0038 -1.3462)
			(stroke
				(width 0.1524)
				(type default)
			)
			(layer "F.SilkS")
		)
		(fp_line
			(start 5.0038 -1.3462)
			(end 3.3528 -1.3462)
			(stroke
				(width 0.1524)
				(type default)
			)
			(layer "F.SilkS")
		)
		(fp_line
			(start 5.0038 1.3462)
			(end 5.0038 3.3528)
			(stroke
				(width 0.1524)
				(type default)
			)
			(layer "F.SilkS")
		)
		(fp_line
			(start 5.0038 3.3528)
			(end -5.0038 3.3528)
			(stroke
				(width 0.1524)
				(type default)
			)
			(layer "F.SilkS")
		)
		(fp_poly
			(pts
				(xy -5.072888 -2.29108) (xy -5.707888 -1.65608) (xy -5.707888 -2.92608)
			)
			(stroke
				(width 0)
				(type default)
			)
			(fill yes)
			(layer "F.SilkS")
		)
		(fp_poly
			(pts
				(xy -3.0988 3.0988) (xy -3.0988 2.5908) (xy -4.4958 2.5908) (xy -4.4958 1.8796) (xy -3.0988 1.8796)
				(xy -3.0988 -1.8796) (xy -4.4958 -1.8796) (xy -4.4958 -2.5908) (xy -3.0988 -2.5908) (xy -3.0988 -3.0988)
				(xy 3.0988 -3.0988) (xy 3.0988 -2.5908) (xy 4.4958 -2.5908) (xy 4.4958 -1.8796) (xy 3.0988 -1.8796)
				(xy 3.0988 1.8796) (xy 4.4958 1.8796) (xy 4.4958 2.5908) (xy 3.0988 2.5908) (xy 3.0988 3.0988)
			)
			(stroke
				(width 0)
				(type default)
			)
			(fill no)
			(layer "F.CrtYd")
		)
		(fp_poly
			(pts
				(xy -5.2578 3.6068) (xy -5.2578 1.0922) (xy -3.6068 1.0922) (xy -3.6068 -1.0922) (xy -5.2578 -1.0922)
				(xy -5.2578 -3.6068) (xy 5.2578 -3.6068) (xy 5.2578 -1.0922) (xy 3.6068 -1.0922) (xy 3.6068 -0.00635)
				(xy 3.0988 -0.00635) (xy 3.0988 -1.8796) (xy 4.4958 -1.8796) (xy 4.4958 -2.5908) (xy 3.0988 -2.5908)
				(xy 3.0988 -3.0988) (xy -3.0988 -3.0988) (xy -3.0988 -2.5908) (xy -4.4958 -2.5908) (xy -4.4958 -1.8796)
				(xy -3.0988 -1.8796) (xy -3.0988 1.8796) (xy -4.4958 1.8796) (xy -4.4958 2.5908) (xy -3.0988 2.5908)
				(xy -3.0988 3.0988) (xy 3.0988 3.0988) (xy 3.0988 2.5908) (xy 4.4958 2.5908) (xy 4.4958 1.8796)
				(xy 3.0988 1.8796) (xy 3.0988 0.00635) (xy 3.6068 0.00635) (xy 3.6068 1.0922) (xy 5.2578 1.0922)
				(xy 5.2578 3.6068)
			)
			(stroke
				(width 0)
				(type default)
			)
			(fill no)
			(layer "F.CrtYd")
		)
		(fp_poly
			(pts
				(xy -5.2578 3.6068) (xy -5.2578 1.0922) (xy -3.6068 1.0922) (xy -3.6068 -1.0922) (xy -5.2578 -1.0922)
				(xy -5.2578 -3.6068) (xy 5.2578 -3.6068) (xy 5.2578 -1.0922) (xy 3.6068 -1.0922) (xy 3.6068 1.0922)
				(xy 5.2578 1.0922) (xy 5.2578 3.6068)
			)
			(stroke
				(width 0)
				(type default)
			)
			(fill no)
			(layer "F.Fab")
		)
		(pad "T1" smd rect
			(at -3.9751 -2.249932)
			(size 1.5494 1.2954)
			(layers "F.Cu" "F.Mask" "F.Paste")
			(net "SYS_RESET_BTN_A")
		)
		(pad "T2" smd rect
			(at 3.9751 -2.249932)
			(size 1.5494 1.2954)
			(layers "F.Cu" "F.Mask" "F.Paste")
			(net "SYS_RESET_BTN_A")
		)
		(pad "T3" smd rect
			(at -3.9751 2.249932)
			(size 1.5494 1.2954)
			(layers "F.Cu" "F.Mask" "F.Paste")
			(net "GND")
		)
		(pad "T4" smd rect
			(at 3.9751 2.249932)
			(size 1.5494 1.2954)
			(layers "F.Cu" "F.Mask" "F.Paste")
			(net "GND")
		)
	)
	(footprint ""
		(layer "F.Cu")
		(at 14.3002 -12.573 90)
		(property "Reference" "U1"
			(at 0 0 90)
			(layer "F.SilkS")
			(hide yes)
			(effects
				(font
					(size 1.27 1.27)
				)
			)
		)
		(property "Value" "TS5A23157DGSR-GP"
			(at 0 -11.811 90)
			(unlocked yes)
			(layer "F.Fab")
			(hide yes)
			(effects
				(font
					(size 2.54 2.54)
					(thickness 0.381)
				)
			)
		)
		(property "Device Type" "MSOP10H44"
			(at 0 -13.335 90)
			(unlocked yes)
			(layer "F.Fab")
			(hide yes)
			(effects
				(font
					(size 2.54 2.54)
					(thickness 0.381)
				)
			)
		)
		(duplicate_pad_numbers_are_jumpers no)
		(fp_line
			(start 1.143 -1.016)
			(end 1.143 1.016)
			(stroke
				(width 0.1524)
				(type default)
			)
			(layer "F.SilkS")
		)
		(fp_line
			(start -2.0066 -1.016)
			(end 1.143 -1.016)
			(stroke
				(width 0.1524)
				(type default)
			)
			(layer "F.SilkS")
		)
		(fp_line
			(start -1.5748 0)
			(end -1.9558 -0.381)
			(stroke
				(width 0.1524)
				(type default)
			)
			(layer "F.SilkS")
		)
		(fp_line
			(start -1.5748 0)
			(end -1.9558 0.381)
			(stroke
				(width 0.1524)
				(type default)
			)
			(layer "F.SilkS")
		)
		(fp_line
			(start 1.143 1.016)
			(end -2.0066 1.016)
			(stroke
				(width 0.1524)
				(type default)
			)
			(layer "F.SilkS")
		)
		(fp_line
			(start -1.8288 1.016)
			(end -1.8288 3.048)
			(stroke
				(width 0.508)
				(type default)
			)
			(layer "F.SilkS")
		)
		(fp_line
			(start -2.0066 1.016)
			(end -2.0066 -1.016)
			(stroke
				(width 0.1524)
				(type default)
			)
			(layer "F.SilkS")
		)
		(fp_poly
			(pts
				(xy -2.0828 3.3401) (xy 2.0828 3.3401) (xy 2.0828 -3.3401) (xy -2.0828 -3.3401)
			)
			(stroke
				(width 0)
				(type default)
			)
			(fill no)
			(layer "F.CrtYd")
		)
		(fp_poly
			(pts
				(xy -2.0828 3.3401) (xy 2.0828 3.3401) (xy 2.0828 -3.3401) (xy -2.0828 -3.3401)
			)
			(stroke
				(width 0)
				(type default)
			)
			(fill no)
			(layer "F.Fab")
		)
		(pad "1" smd rect
			(at -0.99949 2.0701 90)
			(size 0.3048 1.524)
			(layers "F.Cu" "F.Mask" "F.Paste")
			(net "UART_SEL_A_MUX_R")
		)
		(pad "2" smd rect
			(at -0.50038 2.0701 90)
			(size 0.3048 1.524)
			(layers "F.Cu" "F.Mask" "F.Paste")
			(net "UART_EXP_A_TX")
		)
		(pad "3" smd rect
			(at 0 2.0701 90)
			(size 0.3048 1.524)
			(layers "F.Cu" "F.Mask" "F.Paste")
			(net "GND")
		)
		(pad "4" smd rect
			(at 0.50038 2.0701 90)
			(size 0.3048 1.524)
			(layers "F.Cu" "F.Mask" "F.Paste")
			(net "UART_EXP_A_RX")
		)
		(pad "5" smd rect
			(at 0.99949 2.0701 90)
			(size 0.3048 1.524)
			(layers "F.Cu" "F.Mask" "F.Paste")
			(net "UART_SEL_A_MUX_R")
		)
		(pad "6" smd rect
			(at 0.99949 -2.0701 90)
			(size 0.3048 1.524)
			(layers "F.Cu" "F.Mask" "F.Paste")
			(net "UART_A_RX")
		)
		(pad "7" smd rect
			(at 0.50038 -2.0701 90)
			(size 0.3048 1.524)
			(layers "F.Cu" "F.Mask" "F.Paste")
			(net "UART_IOC_A_RX")
		)
		(pad "8" smd rect
			(at 0 -2.0701 90)
			(size 0.3048 1.524)
			(layers "F.Cu" "F.Mask" "F.Paste")
			(net "P3V3_STBY_A")
		)
		(pad "9" smd rect
			(at -0.50038 -2.0701 90)
			(size 0.3048 1.524)
			(layers "F.Cu" "F.Mask" "F.Paste")
			(net "UART_IOC_A_TX")
		)
		(pad "10" smd rect
			(at -0.99949 -2.0701 90)
			(size 0.3048 1.524)
			(layers "F.Cu" "F.Mask" "F.Paste")
			(net "UART_A_TX")
		)
	)
	(footprint ""
		(layer "F.Cu")
		(at 46.609 -10.541 180)
		(property "Reference" "C6"
			(at 0 0 180)
			(layer "F.SilkS")
			(hide yes)
			(effects
				(font
					(size 1.27 1.27)
				)
			)
		)
		(property "Value" "SCD1U16V2KX-3GP"
			(at 1.1811 -3.3909 180)
			(unlocked yes)
			(layer "F.Fab")
			(hide yes)
			(effects
				(font
					(size 2.54 2.54)
					(thickness 0.381)
				)
			)
		)
		(property "Device Type" "C402H22"
			(at 1.1811 -4.9149 180)
			(unlocked yes)
			(layer "F.Fab")
			(hide yes)
			(effects
				(font
					(size 2.54 2.54)
					(thickness 0.381)
				)
			)
		)
		(duplicate_pad_numbers_are_jumpers no)
		(fp_rect
			(start -0.4318 0.9525)
			(end 0.4318 -0.9525)
			(stroke
				(width 0)
				(type default)
			)
			(fill no)
			(layer "F.CrtYd")
		)
		(fp_rect
			(start -0.4318 0.9525)
			(end 0.4318 -0.9525)
			(stroke
				(width 0)
				(type default)
			)
			(fill no)
			(layer "F.Fab")
		)
		(pad "1" smd custom
			(at 0 -0.4445 180)
			(size 0.1524 0.1524)
			(layers "F.Cu" "F.Mask" "F.Paste")
			(net "P3V3_STBY_B")
			(options
				(clearance outline)
				(anchor circle)
			)
			(primitives
				(gr_poly
					(pts
						(arc
							(start 0.3048 -0.2032)
							(mid 0.275042 -0.275042)
							(end 0.2032 -0.3048)
						)
						(arc
							(start -0.2032 -0.3048)
							(mid -0.275042 -0.275042)
							(end -0.3048 -0.2032)
						)
						(arc
							(start -0.3048 0.2032)
							(mid -0.275042 0.275042)
							(end -0.2032 0.3048)
						)
						(arc
							(start 0.2032 0.3048)
							(mid 0.275042 0.275042)
							(end 0.3048 0.2032)
						)
					)
					(width 0)
					(fill yes)
				)
			)
		)
		(pad "2" smd custom
			(at 0 0.4445 180)
			(size 0.1524 0.1524)
			(layers "F.Cu" "F.Mask" "F.Paste")
			(net "GND")
			(options
				(clearance outline)
				(anchor circle)
			)
			(primitives
				(gr_poly
					(pts
						(arc
							(start 0.3048 -0.2032)
							(mid 0.275042 -0.275042)
							(end 0.2032 -0.3048)
						)
						(arc
							(start -0.2032 -0.3048)
							(mid -0.275042 -0.275042)
							(end -0.3048 -0.2032)
						)
						(arc
							(start -0.3048 0.2032)
							(mid -0.275042 0.275042)
							(end -0.2032 0.3048)
						)
						(arc
							(start 0.2032 0.3048)
							(mid 0.275042 0.275042)
							(end 0.3048 0.2032)
						)
					)
					(width 0)
					(fill yes)
				)
			)
		)
	)
	(footprint ""
		(layer "F.Cu")
		(at 29.550106 -19.99996 90)
		(property "Reference" "SCW1"
			(at 0 0 90)
			(layer "F.SilkS")
			(hide yes)
			(effects
				(font
					(size 1.27 1.27)
				)
			)
		)
		(property "Value" "STFT363B238R224H453-GP"
			(at 7.0612 0.7747 90)
			(unlocked yes)
			(layer "F.Fab")
			(hide yes)
			(effects
				(font
					(size 2.54 2.54)
					(thickness 0.381)
				)
			)
		)
		(property "Device Type" "STFT363B238R224H453"
			(at 7.0612 -0.7493 90)
			(unlocked yes)
			(layer "F.Fab")
			(hide yes)
			(effects
				(font
					(size 2.54 2.54)
					(thickness 0.381)
				)
			)
		)
		(duplicate_pad_numbers_are_jumpers no)
		(fp_circle
			(center 0 0)
			(end 0 5.3594)
			(stroke
				(width 0.3048)
				(type default)
			)
			(fill no)
			(layer "F.SilkS")
		)
		(fp_poly
			(pts
				(arc
					(start 0 3.5306)
					(mid 0 -3.5306)
					(end 0 3.5306)
				)
			)
			(stroke
				(width 0)
				(type default)
			)
			(fill no)
			(layer "B.CrtYd")
		)
		(fp_poly
			(pts
				(arc
					(start 0 5.0038)
					(mid 0 -5.0038)
					(end 0 5.0038)
				)
			)
			(stroke
				(width 0)
				(type default)
			)
			(fill no)
			(layer "F.CrtYd")
		)
		(fp_poly
			(pts
				(arc
					(start 5.5118 0.00635)
					(mid -5.511804 0)
					(end 5.5118 -0.00635)
				)
				(arc
					(start 5.0038 -0.00635)
					(mid -5.003804 0)
					(end 5.0038 0.00635)
				)
			)
			(stroke
				(width 0)
				(type default)
			)
			(fill no)
			(layer "F.CrtYd")
		)
		(fp_poly
			(pts
				(arc
					(start 0 3.5306)
					(mid 0 -3.5306)
					(end 0 3.5306)
				)
			)
			(stroke
				(width 0)
				(type default)
			)
			(fill no)
			(layer "B.Fab")
		)
		(fp_poly
			(pts
				(arc
					(start 0 5.5118)
					(mid 0 -5.5118)
					(end 0 5.5118)
				)
			)
			(stroke
				(width 0)
				(type default)
			)
			(fill no)
			(layer "F.Fab")
		)
		(pad "1" thru_hole circle
			(at 0 0 90)
			(size 9.2202 9.2202)
			(drill 5.6896)
			(layers "*.Cu" "*.Mask")
			(remove_unused_layers no)
			(net "Net_76")
			(clearance -1.2573)
			(thermal_gap 0.3302)
			(padstack
				(mode front_inner_back)
				(layer "Inner"
					(shape circle)
					(size 6.0452 6.0452)
					(clearance 0.3302)
				)
				(layer "B.Cu"
					(shape circle)
					(size 6.0452 6.0452)
					(clearance 0.3302)
				)
			)
		)
	)
	(footprint ""
		(layer "F.Cu")
		(at 11.303 -7.4168)
		(property "Reference" "U10"
			(at 0 0 0)
			(layer "F.SilkS")
			(hide yes)
			(effects
				(font
					(size 1.27 1.27)
				)
			)
		)
		(property "Value" "SNLVC1G126DCKR-GP"
			(at -2.3368 -8.6868 0)
			(unlocked yes)
			(layer "F.Fab")
			(hide yes)
			(effects
				(font
					(size 1.016 1.016)
					(thickness 0.1524)
				)
			)
		)
		(property "Device Type" "SC70-5H44"
			(at -2.3114 -10.414 0)
			(unlocked yes)
			(layer "F.Fab")
			(hide yes)
			(effects
				(font
					(size 1.016 1.016)
					(thickness 0.1524)
				)
			)
		)
		(duplicate_pad_numbers_are_jumpers no)
		(fp_line
			(start -1.27 -1.7018)
			(end 1.27 -1.7018)
			(stroke
				(width 0.1524)
				(type default)
			)
			(layer "F.SilkS")
		)
		(fp_line
			(start -1.27 1.7018)
			(end -1.27 -1.7018)
			(stroke
				(width 0.1524)
				(type default)
			)
			(layer "F.SilkS")
		)
		(fp_line
			(start 0.6604 -1.8034)
			(end 1.3843 -1.8034)
			(stroke
				(width 0.3302)
				(type default)
			)
			(layer "F.SilkS")
		)
		(fp_line
			(start 1.27 -1.7018)
			(end 1.27 1.7018)
			(stroke
				(width 0.1524)
				(type default)
			)
			(layer "F.SilkS")
		)
		(fp_line
			(start 1.27 1.7018)
			(end -1.27 1.7018)
			(stroke
				(width 0.1524)
				(type default)
			)
			(layer "F.SilkS")
		)
		(fp_line
			(start 1.3843 -1.8034)
			(end 1.3843 -1.1176)
			(stroke
				(width 0.3302)
				(type default)
			)
			(layer "F.SilkS")
		)
		(fp_rect
			(start -1.524 1.9558)
			(end 1.524 -1.9558)
			(stroke
				(width 0)
				(type default)
			)
			(fill no)
			(layer "F.CrtYd")
		)
		(fp_poly
			(pts
				(xy -1.524 -1.9558) (xy 1.524 -1.9558) (xy 1.524 1.9558) (xy -1.524 1.9558)
			)
			(stroke
				(width 0)
				(type default)
			)
			(fill no)
			(layer "F.Fab")
		)
		(pad "1" smd rect
			(at 0.65024 -0.8255)
			(size 0.4064 1.2192)
			(layers "F.Cu" "F.Mask" "F.Paste")
			(net "DEBUG_CARD_A_PRSNT")
		)
		(pad "2" smd rect
			(at 0 -0.8255)
			(size 0.4064 1.2192)
			(layers "F.Cu" "F.Mask" "F.Paste")
			(net "UART_A_TX")
		)
		(pad "3" smd rect
			(at -0.65024 -0.8255)
			(size 0.4064 1.2192)
			(layers "F.Cu" "F.Mask" "F.Paste")
			(net "GND")
		)
		(pad "4" smd rect
			(at -0.65024 0.8255)
			(size 0.4064 1.2192)
			(layers "F.Cu" "F.Mask" "F.Paste")
			(net "UART_DEBUG_A_TX")
		)
		(pad "5" smd rect
			(at 0.65024 0.8255)
			(size 0.4064 1.2192)
			(layers "F.Cu" "F.Mask" "F.Paste")
			(net "P3V3_STBY_A")
		)
	)
	(footprint ""
		(layer "F.Cu")
		(at 48.951896 -20.07362)
		(property "Reference" "C23"
			(at 0 0 0)
			(layer "F.SilkS")
			(hide yes)
			(effects
				(font
					(size 1.27 1.27)
				)
			)
		)
		(property "Value" "SCD1U16V2KX-3GP"
			(at 1.1811 -2.7051 0)
			(unlocked yes)
			(layer "F.Fab")
			(hide yes)
			(effects
				(font
					(size 1.016 1.016)
					(thickness 0.1524)
				)
			)
		)
		(property "Device Type" "C402H22"
			(at 1.1811 -4.2291 0)
			(unlocked yes)
			(layer "F.Fab")
			(hide yes)
			(effects
				(font
					(size 1.016 1.016)
					(thickness 0.1524)
				)
			)
		)
		(duplicate_pad_numbers_are_jumpers no)
		(fp_rect
			(start -0.4318 0.9525)
			(end 0.4318 -0.9525)
			(stroke
				(width 0)
				(type default)
			)
			(fill no)
			(layer "F.CrtYd")
		)
		(fp_rect
			(start -0.4318 0.9525)
			(end 0.4318 -0.9525)
			(stroke
				(width 0)
				(type default)
			)
			(fill no)
			(layer "F.Fab")
		)
		(pad "1" smd custom
			(at 0 -0.4445)
			(size 0.1524 0.1524)
			(layers "F.Cu" "F.Mask" "F.Paste")
			(net "P3V3_STBY_B")
			(options
				(clearance outline)
				(anchor circle)
			)
			(primitives
				(gr_poly
					(pts
						(arc
							(start 0.3048 -0.2032)
							(mid 0.275042 -0.275042)
							(end 0.2032 -0.3048)
						)
						(arc
							(start -0.2032 -0.3048)
							(mid -0.275042 -0.275042)
							(end -0.3048 -0.2032)
						)
						(arc
							(start -0.3048 0.2032)
							(mid -0.275042 0.275042)
							(end -0.2032 0.3048)
						)
						(arc
							(start 0.2032 0.3048)
							(mid 0.275042 0.275042)
							(end 0.3048 0.2032)
						)
					)
					(width 0)
					(fill yes)
				)
			)
		)
		(pad "2" smd custom
			(at 0 0.4445)
			(size 0.1524 0.1524)
			(layers "F.Cu" "F.Mask" "F.Paste")
			(net "GND")
			(options
				(clearance outline)
				(anchor circle)
			)
			(primitives
				(gr_poly
					(pts
						(arc
							(start 0.3048 -0.2032)
							(mid 0.275042 -0.275042)
							(end 0.2032 -0.3048)
						)
						(arc
							(start -0.2032 -0.3048)
							(mid -0.275042 -0.275042)
							(end -0.3048 -0.2032)
						)
						(arc
							(start -0.3048 0.2032)
							(mid -0.275042 0.275042)
							(end -0.2032 0.3048)
						)
						(arc
							(start 0.2032 0.3048)
							(mid 0.275042 0.275042)
							(end 0.3048 0.2032)
						)
					)
					(width 0)
					(fill yes)
				)
			)
		)
	)
	(footprint ""
		(layer "F.Cu")
		(at 52.197 -12.827)
		(property "Reference" "R14"
			(at 0 0 0)
			(layer "F.SilkS")
			(hide yes)
			(effects
				(font
					(size 1.27 1.27)
				)
			)
		)
		(property "Value" "0R2J-2-GP"
			(at 0.064008 -4.679696 0)
			(unlocked yes)
			(layer "F.Fab")
			(hide yes)
			(effects
				(font
					(size 2.54 2.54)
					(thickness 0.381)
				)
			)
		)
		(property "Device Type" "R402H16"
			(at 0.064008 -6.203696 0)
			(unlocked yes)
			(layer "F.Fab")
			(hide yes)
			(effects
				(font
					(size 2.54 2.54)
					(thickness 0.381)
				)
			)
		)
		(duplicate_pad_numbers_are_jumpers no)
		(fp_line
			(start -0.508 -0.9398)
			(end -0.508 0.9398)
			(stroke
				(width 0.1524)
				(type default)
			)
			(layer "F.SilkS")
		)
		(fp_line
			(start 0.508 -0.9398)
			(end -0.508 -0.9398)
			(stroke
				(width 0.1524)
				(type default)
			)
			(layer "F.SilkS")
		)
		(fp_rect
			(start -0.508 0.9398)
			(end 0.508 -0.9398)
			(stroke
				(width 0)
				(type default)
			)
			(fill no)
			(layer "F.CrtYd")
		)
		(fp_rect
			(start -0.508 0.9398)
			(end 0.508 -0.9398)
			(stroke
				(width 0)
				(type default)
			)
			(fill no)
			(layer "F.Fab")
		)
		(pad "1" smd custom
			(at 0 -0.4445)
			(size 0.1397 0.1397)
			(layers "F.Cu" "F.Mask" "F.Paste")
			(net "I2C_DEBUG_B_SCL_R")
			(options
				(clearance outline)
				(anchor circle)
			)
			(primitives
				(gr_poly
					(pts
						(arc
							(start -0.1778 -0.2794)
							(mid -0.249642 -0.249642)
							(end -0.2794 -0.1778)
						)
						(arc
							(start -0.2794 0.1778)
							(mid -0.249642 0.249642)
							(end -0.1778 0.2794)
						)
						(arc
							(start 0.1778 0.2794)
							(mid 0.249642 0.249642)
							(end 0.2794 0.1778)
						)
						(arc
							(start 0.2794 -0.1778)
							(mid 0.249642 -0.249642)
							(end 0.1778 -0.2794)
						)
					)
					(width 0)
					(fill yes)
				)
			)
		)
		(pad "2" smd custom
			(at 0 0.4445)
			(size 0.1397 0.1397)
			(layers "F.Cu" "F.Mask" "F.Paste")
			(net "I2C_DEBUG_B_SCL_L")
			(options
				(clearance outline)
				(anchor circle)
			)
			(primitives
				(gr_poly
					(pts
						(arc
							(start -0.1778 -0.2794)
							(mid -0.249642 -0.249642)
							(end -0.2794 -0.1778)
						)
						(arc
							(start -0.2794 0.1778)
							(mid -0.249642 0.249642)
							(end -0.1778 0.2794)
						)
						(arc
							(start 0.1778 0.2794)
							(mid 0.249642 0.249642)
							(end 0.2794 0.1778)
						)
						(arc
							(start 0.2794 -0.1778)
							(mid 0.249642 -0.249642)
							(end 0.1778 -0.2794)
						)
					)
					(width 0)
					(fill yes)
				)
			)
		)
	)
	(footprint ""
		(layer "F.Cu")
		(at 49.395634 -30.861 -90)
		(property "Reference" "R52"
			(at 0 0 270)
			(layer "F.SilkS")
			(hide yes)
			(effects
				(font
					(size 1.27 1.27)
				)
			)
		)
		(property "Value" "1KR2F-3-GP"
			(at 0.064008 -4.679696 270)
			(unlocked yes)
			(layer "F.Fab")
			(hide yes)
			(effects
				(font
					(size 2.54 2.54)
					(thickness 0.381)
				)
			)
		)
		(property "Device Type" "R402H16"
			(at 0.064008 -6.203696 270)
			(unlocked yes)
			(layer "F.Fab")
			(hide yes)
			(effects
				(font
					(size 2.54 2.54)
					(thickness 0.381)
				)
			)
		)
		(duplicate_pad_numbers_are_jumpers no)
		(fp_line
			(start -0.508 -0.9398)
			(end -0.508 0.9398)
			(stroke
				(width 0.1524)
				(type default)
			)
			(layer "F.SilkS")
		)
		(fp_line
			(start 0.508 -0.9398)
			(end -0.508 -0.9398)
			(stroke
				(width 0.1524)
				(type default)
			)
			(layer "F.SilkS")
		)
		(fp_rect
			(start -0.508 0.9398)
			(end 0.508 -0.9398)
			(stroke
				(width 0)
				(type default)
			)
			(fill no)
			(layer "F.CrtYd")
		)
		(fp_rect
			(start -0.508 0.9398)
			(end 0.508 -0.9398)
			(stroke
				(width 0)
				(type default)
			)
			(fill no)
			(layer "F.Fab")
		)
		(pad "1" smd custom
			(at 0 -0.4445 270)
			(size 0.1397 0.1397)
			(layers "F.Cu" "F.Mask" "F.Paste")
			(net "P3V3_STBY_B")
			(options
				(clearance outline)
				(anchor circle)
			)
			(primitives
				(gr_poly
					(pts
						(arc
							(start -0.1778 -0.2794)
							(mid -0.249642 -0.249642)
							(end -0.2794 -0.1778)
						)
						(arc
							(start -0.2794 0.1778)
							(mid -0.249642 0.249642)
							(end -0.1778 0.2794)
						)
						(arc
							(start 0.1778 0.2794)
							(mid 0.249642 0.249642)
							(end 0.2794 0.1778)
						)
						(arc
							(start 0.2794 -0.1778)
							(mid 0.249642 -0.249642)
							(end 0.1778 -0.2794)
						)
					)
					(width 0)
					(fill yes)
				)
			)
		)
		(pad "2" smd custom
			(at 0 0.4445 270)
			(size 0.1397 0.1397)
			(layers "F.Cu" "F.Mask" "F.Paste")
			(net "SYS_RESET_BTN_B_N_R")
			(options
				(clearance outline)
				(anchor circle)
			)
			(primitives
				(gr_poly
					(pts
						(arc
							(start -0.1778 -0.2794)
							(mid -0.249642 -0.249642)
							(end -0.2794 -0.1778)
						)
						(arc
							(start -0.2794 0.1778)
							(mid -0.249642 0.249642)
							(end -0.1778 0.2794)
						)
						(arc
							(start 0.1778 0.2794)
							(mid 0.249642 0.249642)
							(end 0.2794 0.1778)
						)
						(arc
							(start 0.2794 -0.1778)
							(mid 0.249642 -0.249642)
							(end 0.1778 -0.2794)
						)
					)
					(width 0)
					(fill yes)
				)
			)
		)
	)
	(footprint ""
		(layer "F.Cu")
		(at 20.1168 -18.2372)
		(property "Reference" "R63"
			(at 0 0 0)
			(layer "F.SilkS")
			(hide yes)
			(effects
				(font
					(size 1.27 1.27)
				)
			)
		)
		(property "Value" "4K7R2F-GP"
			(at 0.064008 -3.993896 0)
			(unlocked yes)
			(layer "F.Fab")
			(hide yes)
			(effects
				(font
					(size 1.016 1.016)
					(thickness 0.1524)
				)
			)
		)
		(property "Device Type" "R402H16"
			(at 0.064008 -5.517896 0)
			(unlocked yes)
			(layer "F.Fab")
			(hide yes)
			(effects
				(font
					(size 1.016 1.016)
					(thickness 0.1524)
				)
			)
		)
		(duplicate_pad_numbers_are_jumpers no)
		(fp_line
			(start -0.508 -0.9398)
			(end -0.508 0.9398)
			(stroke
				(width 0.1524)
				(type default)
			)
			(layer "F.SilkS")
		)
		(fp_line
			(start 0.508 -0.9398)
			(end -0.508 -0.9398)
			(stroke
				(width 0.1524)
				(type default)
			)
			(layer "F.SilkS")
		)
		(fp_rect
			(start -0.508 0.9398)
			(end 0.508 -0.9398)
			(stroke
				(width 0)
				(type default)
			)
			(fill no)
			(layer "F.CrtYd")
		)
		(fp_rect
			(start -0.508 0.9398)
			(end 0.508 -0.9398)
			(stroke
				(width 0)
				(type default)
			)
			(fill no)
			(layer "F.Fab")
		)
		(pad "1" smd custom
			(at 0 -0.4445)
			(size 0.1397 0.1397)
			(layers "F.Cu" "F.Mask" "F.Paste")
			(net "P3V3_STBY_A")
			(options
				(clearance outline)
				(anchor circle)
			)
			(primitives
				(gr_poly
					(pts
						(arc
							(start -0.1778 -0.2794)
							(mid -0.249642 -0.249642)
							(end -0.2794 -0.1778)
						)
						(arc
							(start -0.2794 0.1778)
							(mid -0.249642 0.249642)
							(end -0.1778 0.2794)
						)
						(arc
							(start 0.1778 0.2794)
							(mid 0.249642 0.249642)
							(end 0.2794 0.1778)
						)
						(arc
							(start 0.2794 -0.1778)
							(mid 0.249642 -0.249642)
							(end 0.1778 -0.2794)
						)
					)
					(width 0)
					(fill yes)
				)
			)
		)
		(pad "2" smd custom
			(at 0 0.4445)
			(size 0.1397 0.1397)
			(layers "F.Cu" "F.Mask" "F.Paste")
			(net "TCA9555_A_A1")
			(options
				(clearance outline)
				(anchor circle)
			)
			(primitives
				(gr_poly
					(pts
						(arc
							(start -0.1778 -0.2794)
							(mid -0.249642 -0.249642)
							(end -0.2794 -0.1778)
						)
						(arc
							(start -0.2794 0.1778)
							(mid -0.249642 0.249642)
							(end -0.1778 0.2794)
						)
						(arc
							(start 0.1778 0.2794)
							(mid 0.249642 0.249642)
							(end 0.2794 0.1778)
						)
						(arc
							(start 0.2794 -0.1778)
							(mid 0.249642 -0.249642)
							(end 0.1778 -0.2794)
						)
					)
					(width 0)
					(fill yes)
				)
			)
		)
	)
	(footprint ""
		(layer "F.Cu")
		(at 27.686762 -10.23239)
		(property "Reference" "U19"
			(at 0 0 0)
			(layer "F.SilkS")
			(hide yes)
			(effects
				(font
					(size 1.27 1.27)
				)
			)
		)
		(property "Value" "SN74LVC1G74DCUT-GP"
			(at 0 -11.1252 0)
			(unlocked yes)
			(layer "F.Fab")
			(hide yes)
			(effects
				(font
					(size 1.016 1.016)
					(thickness 0.1524)
				)
			)
		)
		(property "Device Type" "SSOIC8-4H36"
			(at 0 -12.6492 0)
			(unlocked yes)
			(layer "F.Fab")
			(hide yes)
			(effects
				(font
					(size 1.016 1.016)
					(thickness 0.1524)
				)
			)
		)
		(duplicate_pad_numbers_are_jumpers no)
		(fp_line
			(start -1.2954 0.4572)
			(end -1.2954 2.159)
			(stroke
				(width 0.4064)
				(type default)
			)
			(layer "F.SilkS")
		)
		(fp_line
			(start -1.2573 -2.1844)
			(end 1.2573 -2.1844)
			(stroke
				(width 0.1524)
				(type default)
			)
			(layer "F.SilkS")
		)
		(fp_line
			(start -1.2573 -0.3556)
			(end -1.2192 -0.3556)
			(stroke
				(width 0.1524)
				(type default)
			)
			(layer "F.SilkS")
		)
		(fp_line
			(start -1.2573 2.1844)
			(end -1.2573 -2.1844)
			(stroke
				(width 0.1524)
				(type default)
			)
			(layer "F.SilkS")
		)
		(fp_line
			(start -1.2192 -0.3556)
			(end -0.9017 -0.0381)
			(stroke
				(width 0.1524)
				(type default)
			)
			(layer "F.SilkS")
		)
		(fp_line
			(start -1.2065 0.2667)
			(end -1.27 0.2667)
			(stroke
				(width 0.1524)
				(type default)
			)
			(layer "F.SilkS")
		)
		(fp_line
			(start -0.9017 -0.0381)
			(end -1.2065 0.2667)
			(stroke
				(width 0.1524)
				(type default)
			)
			(layer "F.SilkS")
		)
		(fp_line
			(start 1.2573 -2.1844)
			(end 1.2573 2.1844)
			(stroke
				(width 0.1524)
				(type default)
			)
			(layer "F.SilkS")
		)
		(fp_line
			(start 1.2573 2.1844)
			(end -1.2573 2.1844)
			(stroke
				(width 0.1524)
				(type default)
			)
			(layer "F.SilkS")
		)
		(fp_poly
			(pts
				(xy -1.5113 2.4384) (xy 1.5113 2.4384) (xy 1.5113 -2.4384) (xy -1.5113 -2.4384)
			)
			(stroke
				(width 0)
				(type default)
			)
			(fill no)
			(layer "F.CrtYd")
		)
		(fp_poly
			(pts
				(xy -1.5113 -2.4384) (xy 1.5113 -2.4384) (xy 1.5113 2.4384) (xy -1.5113 2.4384)
			)
			(stroke
				(width 0)
				(type default)
			)
			(fill no)
			(layer "F.Fab")
		)
		(pad "1" smd rect
			(at -0.75057 1.1684)
			(size 0.3048 1.524)
			(layers "F.Cu" "F.Mask" "F.Paste")
			(net "DEBUG_HDR_A_UART_SEL")
		)
		(pad "2" smd rect
			(at -0.25019 1.1684)
			(size 0.3048 1.524)
			(layers "F.Cu" "F.Mask" "F.Paste")
			(net "D_FLIP_A_D")
		)
		(pad "3" smd rect
			(at 0.25019 1.1684)
			(size 0.3048 1.524)
			(layers "F.Cu" "F.Mask" "F.Paste")
			(net "D_FLIP_A_Q#")
		)
		(pad "4" smd rect
			(at 0.75057 1.1684)
			(size 0.3048 1.524)
			(layers "F.Cu" "F.Mask" "F.Paste")
			(net "GND")
		)
		(pad "5" smd rect
			(at 0.75057 -1.1684)
			(size 0.3048 1.524)
			(layers "F.Cu" "F.Mask" "F.Paste")
			(net "UART_SEL_A_MUX")
		)
		(pad "6" smd rect
			(at 0.25019 -1.1684)
			(size 0.3048 1.524)
			(layers "F.Cu" "F.Mask" "F.Paste")
			(net "D_FLIP_CLR_A#")
		)
		(pad "7" smd rect
			(at -0.25019 -1.1684)
			(size 0.3048 1.524)
			(layers "F.Cu" "F.Mask" "F.Paste")
			(net "D_FLIP_PRE_A#")
		)
		(pad "8" smd rect
			(at -0.75057 -1.1684)
			(size 0.3048 1.524)
			(layers "F.Cu" "F.Mask" "F.Paste")
			(net "P3V3_STBY_A")
		)
	)
	(footprint ""
		(layer "F.Cu")
		(at 41.4274 -12.2428 -90)
		(property "Reference" "C26"
			(at 0 0 270)
			(layer "F.SilkS")
			(hide yes)
			(effects
				(font
					(size 1.27 1.27)
				)
			)
		)
		(property "Value" "SCD1U16V2KX-3GP"
			(at 1.1811 -2.7051 270)
			(unlocked yes)
			(layer "F.Fab")
			(hide yes)
			(effects
				(font
					(size 1.016 1.016)
					(thickness 0.1524)
				)
			)
		)
		(property "Device Type" "C402H22"
			(at 1.1811 -4.2291 270)
			(unlocked yes)
			(layer "F.Fab")
			(hide yes)
			(effects
				(font
					(size 1.016 1.016)
					(thickness 0.1524)
				)
			)
		)
		(duplicate_pad_numbers_are_jumpers no)
		(fp_rect
			(start -0.4318 0.9525)
			(end 0.4318 -0.9525)
			(stroke
				(width 0)
				(type default)
			)
			(fill no)
			(layer "F.CrtYd")
		)
		(fp_rect
			(start -0.4318 0.9525)
			(end 0.4318 -0.9525)
			(stroke
				(width 0)
				(type default)
			)
			(fill no)
			(layer "F.Fab")
		)
		(pad "1" smd custom
			(at 0 -0.4445 270)
			(size 0.1524 0.1524)
			(layers "F.Cu" "F.Mask" "F.Paste")
			(net "P3V3_STBY_B")
			(options
				(clearance outline)
				(anchor circle)
			)
			(primitives
				(gr_poly
					(pts
						(arc
							(start 0.3048 -0.2032)
							(mid 0.275042 -0.275042)
							(end 0.2032 -0.3048)
						)
						(arc
							(start -0.2032 -0.3048)
							(mid -0.275042 -0.275042)
							(end -0.3048 -0.2032)
						)
						(arc
							(start -0.3048 0.2032)
							(mid -0.275042 0.275042)
							(end -0.2032 0.3048)
						)
						(arc
							(start 0.2032 0.3048)
							(mid 0.275042 0.275042)
							(end 0.3048 0.2032)
						)
					)
					(width 0)
					(fill yes)
				)
			)
		)
		(pad "2" smd custom
			(at 0 0.4445 270)
			(size 0.1524 0.1524)
			(layers "F.Cu" "F.Mask" "F.Paste")
			(net "GND")
			(options
				(clearance outline)
				(anchor circle)
			)
			(primitives
				(gr_poly
					(pts
						(arc
							(start 0.3048 -0.2032)
							(mid 0.275042 -0.275042)
							(end 0.2032 -0.3048)
						)
						(arc
							(start -0.2032 -0.3048)
							(mid -0.275042 -0.275042)
							(end -0.3048 -0.2032)
						)
						(arc
							(start -0.3048 0.2032)
							(mid -0.275042 0.275042)
							(end -0.2032 0.3048)
						)
						(arc
							(start 0.2032 0.3048)
							(mid 0.275042 0.275042)
							(end 0.3048 0.2032)
						)
					)
					(width 0)
					(fill yes)
				)
			)
		)
	)
	(footprint ""
		(layer "F.Cu")
		(at 30.0482 -6.9596 90)
		(property "Reference" "C34"
			(at 0 0 90)
			(layer "F.SilkS")
			(hide yes)
			(effects
				(font
					(size 1.27 1.27)
				)
			)
		)
		(property "Value" "SCD1U16V2KX-3GP"
			(at 1.1811 -2.7051 90)
			(unlocked yes)
			(layer "F.Fab")
			(hide yes)
			(effects
				(font
					(size 1.016 1.016)
					(thickness 0.1524)
				)
			)
		)
		(property "Device Type" "C402H22"
			(at 1.1811 -4.2291 90)
			(unlocked yes)
			(layer "F.Fab")
			(hide yes)
			(effects
				(font
					(size 1.016 1.016)
					(thickness 0.1524)
				)
			)
		)
		(duplicate_pad_numbers_are_jumpers no)
		(fp_rect
			(start -0.4318 0.9525)
			(end 0.4318 -0.9525)
			(stroke
				(width 0)
				(type default)
			)
			(fill no)
			(layer "F.CrtYd")
		)
		(fp_rect
			(start -0.4318 0.9525)
			(end 0.4318 -0.9525)
			(stroke
				(width 0)
				(type default)
			)
			(fill no)
			(layer "F.Fab")
		)
		(pad "1" smd custom
			(at 0 -0.4445 90)
			(size 0.1524 0.1524)
			(layers "F.Cu" "F.Mask" "F.Paste")
			(net "D_FLIP_CLR_B#")
			(options
				(clearance outline)
				(anchor circle)
			)
			(primitives
				(gr_poly
					(pts
						(arc
							(start 0.3048 -0.2032)
							(mid 0.275042 -0.275042)
							(end 0.2032 -0.3048)
						)
						(arc
							(start -0.2032 -0.3048)
							(mid -0.275042 -0.275042)
							(end -0.3048 -0.2032)
						)
						(arc
							(start -0.3048 0.2032)
							(mid -0.275042 0.275042)
							(end -0.2032 0.3048)
						)
						(arc
							(start 0.2032 0.3048)
							(mid 0.275042 0.275042)
							(end 0.3048 0.2032)
						)
					)
					(width 0)
					(fill yes)
				)
			)
		)
		(pad "2" smd custom
			(at 0 0.4445 90)
			(size 0.1524 0.1524)
			(layers "F.Cu" "F.Mask" "F.Paste")
			(net "GND")
			(options
				(clearance outline)
				(anchor circle)
			)
			(primitives
				(gr_poly
					(pts
						(arc
							(start 0.3048 -0.2032)
							(mid 0.275042 -0.275042)
							(end 0.2032 -0.3048)
						)
						(arc
							(start -0.2032 -0.3048)
							(mid -0.275042 -0.275042)
							(end -0.3048 -0.2032)
						)
						(arc
							(start -0.3048 0.2032)
							(mid -0.275042 0.275042)
							(end -0.2032 0.3048)
						)
						(arc
							(start 0.2032 0.3048)
							(mid 0.275042 0.275042)
							(end 0.3048 0.2032)
						)
					)
					(width 0)
					(fill yes)
				)
			)
		)
	)
	(footprint ""
		(layer "F.Cu")
		(at 56.436006 -79.560674 180)
		(property "Reference" "D8"
			(at 0 0 180)
			(layer "F.SilkS")
			(hide yes)
			(effects
				(font
					(size 1.27 1.27)
				)
			)
		)
		(property "Value" "PESD5V0X1UAB-GP"
			(at 0 -4.690618 180)
			(unlocked yes)
			(layer "F.Fab")
			(hide yes)
			(effects
				(font
					(size 1.016 1.016)
					(thickness 0.1524)
				)
			)
		)
		(property "Device Type" "SOD523AKH26"
			(at 0 -6.214618 180)
			(unlocked yes)
			(layer "F.Fab")
			(hide yes)
			(effects
				(font
					(size 1.016 1.016)
					(thickness 0.1524)
				)
			)
		)
		(duplicate_pad_numbers_are_jumpers no)
		(fp_line
			(start 0.5334 1.524)
			(end -0.5334 1.524)
			(stroke
				(width 0.1524)
				(type default)
			)
			(layer "F.SilkS")
		)
		(fp_line
			(start 0.5334 -1.4478)
			(end 0.5334 1.524)
			(stroke
				(width 0.1524)
				(type default)
			)
			(layer "F.SilkS")
		)
		(fp_line
			(start 0.4064 1.651)
			(end -0.4064 1.651)
			(stroke
				(width 0.4064)
				(type default)
			)
			(layer "F.SilkS")
		)
		(fp_line
			(start -0.5334 1.524)
			(end -0.5334 -1.4478)
			(stroke
				(width 0.1524)
				(type default)
			)
			(layer "F.SilkS")
		)
		(fp_line
			(start -0.5334 -1.4478)
			(end 0.5334 -1.4478)
			(stroke
				(width 0.1524)
				(type default)
			)
			(layer "F.SilkS")
		)
		(fp_rect
			(start -0.6096 1.8542)
			(end 0.6096 -1.524)
			(stroke
				(width 0)
				(type default)
			)
			(fill no)
			(layer "F.CrtYd")
		)
		(fp_poly
			(pts
				(xy -0.6096 -1.524) (xy 0.6096 -1.524) (xy 0.6096 1.8542) (xy -0.6096 1.8542)
			)
			(stroke
				(width 0)
				(type default)
			)
			(fill no)
			(layer "F.Fab")
		)
		(pad "A" smd rect
			(at 0 -0.762 180)
			(size 0.5588 1.016)
			(layers "F.Cu" "F.Mask" "F.Paste")
			(net "GND")
		)
		(pad "K" smd rect
			(at 0 0.762 180)
			(size 0.5588 1.016)
			(layers "F.Cu" "F.Mask" "F.Paste")
			(net "PWR_BTN_B")
		)
	)
	(footprint ""
		(layer "F.Cu")
		(at 48.90008 -79.499968)
		(property "Reference" "SW2"
			(at 0 0 0)
			(layer "F.SilkS")
			(hide yes)
			(effects
				(font
					(size 1.27 1.27)
				)
			)
		)
		(property "Value" "SW-TACT-6P-100-GP"
			(at 6.9088 -7.239 0)
			(unlocked yes)
			(layer "F.Fab")
			(hide yes)
			(effects
				(font
					(size 2.54 2.54)
					(thickness 0.381)
				)
			)
		)
		(property "Device Type" "PS004-L22NPR1KKK3UBXX"
			(at 6.9088 -8.763 0)
			(unlocked yes)
			(layer "F.Fab")
			(hide yes)
			(effects
				(font
					(size 2.54 2.54)
					(thickness 0.381)
				)
			)
		)
		(duplicate_pad_numbers_are_jumpers no)
		(fp_line
			(start -5.7912 -0.7874)
			(end -5.198618 -0.7874)
			(stroke
				(width 0.1524)
				(type default)
			)
			(layer "F.SilkS")
		)
		(fp_line
			(start -5.7912 0.7874)
			(end -5.7912 -0.7874)
			(stroke
				(width 0.1524)
				(type default)
			)
			(layer "F.SilkS")
		)
		(fp_line
			(start -5.198618 0.7874)
			(end -5.7912 0.7874)
			(stroke
				(width 0.1524)
				(type default)
			)
			(layer "F.SilkS")
		)
		(fp_line
			(start -4.7498 -4.7498)
			(end -2.254758 -4.7498)
			(stroke
				(width 0.1524)
				(type default)
			)
			(layer "F.SilkS")
		)
		(fp_line
			(start -4.7498 -2.254758)
			(end -4.7498 -4.7498)
			(stroke
				(width 0.1524)
				(type default)
			)
			(layer "F.SilkS")
		)
		(fp_line
			(start -4.7498 4.7498)
			(end -4.7498 2.254758)
			(stroke
				(width 0.1524)
				(type default)
			)
			(layer "F.SilkS")
		)
		(fp_line
			(start -2.254758 4.7498)
			(end -4.7498 4.7498)
			(stroke
				(width 0.1524)
				(type default)
			)
			(layer "F.SilkS")
		)
		(fp_line
			(start 0 -1.0922)
			(end 0 -0.4572)
			(stroke
				(width 0.1524)
				(type default)
			)
			(layer "F.SilkS")
		)
		(fp_line
			(start 2.254758 -4.7498)
			(end 4.7498 -4.7498)
			(stroke
				(width 0.1524)
				(type default)
			)
			(layer "F.SilkS")
		)
		(fp_line
			(start 4.1402 -4.8387)
			(end 4.8387 -4.8387)
			(stroke
				(width 0.3302)
				(type default)
			)
			(layer "F.SilkS")
		)
		(fp_line
			(start 4.7498 -4.7498)
			(end 4.7498 -2.254758)
			(stroke
				(width 0.1524)
				(type default)
			)
			(layer "F.SilkS")
		)
		(fp_line
			(start 4.7498 2.254758)
			(end 4.7498 4.7498)
			(stroke
				(width 0.1524)
				(type default)
			)
			(layer "F.SilkS")
		)
		(fp_line
			(start 4.7498 4.7498)
			(end 2.254758 4.7498)
			(stroke
				(width 0.1524)
				(type default)
			)
			(layer "F.SilkS")
		)
		(fp_line
			(start 4.8387 -4.8387)
			(end 4.8387 -4.1656)
			(stroke
				(width 0.3302)
				(type default)
			)
			(layer "F.SilkS")
		)
		(fp_line
			(start 5.198618 -0.7874)
			(end 5.7912 -0.7874)
			(stroke
				(width 0.1524)
				(type default)
			)
			(layer "F.SilkS")
		)
		(fp_line
			(start 5.7912 -0.7874)
			(end 5.7912 0.7874)
			(stroke
				(width 0.1524)
				(type default)
			)
			(layer "F.SilkS")
		)
		(fp_line
			(start 5.7912 0.7874)
			(end 5.198618 0.7874)
			(stroke
				(width 0.1524)
				(type default)
			)
			(layer "F.SilkS")
		)
		(fp_arc
			(start -5.198618 -0.7874)
			(mid -5.028041 -1.537546)
			(end -4.7498 -2.254758)
			(stroke
				(width 0.1524)
				(type default)
			)
			(layer "F.SilkS")
		)
		(fp_arc
			(start -4.7498 2.254758)
			(mid -5.02801 1.537536)
			(end -5.198618 0.7874)
			(stroke
				(width 0.1524)
				(type default)
			)
			(layer "F.SilkS")
		)
		(fp_arc
			(start -2.254758 -4.7498)
			(mid 0 -5.257807)
			(end 2.254758 -4.7498)
			(stroke
				(width 0.1524)
				(type default)
			)
			(layer "F.SilkS")
		)
		(fp_arc
			(start 0 1.016)
			(mid -0.938662 0.388806)
			(end -0.718312 -0.718312)
			(stroke
				(width 0.1524)
				(type default)
			)
			(layer "F.SilkS")
		)
		(fp_arc
			(start 0.718312 -0.718312)
			(mid 0.93852 0.388748)
			(end 0 1.016)
			(stroke
				(width 0.1524)
				(type default)
			)
			(layer "F.SilkS")
		)
		(fp_arc
			(start 2.254758 4.7498)
			(mid 0 5.257807)
			(end -2.254758 4.7498)
			(stroke
				(width 0.1524)
				(type default)
			)
			(layer "F.SilkS")
		)
		(fp_arc
			(start 4.7498 -2.254758)
			(mid 5.02801 -1.537536)
			(end 5.198618 -0.7874)
			(stroke
				(width 0.1524)
				(type default)
			)
			(layer "F.SilkS")
		)
		(fp_arc
			(start 5.198618 0.7874)
			(mid 5.028041 1.537546)
			(end 4.7498 2.254758)
			(stroke
				(width 0.1524)
				(type default)
			)
			(layer "F.SilkS")
		)
		(fp_circle
			(center -4.99999 0)
			(end -4.11099 0)
			(stroke
				(width 0.3048)
				(type default)
			)
			(fill no)
			(layer "F.SilkS")
		)
		(fp_circle
			(center -2.500122 -2.500122)
			(end -1.484122 -2.500122)
			(stroke
				(width 0.3048)
				(type default)
			)
			(fill no)
			(layer "F.SilkS")
		)
		(fp_circle
			(center -2.500122 2.500122)
			(end -1.484122 2.500122)
			(stroke
				(width 0.3048)
				(type default)
			)
			(fill no)
			(layer "F.SilkS")
		)
		(fp_circle
			(center 0 -2.500122)
			(end 1.016 -2.500122)
			(stroke
				(width 0.3048)
				(type default)
			)
			(fill no)
			(layer "F.SilkS")
		)
		(fp_circle
			(center 0 2.500122)
			(end 1.016 2.500122)
			(stroke
				(width 0.3048)
				(type default)
			)
			(fill no)
			(layer "F.SilkS")
		)
		(fp_circle
			(center 2.500122 -2.500122)
			(end 3.516122 -2.500122)
			(stroke
				(width 0.3048)
				(type default)
			)
			(fill no)
			(layer "F.SilkS")
		)
		(fp_circle
			(center 2.500122 2.500122)
			(end 3.516122 2.500122)
			(stroke
				(width 0.3048)
				(type default)
			)
			(fill no)
			(layer "F.SilkS")
		)
		(fp_circle
			(center 4.99999 0)
			(end 5.88899 0)
			(stroke
				(width 0.3048)
				(type default)
			)
			(fill no)
			(layer "F.SilkS")
		)
		(fp_poly
			(pts
				(arc
					(start 2.196846 4.4958)
					(mid 0 5.003834)
					(end -2.196846 4.4958)
				)
				(xy -4.4958 4.4958)
				(arc
					(start -4.4958 2.196846)
					(mid -4.845024 1.250828)
					(end -4.99745 0.254)
				)
				(xy -5.1308 0.254) (xy -5.1308 -0.254)
				(arc
					(start -4.99745 -0.254)
					(mid -4.844994 -1.250821)
					(end -4.4958 -2.196846)
				)
				(xy -4.4958 -4.4958)
				(arc
					(start -2.196846 -4.4958)
					(mid 0 -5.003834)
					(end 2.196846 -4.4958)
				)
				(xy 4.4958 -4.4958)
				(arc
					(start 4.4958 -2.196846)
					(mid 4.845024 -1.250828)
					(end 4.99745 -0.254)
				)
				(xy 5.1308 -0.254) (xy 5.1308 0.254)
				(arc
					(start 4.99745 0.254)
					(mid 4.844994 1.250821)
					(end 4.4958 2.196846)
				)
				(xy 4.4958 4.4958)
			)
			(stroke
				(width 0)
				(type default)
			)
			(fill no)
			(layer "F.CrtYd")
		)
		(fp_poly
			(pts
				(arc
					(start 2.3114 5.0038)
					(mid 0 5.511859)
					(end -2.3114 5.0038)
				)
				(xy -5.0038 5.0038)
				(arc
					(start -5.0038 2.3114)
					(mid -5.246729 1.688816)
					(end -5.412486 1.0414)
				)
				(xy -6.0452 1.0414) (xy -6.0452 -1.0414)
				(arc
					(start -5.412486 -1.0414)
					(mid -5.246693 -1.688804)
					(end -5.0038 -2.3114)
				)
				(xy -5.0038 -5.0038)
				(arc
					(start -2.3114 -5.0038)
					(mid 0 -5.511859)
					(end 2.3114 -5.0038)
				)
				(xy 5.0038 -5.0038)
				(arc
					(start 5.0038 -2.3114)
					(mid 5.246729 -1.688816)
					(end 5.412486 -1.0414)
				)
				(xy 6.0452 -1.0414) (xy 6.0452 -0.00635) (xy 5.1308 -0.00635) (xy 5.1308 -0.254)
				(arc
					(start 4.997704 -0.254)
					(mid 4.845133 -1.250792)
					(end 4.496054 -2.196846)
				)
				(xy 4.4958 -4.4958)
				(arc
					(start 2.196846 -4.4958)
					(mid 0 -5.003834)
					(end -2.196846 -4.4958)
				)
				(xy -4.4958 -4.4958)
				(arc
					(start -4.4958 -2.196846)
					(mid -4.84509 -1.250826)
					(end -4.997704 -0.254)
				)
				(xy -5.1308 -0.254) (xy -5.1308 0.254)
				(arc
					(start -4.997704 0.254)
					(mid -4.845193 1.250762)
					(end -4.496308 2.196846)
				)
				(xy -4.4958 4.4958)
				(arc
					(start -2.196846 4.4958)
					(mid 0 5.003834)
					(end 2.196846 4.4958)
				)
				(xy 4.4958 4.4958)
				(arc
					(start 4.4958 2.196846)
					(mid 4.84509 1.250826)
					(end 4.997704 0.254)
				)
				(xy 5.1308 0.254) (xy 5.1308 0.00635) (xy 6.0452 0.00635) (xy 6.0452 1.0414)
				(arc
					(start 5.412486 1.0414)
					(mid 5.246693 1.688804)
					(end 5.0038 2.3114)
				)
				(xy 5.0038 5.0038)
			)
			(stroke
				(width 0)
				(type default)
			)
			(fill no)
			(layer "F.CrtYd")
		)
		(fp_poly
			(pts
				(arc
					(start 2.3114 5.0038)
					(mid 0 5.511859)
					(end -2.3114 5.0038)
				)
				(xy -5.0038 5.0038)
				(arc
					(start -5.0038 2.3114)
					(mid -5.246729 1.688816)
					(end -5.412486 1.0414)
				)
				(xy -6.0452 1.0414) (xy -6.0452 -1.0414)
				(arc
					(start -5.412486 -1.0414)
					(mid -5.246693 -1.688804)
					(end -5.0038 -2.3114)
				)
				(xy -5.0038 -5.0038)
				(arc
					(start -2.3114 -5.0038)
					(mid 0 -5.511859)
					(end 2.3114 -5.0038)
				)
				(xy 5.0038 -5.0038)
				(arc
					(start 5.0038 -2.3114)
					(mid 5.246729 -1.688816)
					(end 5.412486 -1.0414)
				)
				(xy 6.0452 -1.0414) (xy 6.0452 1.0414)
				(arc
					(start 5.412486 1.0414)
					(mid 5.246693 1.688804)
					(end 5.0038 2.3114)
				)
				(xy 5.0038 5.0038)
			)
			(stroke
				(width 0)
				(type default)
			)
			(fill no)
			(layer "F.Fab")
		)
		(pad "1" thru_hole circle
			(at 2.500122 -2.500122)
			(size 1.3208 1.3208)
			(drill 0.9144)
			(layers "*.Cu" "*.Mask")
			(remove_unused_layers no)
			(net "PWR_BTN_B")
			(clearance 0.1524)
			(thermal_gap 0.1524)
		)
		(pad "2" thru_hole circle
			(at 0 -2.500122)
			(size 1.3208 1.3208)
			(drill 0.9144)
			(layers "*.Cu" "*.Mask")
			(remove_unused_layers no)
			(net "PWR_BTN_B_CONN")
			(clearance 0.1524)
			(thermal_gap 0.1524)
		)
		(pad "3" thru_hole circle
			(at -2.500122 -2.500122)
			(size 1.3208 1.3208)
			(drill 0.9144)
			(layers "*.Cu" "*.Mask")
			(remove_unused_layers no)
			(net "Net_81")
			(clearance 0.1524)
			(thermal_gap 0.1524)
		)
		(pad "4" thru_hole circle
			(at 2.500122 2.500122)
			(size 1.3208 1.3208)
			(drill 0.9144)
			(layers "*.Cu" "*.Mask")
			(remove_unused_layers no)
			(net "GND")
			(clearance 0.1524)
			(thermal_gap 0.1524)
		)
		(pad "5" thru_hole circle
			(at 0 2.500122)
			(size 1.3208 1.3208)
			(drill 0.9144)
			(layers "*.Cu" "*.Mask")
			(remove_unused_layers no)
			(net "PWR_BTN_B_CONN")
			(clearance 0.1524)
			(thermal_gap 0.1524)
		)
		(pad "6" thru_hole circle
			(at -2.500122 2.500122)
			(size 1.3208 1.3208)
			(drill 0.9144)
			(layers "*.Cu" "*.Mask")
			(remove_unused_layers no)
			(net "Net_82")
			(clearance 0.1524)
			(thermal_gap 0.1524)
		)
		(pad "L1" thru_hole circle
			(at 4.99999 0)
			(size 1.0668 1.0668)
			(drill 0.7112)
			(layers "*.Cu" "*.Mask")
			(remove_unused_layers no)
			(net "PWR_BTN_LED_B_R")
			(clearance 0.1778)
			(thermal_gap 0.1778)
		)
		(pad "L2" thru_hole circle
			(at -4.99999 0)
			(size 1.0668 1.0668)
			(drill 0.7112)
			(layers "*.Cu" "*.Mask")
			(remove_unused_layers no)
			(net "PWR_LED_B_N")
			(clearance 0.1778)
			(thermal_gap 0.1778)
		)
	)
	(footprint ""
		(layer "F.Cu")
		(at 9.9568 -12.3444 -90)
		(property "Reference" "C1"
			(at 0 0 270)
			(layer "F.SilkS")
			(hide yes)
			(effects
				(font
					(size 1.27 1.27)
				)
			)
		)
		(property "Value" "SCD1U16V2KX-3GP"
			(at 1.1811 -3.3909 270)
			(unlocked yes)
			(layer "F.Fab")
			(hide yes)
			(effects
				(font
					(size 2.54 2.54)
					(thickness 0.381)
				)
			)
		)
		(property "Device Type" "C402H22"
			(at 1.1811 -4.9149 270)
			(unlocked yes)
			(layer "F.Fab")
			(hide yes)
			(effects
				(font
					(size 2.54 2.54)
					(thickness 0.381)
				)
			)
		)
		(duplicate_pad_numbers_are_jumpers no)
		(fp_rect
			(start -0.4318 0.9525)
			(end 0.4318 -0.9525)
			(stroke
				(width 0)
				(type default)
			)
			(fill no)
			(layer "F.CrtYd")
		)
		(fp_rect
			(start -0.4318 0.9525)
			(end 0.4318 -0.9525)
			(stroke
				(width 0)
				(type default)
			)
			(fill no)
			(layer "F.Fab")
		)
		(pad "1" smd custom
			(at 0 -0.4445 270)
			(size 0.1524 0.1524)
			(layers "F.Cu" "F.Mask" "F.Paste")
			(net "P3V3_STBY_A")
			(options
				(clearance outline)
				(anchor circle)
			)
			(primitives
				(gr_poly
					(pts
						(arc
							(start 0.3048 -0.2032)
							(mid 0.275042 -0.275042)
							(end 0.2032 -0.3048)
						)
						(arc
							(start -0.2032 -0.3048)
							(mid -0.275042 -0.275042)
							(end -0.3048 -0.2032)
						)
						(arc
							(start -0.3048 0.2032)
							(mid -0.275042 0.275042)
							(end -0.2032 0.3048)
						)
						(arc
							(start 0.2032 0.3048)
							(mid 0.275042 0.275042)
							(end 0.3048 0.2032)
						)
					)
					(width 0)
					(fill yes)
				)
			)
		)
		(pad "2" smd custom
			(at 0 0.4445 270)
			(size 0.1524 0.1524)
			(layers "F.Cu" "F.Mask" "F.Paste")
			(net "GND")
			(options
				(clearance outline)
				(anchor circle)
			)
			(primitives
				(gr_poly
					(pts
						(arc
							(start 0.3048 -0.2032)
							(mid 0.275042 -0.275042)
							(end 0.2032 -0.3048)
						)
						(arc
							(start -0.2032 -0.3048)
							(mid -0.275042 -0.275042)
							(end -0.3048 -0.2032)
						)
						(arc
							(start -0.3048 0.2032)
							(mid -0.275042 0.275042)
							(end -0.2032 0.3048)
						)
						(arc
							(start 0.2032 0.3048)
							(mid 0.275042 0.275042)
							(end 0.3048 0.2032)
						)
					)
					(width 0)
					(fill yes)
				)
			)
		)
	)
	(footprint ""
		(layer "F.Cu")
		(at 45.400214 -72.186546 180)
		(property "Reference" "D4"
			(at 0 0 180)
			(layer "F.SilkS")
			(hide yes)
			(effects
				(font
					(size 1.27 1.27)
				)
			)
		)
		(property "Value" "PESD5V0S1BL-1-GP"
			(at 1.8923 -1.5621 180)
			(unlocked yes)
			(layer "F.Fab")
			(hide yes)
			(effects
				(font
					(size 1.016 1.016)
					(thickness 0.1524)
				)
			)
		)
		(property "Device Type" "SOD882-10D6-1H20"
			(at 1.8923 -3.0861 180)
			(unlocked yes)
			(layer "F.Fab")
			(hide yes)
			(effects
				(font
					(size 1.016 1.016)
					(thickness 0.1524)
				)
			)
		)
		(duplicate_pad_numbers_are_jumpers no)
		(fp_line
			(start -0.3048 -0.9271)
			(end 0.3048 -0.9271)
			(stroke
				(width 0.254)
				(type default)
			)
			(layer "F.SilkS")
		)
		(fp_rect
			(start -0.2921 0.4953)
			(end 0.2921 -0.4953)
			(stroke
				(width 0)
				(type default)
			)
			(fill no)
			(layer "F.CrtYd")
		)
		(fp_poly
			(pts
				(xy -0.4318 0.8001) (xy -0.4318 -0.266192) (xy -0.2921 -0.266192) (xy -0.2921 0.4953) (xy 0.2921 0.4953)
				(xy 0.2921 -0.4953) (xy -0.2921 -0.4953) (xy -0.2921 -0.2667) (xy -0.4318 -0.2667) (xy -0.4318 -0.8001)
				(xy 0.4318 -0.8001) (xy 0.4318 0.8001)
			)
			(stroke
				(width 0)
				(type default)
			)
			(fill no)
			(layer "F.CrtYd")
		)
		(fp_rect
			(start -0.4318 0.8001)
			(end 0.4318 -0.8001)
			(stroke
				(width 0)
				(type default)
			)
			(fill no)
			(layer "F.Fab")
		)
		(pad "1" smd custom
			(at 0 -0.4445 180)
			(size 0.1143 0.1143)
			(layers "F.Cu" "F.Mask" "F.Paste")
			(net "P5V_VBUS_B")
			(options
				(clearance outline)
				(anchor circle)
			)
			(primitives
				(gr_poly
					(pts
						(arc
							(start -0.2032 0.2286)
							(mid -0.275042 0.198842)
							(end -0.3048 0.127)
						)
						(arc
							(start -0.3048 -0.127)
							(mid -0.275042 -0.198842)
							(end -0.2032 -0.2286)
						)
						(arc
							(start 0.2032 -0.2286)
							(mid 0.275042 -0.198842)
							(end 0.3048 -0.127)
						)
						(arc
							(start 0.3048 0.127)
							(mid 0.275042 0.198842)
							(end 0.2032 0.2286)
						)
					)
					(width 0)
					(fill yes)
				)
			)
		)
		(pad "2" smd custom
			(at 0 0.4445 180)
			(size 0.1143 0.1143)
			(layers "F.Cu" "F.Mask" "F.Paste")
			(net "GND")
			(options
				(clearance outline)
				(anchor circle)
			)
			(primitives
				(gr_poly
					(pts
						(arc
							(start 0.2032 -0.2286)
							(mid 0.275042 -0.198842)
							(end 0.3048 -0.127)
						)
						(arc
							(start 0.3048 0.127)
							(mid 0.275042 0.198842)
							(end 0.2032 0.2286)
						)
						(arc
							(start -0.2032 0.2286)
							(mid -0.275042 0.198842)
							(end -0.3048 0.127)
						)
						(arc
							(start -0.3048 -0.127)
							(mid -0.275042 -0.198842)
							(end -0.2032 -0.2286)
						)
					)
					(width 0)
					(fill yes)
				)
			)
		)
	)
	(footprint ""
		(layer "F.Cu")
		(at 8.128 -72.136 -90)
		(property "Reference" "R45"
			(at 0 0 270)
			(layer "F.SilkS")
			(hide yes)
			(effects
				(font
					(size 1.27 1.27)
				)
			)
		)
		(property "Value" "1MR2F-GP"
			(at 0.064008 -4.679696 270)
			(unlocked yes)
			(layer "F.Fab")
			(hide yes)
			(effects
				(font
					(size 2.54 2.54)
					(thickness 0.381)
				)
			)
		)
		(property "Device Type" "R402H16"
			(at 0.064008 -6.203696 270)
			(unlocked yes)
			(layer "F.Fab")
			(hide yes)
			(effects
				(font
					(size 2.54 2.54)
					(thickness 0.381)
				)
			)
		)
		(duplicate_pad_numbers_are_jumpers no)
		(fp_line
			(start -0.508 -0.9398)
			(end -0.508 0.9398)
			(stroke
				(width 0.1524)
				(type default)
			)
			(layer "F.SilkS")
		)
		(fp_line
			(start 0.508 -0.9398)
			(end -0.508 -0.9398)
			(stroke
				(width 0.1524)
				(type default)
			)
			(layer "F.SilkS")
		)
		(fp_rect
			(start -0.508 0.9398)
			(end 0.508 -0.9398)
			(stroke
				(width 0)
				(type default)
			)
			(fill no)
			(layer "F.CrtYd")
		)
		(fp_rect
			(start -0.508 0.9398)
			(end 0.508 -0.9398)
			(stroke
				(width 0)
				(type default)
			)
			(fill no)
			(layer "F.Fab")
		)
		(pad "1" smd custom
			(at 0 -0.4445 270)
			(size 0.1397 0.1397)
			(layers "F.Cu" "F.Mask" "F.Paste")
			(net "USB_CONN_A_GND")
			(options
				(clearance outline)
				(anchor circle)
			)
			(primitives
				(gr_poly
					(pts
						(arc
							(start -0.1778 -0.2794)
							(mid -0.249642 -0.249642)
							(end -0.2794 -0.1778)
						)
						(arc
							(start -0.2794 0.1778)
							(mid -0.249642 0.249642)
							(end -0.1778 0.2794)
						)
						(arc
							(start 0.1778 0.2794)
							(mid 0.249642 0.249642)
							(end 0.2794 0.1778)
						)
						(arc
							(start 0.2794 -0.1778)
							(mid 0.249642 -0.249642)
							(end 0.1778 -0.2794)
						)
					)
					(width 0)
					(fill yes)
				)
			)
		)
		(pad "2" smd custom
			(at 0 0.4445 270)
			(size 0.1397 0.1397)
			(layers "F.Cu" "F.Mask" "F.Paste")
			(net "GND")
			(options
				(clearance outline)
				(anchor circle)
			)
			(primitives
				(gr_poly
					(pts
						(arc
							(start -0.1778 -0.2794)
							(mid -0.249642 -0.249642)
							(end -0.2794 -0.1778)
						)
						(arc
							(start -0.2794 0.1778)
							(mid -0.249642 0.249642)
							(end -0.1778 0.2794)
						)
						(arc
							(start 0.1778 0.2794)
							(mid 0.249642 0.249642)
							(end 0.2794 0.1778)
						)
						(arc
							(start 0.2794 -0.1778)
							(mid 0.249642 -0.249642)
							(end 0.1778 -0.2794)
						)
					)
					(width 0)
					(fill yes)
				)
			)
		)
	)
	(footprint ""
		(layer "F.Cu")
		(at 13.840968 -46.640496)
		(property "Reference" "R33"
			(at 0 0 0)
			(layer "F.SilkS")
			(hide yes)
			(effects
				(font
					(size 1.27 1.27)
				)
			)
		)
		(property "Value" "4K7R2F-GP"
			(at 0.064008 -4.679696 0)
			(unlocked yes)
			(layer "F.Fab")
			(hide yes)
			(effects
				(font
					(size 2.54 2.54)
					(thickness 0.381)
				)
			)
		)
		(property "Device Type" "R402H16"
			(at 0.064008 -6.203696 0)
			(unlocked yes)
			(layer "F.Fab")
			(hide yes)
			(effects
				(font
					(size 2.54 2.54)
					(thickness 0.381)
				)
			)
		)
		(duplicate_pad_numbers_are_jumpers no)
		(fp_line
			(start -0.508 -0.9398)
			(end -0.508 0.9398)
			(stroke
				(width 0.1524)
				(type default)
			)
			(layer "F.SilkS")
		)
		(fp_line
			(start 0.508 -0.9398)
			(end -0.508 -0.9398)
			(stroke
				(width 0.1524)
				(type default)
			)
			(layer "F.SilkS")
		)
		(fp_rect
			(start -0.508 0.9398)
			(end 0.508 -0.9398)
			(stroke
				(width 0)
				(type default)
			)
			(fill no)
			(layer "F.CrtYd")
		)
		(fp_rect
			(start -0.508 0.9398)
			(end 0.508 -0.9398)
			(stroke
				(width 0)
				(type default)
			)
			(fill no)
			(layer "F.Fab")
		)
		(pad "1" smd custom
			(at 0 -0.4445)
			(size 0.1397 0.1397)
			(layers "F.Cu" "F.Mask" "F.Paste")
			(net "P3V3_STBY_A")
			(options
				(clearance outline)
				(anchor circle)
			)
			(primitives
				(gr_poly
					(pts
						(arc
							(start -0.1778 -0.2794)
							(mid -0.249642 -0.249642)
							(end -0.2794 -0.1778)
						)
						(arc
							(start -0.2794 0.1778)
							(mid -0.249642 0.249642)
							(end -0.1778 0.2794)
						)
						(arc
							(start 0.1778 0.2794)
							(mid 0.249642 0.249642)
							(end 0.2794 0.1778)
						)
						(arc
							(start 0.2794 -0.1778)
							(mid 0.249642 -0.249642)
							(end 0.1778 -0.2794)
						)
					)
					(width 0)
					(fill yes)
				)
			)
		)
		(pad "2" smd custom
			(at 0 0.4445)
			(size 0.1397 0.1397)
			(layers "F.Cu" "F.Mask" "F.Paste")
			(net "TEMP_1_A1")
			(options
				(clearance outline)
				(anchor circle)
			)
			(primitives
				(gr_poly
					(pts
						(arc
							(start -0.1778 -0.2794)
							(mid -0.249642 -0.249642)
							(end -0.2794 -0.1778)
						)
						(arc
							(start -0.2794 0.1778)
							(mid -0.249642 0.249642)
							(end -0.1778 0.2794)
						)
						(arc
							(start 0.1778 0.2794)
							(mid 0.249642 0.249642)
							(end 0.2794 0.1778)
						)
						(arc
							(start 0.2794 -0.1778)
							(mid 0.249642 -0.249642)
							(end 0.1778 -0.2794)
						)
					)
					(width 0)
					(fill yes)
				)
			)
		)
	)
	(footprint ""
		(layer "F.Cu")
		(at 53.218588 -12.830048 180)
		(property "Reference" "R8"
			(at 0 0 180)
			(layer "F.SilkS")
			(hide yes)
			(effects
				(font
					(size 1.27 1.27)
				)
			)
		)
		(property "Value" "10KR2F-2-GP"
			(at 0.064008 -4.679696 180)
			(unlocked yes)
			(layer "F.Fab")
			(hide yes)
			(effects
				(font
					(size 2.54 2.54)
					(thickness 0.381)
				)
			)
		)
		(property "Device Type" "R402H16"
			(at 0.064008 -6.203696 180)
			(unlocked yes)
			(layer "F.Fab")
			(hide yes)
			(effects
				(font
					(size 2.54 2.54)
					(thickness 0.381)
				)
			)
		)
		(duplicate_pad_numbers_are_jumpers no)
		(fp_line
			(start 0.508 -0.9398)
			(end -0.508 -0.9398)
			(stroke
				(width 0.1524)
				(type default)
			)
			(layer "F.SilkS")
		)
		(fp_line
			(start -0.508 -0.9398)
			(end -0.508 0.9398)
			(stroke
				(width 0.1524)
				(type default)
			)
			(layer "F.SilkS")
		)
		(fp_rect
			(start -0.508 0.9398)
			(end 0.508 -0.9398)
			(stroke
				(width 0)
				(type default)
			)
			(fill no)
			(layer "F.CrtYd")
		)
		(fp_rect
			(start -0.508 0.9398)
			(end 0.508 -0.9398)
			(stroke
				(width 0)
				(type default)
			)
			(fill no)
			(layer "F.Fab")
		)
		(pad "1" smd custom
			(at 0 -0.4445 180)
			(size 0.1397 0.1397)
			(layers "F.Cu" "F.Mask" "F.Paste")
			(net "P3V3_STBY_B")
			(options
				(clearance outline)
				(anchor circle)
			)
			(primitives
				(gr_poly
					(pts
						(arc
							(start -0.1778 -0.2794)
							(mid -0.249642 -0.249642)
							(end -0.2794 -0.1778)
						)
						(arc
							(start -0.2794 0.1778)
							(mid -0.249642 0.249642)
							(end -0.1778 0.2794)
						)
						(arc
							(start 0.1778 0.2794)
							(mid 0.249642 0.249642)
							(end 0.2794 0.1778)
						)
						(arc
							(start 0.2794 -0.1778)
							(mid 0.249642 -0.249642)
							(end 0.1778 -0.2794)
						)
					)
					(width 0)
					(fill yes)
				)
			)
		)
		(pad "2" smd custom
			(at 0 0.4445 180)
			(size 0.1397 0.1397)
			(layers "F.Cu" "F.Mask" "F.Paste")
			(net "UART_SEL_B_MUX_R")
			(options
				(clearance outline)
				(anchor circle)
			)
			(primitives
				(gr_poly
					(pts
						(arc
							(start -0.1778 -0.2794)
							(mid -0.249642 -0.249642)
							(end -0.2794 -0.1778)
						)
						(arc
							(start -0.2794 0.1778)
							(mid -0.249642 0.249642)
							(end -0.1778 0.2794)
						)
						(arc
							(start 0.1778 0.2794)
							(mid 0.249642 0.249642)
							(end 0.2794 0.1778)
						)
						(arc
							(start 0.2794 -0.1778)
							(mid 0.249642 -0.249642)
							(end 0.1778 -0.2794)
						)
					)
					(width 0)
					(fill yes)
				)
			)
		)
	)
	(footprint ""
		(layer "F.Cu")
		(at 53.213 -19.177 90)
		(property "Reference" "U4"
			(at 0 0 90)
			(layer "F.SilkS")
			(hide yes)
			(effects
				(font
					(size 1.27 1.27)
				)
			)
		)
		(property "Value" "TCA9555PWR-GP"
			(at 0 -6.9342 90)
			(unlocked yes)
			(layer "F.Fab")
			(hide yes)
			(effects
				(font
					(size 1.016 1.016)
					(thickness 0.1524)
				)
			)
		)
		(property "Device Type" "TSOIC24H48"
			(at 0 -8.5852 90)
			(unlocked yes)
			(layer "F.Fab")
			(hide yes)
			(effects
				(font
					(size 1.016 1.016)
					(thickness 0.1524)
				)
			)
		)
		(duplicate_pad_numbers_are_jumpers no)
		(fp_line
			(start 3.81 -1.397)
			(end 3.81 1.397)
			(stroke
				(width 0.1524)
				(type default)
			)
			(layer "F.SilkS")
		)
		(fp_line
			(start -4.2291 -1.397)
			(end 3.81 -1.397)
			(stroke
				(width 0.1524)
				(type default)
			)
			(layer "F.SilkS")
		)
		(fp_line
			(start -4.2291 -0.8001)
			(end -3.429 0)
			(stroke
				(width 0.1524)
				(type default)
			)
			(layer "F.SilkS")
		)
		(fp_line
			(start -3.429 0)
			(end -4.2291 0.8001)
			(stroke
				(width 0.1524)
				(type default)
			)
			(layer "F.SilkS")
		)
		(fp_line
			(start 3.81 1.397)
			(end -4.2291 1.397)
			(stroke
				(width 0.1524)
				(type default)
			)
			(layer "F.SilkS")
		)
		(fp_line
			(start -4.22656 3.81)
			(end -4.2291 1.397)
			(stroke
				(width 0.508)
				(type default)
			)
			(layer "F.SilkS")
		)
		(fp_line
			(start -4.2291 3.937)
			(end -4.2291 -1.397)
			(stroke
				(width 0.1524)
				(type default)
			)
			(layer "F.SilkS")
		)
		(fp_poly
			(pts
				(xy -3.90652 -1.8542) (xy 3.90652 -1.8542) (xy 3.90652 1.8542) (xy -3.90652 1.8542)
			)
			(stroke
				(width 0)
				(type default)
			)
			(fill yes)
			(layer "F.SilkS")
		)
		(fp_poly
			(pts
				(xy -4.2164 3.81) (xy 4.2164 3.81) (xy 4.22656 -3.81) (xy -4.2164 -3.81)
			)
			(stroke
				(width 0)
				(type default)
			)
			(fill no)
			(layer "F.CrtYd")
		)
		(fp_poly
			(pts
				(xy -4.22656 -3.81) (xy 4.22656 -3.81) (xy 4.22656 3.81) (xy -4.22656 3.81)
			)
			(stroke
				(width 0)
				(type default)
			)
			(fill no)
			(layer "F.Fab")
		)
		(pad "1" smd rect
			(at -3.57632 2.8194 90)
			(size 0.3556 1.524)
			(layers "F.Cu" "F.Mask" "F.Paste")
			(net "IO_EXP_B_RESET#_FLT")
		)
		(pad "2" smd rect
			(at -2.92608 2.8194 90)
			(size 0.3556 1.524)
			(layers "F.Cu" "F.Mask" "F.Paste")
			(net "TCA9555_B_A1")
		)
		(pad "3" smd rect
			(at -2.27584 2.8194 90)
			(size 0.3556 1.524)
			(layers "F.Cu" "F.Mask" "F.Paste")
			(net "TCA9555_B_A2")
		)
		(pad "4" smd rect
			(at -1.6256 2.8194 90)
			(size 0.3556 1.524)
			(layers "F.Cu" "F.Mask" "F.Paste")
			(net "Net_53")
		)
		(pad "5" smd rect
			(at -0.97536 2.8194 90)
			(size 0.3556 1.524)
			(layers "F.Cu" "F.Mask" "F.Paste")
			(net "Net_52")
		)
		(pad "6" smd rect
			(at -0.32512 2.8194 90)
			(size 0.3556 1.524)
			(layers "F.Cu" "F.Mask" "F.Paste")
			(net "Net_51")
		)
		(pad "7" smd rect
			(at 0.32512 2.8194 90)
			(size 0.3556 1.524)
			(layers "F.Cu" "F.Mask" "F.Paste")
			(net "Net_50")
		)
		(pad "8" smd rect
			(at 0.97536 2.8194 90)
			(size 0.3556 1.524)
			(layers "F.Cu" "F.Mask" "F.Paste")
			(net "Net_49")
		)
		(pad "9" smd rect
			(at 1.6256 2.8194 90)
			(size 0.3556 1.524)
			(layers "F.Cu" "F.Mask" "F.Paste")
			(net "Net_48")
		)
		(pad "10" smd rect
			(at 2.27584 2.8194 90)
			(size 0.3556 1.524)
			(layers "F.Cu" "F.Mask" "F.Paste")
			(net "Net_47")
		)
		(pad "11" smd rect
			(at 2.92608 2.8194 90)
			(size 0.3556 1.524)
			(layers "F.Cu" "F.Mask" "F.Paste")
			(net "Net_46")
		)
		(pad "12" smd rect
			(at 3.57632 2.8194 90)
			(size 0.3556 1.524)
			(layers "F.Cu" "F.Mask" "F.Paste")
			(net "GND")
		)
		(pad "13" smd rect
			(at 3.57632 -2.8194 90)
			(size 0.3556 1.524)
			(layers "F.Cu" "F.Mask" "F.Paste")
			(net "DEBUG_RST_B_BTN_N")
		)
		(pad "14" smd rect
			(at 2.92608 -2.8194 90)
			(size 0.3556 1.524)
			(layers "F.Cu" "F.Mask" "F.Paste")
			(net "Net_45")
		)
		(pad "15" smd rect
			(at 2.27584 -2.8194 90)
			(size 0.3556 1.524)
			(layers "F.Cu" "F.Mask" "F.Paste")
			(net "Net_44")
		)
		(pad "16" smd rect
			(at 1.6256 -2.8194 90)
			(size 0.3556 1.524)
			(layers "F.Cu" "F.Mask" "F.Paste")
			(net "Net_43")
		)
		(pad "17" smd rect
			(at 0.97536 -2.8194 90)
			(size 0.3556 1.524)
			(layers "F.Cu" "F.Mask" "F.Paste")
			(net "Net_42")
		)
		(pad "18" smd rect
			(at 0.32512 -2.8194 90)
			(size 0.3556 1.524)
			(layers "F.Cu" "F.Mask" "F.Paste")
			(net "Net_41")
		)
		(pad "19" smd rect
			(at -0.32512 -2.8194 90)
			(size 0.3556 1.524)
			(layers "F.Cu" "F.Mask" "F.Paste")
			(net "Net_40")
		)
		(pad "20" smd rect
			(at -0.97536 -2.8194 90)
			(size 0.3556 1.524)
			(layers "F.Cu" "F.Mask" "F.Paste")
			(net "DEBUG_HDR_B_UART_SEL")
		)
		(pad "21" smd rect
			(at -1.6256 -2.8194 90)
			(size 0.3556 1.524)
			(layers "F.Cu" "F.Mask" "F.Paste")
			(net "TCA9555_B_A0")
		)
		(pad "22" smd rect
			(at -2.27584 -2.8194 90)
			(size 0.3556 1.524)
			(layers "F.Cu" "F.Mask" "F.Paste")
			(net "I2C_DEBUG_B_SCL_R")
		)
		(pad "23" smd rect
			(at -2.92608 -2.8194 90)
			(size 0.3556 1.524)
			(layers "F.Cu" "F.Mask" "F.Paste")
			(net "I2C_DEBUG_B_SDA_R")
		)
		(pad "24" smd rect
			(at -3.57632 -2.8194 90)
			(size 0.3556 1.524)
			(layers "F.Cu" "F.Mask" "F.Paste")
			(net "P3V3_STBY_B")
		)
	)
	(footprint ""
		(layer "F.Cu")
		(at 52.90566 -70.136512 90)
		(property "Reference" "C17"
			(at 0 0 90)
			(layer "F.SilkS")
			(hide yes)
			(effects
				(font
					(size 1.27 1.27)
				)
			)
		)
		(property "Value" "SC1000P2KV6KX-GP-U"
			(at 0.0508 -3.5052 90)
			(unlocked yes)
			(layer "F.Fab")
			(hide yes)
			(effects
				(font
					(size 1.016 1.016)
					(thickness 0.1524)
				)
			)
		)
		(property "Device Type" "C1206H58"
			(at 0.0508 -5.0292 90)
			(unlocked yes)
			(layer "F.Fab")
			(hide yes)
			(effects
				(font
					(size 1.016 1.016)
					(thickness 0.1524)
				)
			)
		)
		(duplicate_pad_numbers_are_jumpers no)
		(fp_line
			(start 1.016 -2.2352)
			(end -1.016 -2.2352)
			(stroke
				(width 0.1524)
				(type default)
			)
			(layer "F.SilkS")
		)
		(fp_line
			(start 1.016 -2.2352)
			(end 1.016 -0.8382)
			(stroke
				(width 0.1524)
				(type default)
			)
			(layer "F.SilkS")
		)
		(fp_line
			(start -1.016 -2.2352)
			(end -1.016 -0.8382)
			(stroke
				(width 0.1524)
				(type default)
			)
			(layer "F.SilkS")
		)
		(fp_line
			(start 1.016 0.8382)
			(end 1.016 2.2352)
			(stroke
				(width 0.1524)
				(type default)
			)
			(layer "F.SilkS")
		)
		(fp_line
			(start 1.016 2.2352)
			(end -1.016 2.2352)
			(stroke
				(width 0.1524)
				(type default)
			)
			(layer "F.SilkS")
		)
		(fp_line
			(start -1.016 2.2352)
			(end -1.016 0.8128)
			(stroke
				(width 0.1524)
				(type default)
			)
			(layer "F.SilkS")
		)
		(fp_rect
			(start -1.0922 2.3114)
			(end 1.0922 -2.3114)
			(stroke
				(width 0)
				(type default)
			)
			(fill no)
			(layer "F.CrtYd")
		)
		(fp_poly
			(pts
				(xy -1.0922 -2.3114) (xy 1.0922 -2.3114) (xy 1.0922 2.3114) (xy -1.0922 2.3114)
			)
			(stroke
				(width 0)
				(type default)
			)
			(fill no)
			(layer "F.Fab")
		)
		(pad "1" smd rect
			(at 0 -1.397 90)
			(size 1.651 1.27)
			(layers "F.Cu" "F.Mask" "F.Paste")
			(net "USB_CONN_B_GND")
		)
		(pad "2" smd rect
			(at 0 1.397 90)
			(size 1.651 1.27)
			(layers "F.Cu" "F.Mask" "F.Paste")
			(net "GND")
		)
	)
	(footprint ""
		(layer "F.Cu")
		(at 31.496 -13.716 -90)
		(property "Reference" "R17"
			(at 0 0 270)
			(layer "F.SilkS")
			(hide yes)
			(effects
				(font
					(size 1.27 1.27)
				)
			)
		)
		(property "Value" "0R2J-2-GP"
			(at 0.064008 -3.993896 270)
			(unlocked yes)
			(layer "F.Fab")
			(hide yes)
			(effects
				(font
					(size 1.016 1.016)
					(thickness 0.1524)
				)
			)
		)
		(property "Device Type" "R402H16"
			(at 0.064008 -5.517896 270)
			(unlocked yes)
			(layer "F.Fab")
			(hide yes)
			(effects
				(font
					(size 1.016 1.016)
					(thickness 0.1524)
				)
			)
		)
		(duplicate_pad_numbers_are_jumpers no)
		(fp_line
			(start -0.508 -0.9398)
			(end -0.508 0.9398)
			(stroke
				(width 0.1524)
				(type default)
			)
			(layer "F.SilkS")
		)
		(fp_line
			(start 0.508 -0.9398)
			(end -0.508 -0.9398)
			(stroke
				(width 0.1524)
				(type default)
			)
			(layer "F.SilkS")
		)
		(fp_rect
			(start -0.508 0.9398)
			(end 0.508 -0.9398)
			(stroke
				(width 0)
				(type default)
			)
			(fill no)
			(layer "F.CrtYd")
		)
		(fp_rect
			(start -0.508 0.9398)
			(end 0.508 -0.9398)
			(stroke
				(width 0)
				(type default)
			)
			(fill no)
			(layer "F.Fab")
		)
		(pad "1" smd custom
			(at 0 -0.4445 270)
			(size 0.1397 0.1397)
			(layers "F.Cu" "F.Mask" "F.Paste")
			(net "D_FLIP_B_D")
			(options
				(clearance outline)
				(anchor circle)
			)
			(primitives
				(gr_poly
					(pts
						(arc
							(start -0.1778 -0.2794)
							(mid -0.249642 -0.249642)
							(end -0.2794 -0.1778)
						)
						(arc
							(start -0.2794 0.1778)
							(mid -0.249642 0.249642)
							(end -0.1778 0.2794)
						)
						(arc
							(start 0.1778 0.2794)
							(mid 0.249642 0.249642)
							(end 0.2794 0.1778)
						)
						(arc
							(start 0.2794 -0.1778)
							(mid 0.249642 -0.249642)
							(end 0.1778 -0.2794)
						)
					)
					(width 0)
					(fill yes)
				)
			)
		)
		(pad "2" smd custom
			(at 0 0.4445 270)
			(size 0.1397 0.1397)
			(layers "F.Cu" "F.Mask" "F.Paste")
			(net "D_FLIP_B_Q#")
			(options
				(clearance outline)
				(anchor circle)
			)
			(primitives
				(gr_poly
					(pts
						(arc
							(start -0.1778 -0.2794)
							(mid -0.249642 -0.249642)
							(end -0.2794 -0.1778)
						)
						(arc
							(start -0.2794 0.1778)
							(mid -0.249642 0.249642)
							(end -0.1778 0.2794)
						)
						(arc
							(start 0.1778 0.2794)
							(mid 0.249642 0.249642)
							(end 0.2794 0.1778)
						)
						(arc
							(start 0.2794 -0.1778)
							(mid 0.249642 -0.249642)
							(end 0.1778 -0.2794)
						)
					)
					(width 0)
					(fill yes)
				)
			)
		)
	)
	(footprint ""
		(layer "F.Cu")
		(at 55.2196 -46.0502 90)
		(property "Reference" "R37"
			(at 0 0 90)
			(layer "F.SilkS")
			(hide yes)
			(effects
				(font
					(size 1.27 1.27)
				)
			)
		)
		(property "Value" "4K7R2F-GP"
			(at 0.064008 -4.679696 90)
			(unlocked yes)
			(layer "F.Fab")
			(hide yes)
			(effects
				(font
					(size 2.54 2.54)
					(thickness 0.381)
				)
			)
		)
		(property "Device Type" "R402H16"
			(at 0.064008 -6.203696 90)
			(unlocked yes)
			(layer "F.Fab")
			(hide yes)
			(effects
				(font
					(size 2.54 2.54)
					(thickness 0.381)
				)
			)
		)
		(duplicate_pad_numbers_are_jumpers no)
		(fp_line
			(start 0.508 -0.9398)
			(end -0.508 -0.9398)
			(stroke
				(width 0.1524)
				(type default)
			)
			(layer "F.SilkS")
		)
		(fp_line
			(start -0.508 -0.9398)
			(end -0.508 0.9398)
			(stroke
				(width 0.1524)
				(type default)
			)
			(layer "F.SilkS")
		)
		(fp_rect
			(start -0.508 0.9398)
			(end 0.508 -0.9398)
			(stroke
				(width 0)
				(type default)
			)
			(fill no)
			(layer "F.CrtYd")
		)
		(fp_rect
			(start -0.508 0.9398)
			(end 0.508 -0.9398)
			(stroke
				(width 0)
				(type default)
			)
			(fill no)
			(layer "F.Fab")
		)
		(pad "1" smd custom
			(at 0 -0.4445 90)
			(size 0.1397 0.1397)
			(layers "F.Cu" "F.Mask" "F.Paste")
			(net "TEMP_2_A2")
			(options
				(clearance outline)
				(anchor circle)
			)
			(primitives
				(gr_poly
					(pts
						(arc
							(start -0.1778 -0.2794)
							(mid -0.249642 -0.249642)
							(end -0.2794 -0.1778)
						)
						(arc
							(start -0.2794 0.1778)
							(mid -0.249642 0.249642)
							(end -0.1778 0.2794)
						)
						(arc
							(start 0.1778 0.2794)
							(mid 0.249642 0.249642)
							(end 0.2794 0.1778)
						)
						(arc
							(start 0.2794 -0.1778)
							(mid 0.249642 -0.249642)
							(end 0.1778 -0.2794)
						)
					)
					(width 0)
					(fill yes)
				)
			)
		)
		(pad "2" smd custom
			(at 0 0.4445 90)
			(size 0.1397 0.1397)
			(layers "F.Cu" "F.Mask" "F.Paste")
			(net "GND")
			(options
				(clearance outline)
				(anchor circle)
			)
			(primitives
				(gr_poly
					(pts
						(arc
							(start -0.1778 -0.2794)
							(mid -0.249642 -0.249642)
							(end -0.2794 -0.1778)
						)
						(arc
							(start -0.2794 0.1778)
							(mid -0.249642 0.249642)
							(end -0.1778 0.2794)
						)
						(arc
							(start 0.1778 0.2794)
							(mid 0.249642 0.249642)
							(end 0.2794 0.1778)
						)
						(arc
							(start 0.2794 -0.1778)
							(mid 0.249642 -0.249642)
							(end 0.1778 -0.2794)
						)
					)
					(width 0)
					(fill yes)
				)
			)
		)
	)
	(footprint ""
		(layer "F.Cu")
		(at 55.621428 -12.481306 90)
		(property "Reference" "R10"
			(at 0 0 90)
			(layer "F.SilkS")
			(hide yes)
			(effects
				(font
					(size 1.27 1.27)
				)
			)
		)
		(property "Value" "0R2J-2-GP"
			(at 0.064008 -4.679696 90)
			(unlocked yes)
			(layer "F.Fab")
			(hide yes)
			(effects
				(font
					(size 2.54 2.54)
					(thickness 0.381)
				)
			)
		)
		(property "Device Type" "R402H16"
			(at 0.064008 -6.203696 90)
			(unlocked yes)
			(layer "F.Fab")
			(hide yes)
			(effects
				(font
					(size 2.54 2.54)
					(thickness 0.381)
				)
			)
		)
		(duplicate_pad_numbers_are_jumpers no)
		(fp_line
			(start 0.508 -0.9398)
			(end -0.508 -0.9398)
			(stroke
				(width 0.1524)
				(type default)
			)
			(layer "F.SilkS")
		)
		(fp_line
			(start -0.508 -0.9398)
			(end -0.508 0.9398)
			(stroke
				(width 0.1524)
				(type default)
			)
			(layer "F.SilkS")
		)
		(fp_rect
			(start -0.508 0.9398)
			(end 0.508 -0.9398)
			(stroke
				(width 0)
				(type default)
			)
			(fill no)
			(layer "F.CrtYd")
		)
		(fp_rect
			(start -0.508 0.9398)
			(end 0.508 -0.9398)
			(stroke
				(width 0)
				(type default)
			)
			(fill no)
			(layer "F.Fab")
		)
		(pad "1" smd custom
			(at 0 -0.4445 90)
			(size 0.1397 0.1397)
			(layers "F.Cu" "F.Mask" "F.Paste")
			(net "UART_SEL_B_MUX_R")
			(options
				(clearance outline)
				(anchor circle)
			)
			(primitives
				(gr_poly
					(pts
						(arc
							(start -0.1778 -0.2794)
							(mid -0.249642 -0.249642)
							(end -0.2794 -0.1778)
						)
						(arc
							(start -0.2794 0.1778)
							(mid -0.249642 0.249642)
							(end -0.1778 0.2794)
						)
						(arc
							(start 0.1778 0.2794)
							(mid 0.249642 0.249642)
							(end 0.2794 0.1778)
						)
						(arc
							(start 0.2794 -0.1778)
							(mid 0.249642 -0.249642)
							(end 0.1778 -0.2794)
						)
					)
					(width 0)
					(fill yes)
				)
			)
		)
		(pad "2" smd custom
			(at 0 0.4445 90)
			(size 0.1397 0.1397)
			(layers "F.Cu" "F.Mask" "F.Paste")
			(net "GND")
			(options
				(clearance outline)
				(anchor circle)
			)
			(primitives
				(gr_poly
					(pts
						(arc
							(start -0.1778 -0.2794)
							(mid -0.249642 -0.249642)
							(end -0.2794 -0.1778)
						)
						(arc
							(start -0.2794 0.1778)
							(mid -0.249642 0.249642)
							(end -0.1778 0.2794)
						)
						(arc
							(start 0.1778 0.2794)
							(mid 0.249642 0.249642)
							(end 0.2794 0.1778)
						)
						(arc
							(start 0.2794 -0.1778)
							(mid 0.249642 -0.249642)
							(end 0.1778 -0.2794)
						)
					)
					(width 0)
					(fill yes)
				)
			)
		)
	)
	(footprint ""
		(layer "F.Cu")
		(at 20.1168 -16.3322)
		(property "Reference" "R66"
			(at 0 0 0)
			(layer "F.SilkS")
			(hide yes)
			(effects
				(font
					(size 1.27 1.27)
				)
			)
		)
		(property "Value" "4K7R2F-GP"
			(at 0.064008 -3.993896 0)
			(unlocked yes)
			(layer "F.Fab")
			(hide yes)
			(effects
				(font
					(size 1.016 1.016)
					(thickness 0.1524)
				)
			)
		)
		(property "Device Type" "R402H16"
			(at 0.064008 -5.517896 0)
			(unlocked yes)
			(layer "F.Fab")
			(hide yes)
			(effects
				(font
					(size 1.016 1.016)
					(thickness 0.1524)
				)
			)
		)
		(duplicate_pad_numbers_are_jumpers no)
		(fp_line
			(start -0.508 -0.9398)
			(end -0.508 0.9398)
			(stroke
				(width 0.1524)
				(type default)
			)
			(layer "F.SilkS")
		)
		(fp_line
			(start 0.508 -0.9398)
			(end -0.508 -0.9398)
			(stroke
				(width 0.1524)
				(type default)
			)
			(layer "F.SilkS")
		)
		(fp_rect
			(start -0.508 0.9398)
			(end 0.508 -0.9398)
			(stroke
				(width 0)
				(type default)
			)
			(fill no)
			(layer "F.CrtYd")
		)
		(fp_rect
			(start -0.508 0.9398)
			(end 0.508 -0.9398)
			(stroke
				(width 0)
				(type default)
			)
			(fill no)
			(layer "F.Fab")
		)
		(pad "1" smd custom
			(at 0 -0.4445)
			(size 0.1397 0.1397)
			(layers "F.Cu" "F.Mask" "F.Paste")
			(net "TCA9555_A_A1")
			(options
				(clearance outline)
				(anchor circle)
			)
			(primitives
				(gr_poly
					(pts
						(arc
							(start -0.1778 -0.2794)
							(mid -0.249642 -0.249642)
							(end -0.2794 -0.1778)
						)
						(arc
							(start -0.2794 0.1778)
							(mid -0.249642 0.249642)
							(end -0.1778 0.2794)
						)
						(arc
							(start 0.1778 0.2794)
							(mid 0.249642 0.249642)
							(end 0.2794 0.1778)
						)
						(arc
							(start 0.2794 -0.1778)
							(mid 0.249642 -0.249642)
							(end 0.1778 -0.2794)
						)
					)
					(width 0)
					(fill yes)
				)
			)
		)
		(pad "2" smd custom
			(at 0 0.4445)
			(size 0.1397 0.1397)
			(layers "F.Cu" "F.Mask" "F.Paste")
			(net "GND")
			(options
				(clearance outline)
				(anchor circle)
			)
			(primitives
				(gr_poly
					(pts
						(arc
							(start -0.1778 -0.2794)
							(mid -0.249642 -0.249642)
							(end -0.2794 -0.1778)
						)
						(arc
							(start -0.2794 0.1778)
							(mid -0.249642 0.249642)
							(end -0.1778 0.2794)
						)
						(arc
							(start 0.1778 0.2794)
							(mid 0.249642 0.249642)
							(end 0.2794 0.1778)
						)
						(arc
							(start 0.2794 -0.1778)
							(mid 0.249642 -0.249642)
							(end 0.1778 -0.2794)
						)
					)
					(width 0)
					(fill yes)
				)
			)
		)
	)
	(footprint ""
		(layer "F.Cu")
		(at 46.647862 -48.528732)
		(property "Reference" "TP8"
			(at 0 0 0)
			(layer "F.SilkS")
			(hide yes)
			(effects
				(font
					(size 1.27 1.27)
				)
			)
		)
		(property "Value" "TPAD32-GP"
			(at -0.0508 -1.6764 0)
			(unlocked yes)
			(layer "F.Fab")
			(hide yes)
			(effects
				(font
					(size 1.016 1.016)
					(thickness 0.1524)
				)
			)
		)
		(property "Device Type" "TPAD32"
			(at -0.0508 -3.2004 0)
			(unlocked yes)
			(layer "F.Fab")
			(hide yes)
			(effects
				(font
					(size 1.016 1.016)
					(thickness 0.1524)
				)
			)
		)
		(duplicate_pad_numbers_are_jumpers no)
		(fp_poly
			(pts
				(arc
					(start 0.4064 0)
					(mid -0.4064 0)
					(end 0.4064 0)
				)
			)
			(stroke
				(width 0)
				(type default)
			)
			(fill no)
			(layer "F.CrtYd")
		)
		(fp_poly
			(pts
				(arc
					(start 0.7112 0)
					(mid -0.7112 0)
					(end 0.7112 0)
				)
			)
			(stroke
				(width 0)
				(type default)
			)
			(fill no)
			(layer "F.Fab")
		)
		(pad "1" smd circle
			(at 0 0)
			(size 0.8128 0.8128)
			(layers "F.Cu" "F.Mask" "F.Paste")
			(net "TEMP_2_ALERT")
		)
	)
	(footprint ""
		(layer "F.Cu")
		(at 42.342308 -9.672828 90)
		(property "Reference" "U13"
			(at 0 0 90)
			(layer "F.SilkS")
			(hide yes)
			(effects
				(font
					(size 1.27 1.27)
				)
			)
		)
		(property "Value" "SNLVC1G126DCKR-GP"
			(at -2.3368 -8.6868 90)
			(unlocked yes)
			(layer "F.Fab")
			(hide yes)
			(effects
				(font
					(size 1.016 1.016)
					(thickness 0.1524)
				)
			)
		)
		(property "Device Type" "SC70-5H44"
			(at -2.3114 -10.414 90)
			(unlocked yes)
			(layer "F.Fab")
			(hide yes)
			(effects
				(font
					(size 1.016 1.016)
					(thickness 0.1524)
				)
			)
		)
		(duplicate_pad_numbers_are_jumpers no)
		(fp_line
			(start 1.3843 -1.8034)
			(end 1.3843 -1.1176)
			(stroke
				(width 0.3302)
				(type default)
			)
			(layer "F.SilkS")
		)
		(fp_line
			(start 0.6604 -1.8034)
			(end 1.3843 -1.8034)
			(stroke
				(width 0.3302)
				(type default)
			)
			(layer "F.SilkS")
		)
		(fp_line
			(start 1.27 -1.7018)
			(end 1.27 1.7018)
			(stroke
				(width 0.1524)
				(type default)
			)
			(layer "F.SilkS")
		)
		(fp_line
			(start -1.27 -1.7018)
			(end 1.27 -1.7018)
			(stroke
				(width 0.1524)
				(type default)
			)
			(layer "F.SilkS")
		)
		(fp_line
			(start 1.27 1.7018)
			(end -1.27 1.7018)
			(stroke
				(width 0.1524)
				(type default)
			)
			(layer "F.SilkS")
		)
		(fp_line
			(start -1.27 1.7018)
			(end -1.27 -1.7018)
			(stroke
				(width 0.1524)
				(type default)
			)
			(layer "F.SilkS")
		)
		(fp_rect
			(start -1.524 1.9558)
			(end 1.524 -1.9558)
			(stroke
				(width 0)
				(type default)
			)
			(fill no)
			(layer "F.CrtYd")
		)
		(fp_poly
			(pts
				(xy -1.524 -1.9558) (xy 1.524 -1.9558) (xy 1.524 1.9558) (xy -1.524 1.9558)
			)
			(stroke
				(width 0)
				(type default)
			)
			(fill no)
			(layer "F.Fab")
		)
		(pad "1" smd rect
			(at 0.65024 -0.8255 90)
			(size 0.4064 1.2192)
			(layers "F.Cu" "F.Mask" "F.Paste")
			(net "DEBUG_CARD_B_PRSNT")
		)
		(pad "2" smd rect
			(at 0 -0.8255 90)
			(size 0.4064 1.2192)
			(layers "F.Cu" "F.Mask" "F.Paste")
			(net "UART_B_TX")
		)
		(pad "3" smd rect
			(at -0.65024 -0.8255 90)
			(size 0.4064 1.2192)
			(layers "F.Cu" "F.Mask" "F.Paste")
			(net "GND")
		)
		(pad "4" smd rect
			(at -0.65024 0.8255 90)
			(size 0.4064 1.2192)
			(layers "F.Cu" "F.Mask" "F.Paste")
			(net "UART_DEBUG_B_TX")
		)
		(pad "5" smd rect
			(at 0.65024 0.8255 90)
			(size 0.4064 1.2192)
			(layers "F.Cu" "F.Mask" "F.Paste")
			(net "P3V3_STBY_B")
		)
	)
	(footprint ""
		(layer "F.Cu")
		(at 4.977892 -39.310818 90)
		(property "Reference" "C11"
			(at 0 0 90)
			(layer "F.SilkS")
			(hide yes)
			(effects
				(font
					(size 1.27 1.27)
				)
			)
		)
		(property "Value" "SC1U16V3KX-5GP"
			(at 0 -3.5052 90)
			(unlocked yes)
			(layer "F.Fab")
			(hide yes)
			(effects
				(font
					(size 2.54 2.54)
					(thickness 0.381)
				)
			)
		)
		(property "Device Type" "C603H36"
			(at 0 -5.0292 90)
			(unlocked yes)
			(layer "F.Fab")
			(hide yes)
			(effects
				(font
					(size 2.54 2.54)
					(thickness 0.381)
				)
			)
		)
		(duplicate_pad_numbers_are_jumpers no)
		(fp_line
			(start 0.508 0)
			(end -0.508 0)
			(stroke
				(width 0.2032)
				(type default)
			)
			(layer "F.SilkS")
		)
		(fp_rect
			(start -0.5842 1.3335)
			(end 0.5842 -1.3335)
			(stroke
				(width 0)
				(type default)
			)
			(fill no)
			(layer "F.CrtYd")
		)
		(fp_rect
			(start -0.5842 1.3335)
			(end 0.5842 -1.3335)
			(stroke
				(width 0)
				(type default)
			)
			(fill no)
			(layer "F.Fab")
		)
		(pad "1" smd custom
			(at 0 -0.762 90)
			(size 0.2159 0.2159)
			(layers "F.Cu" "F.Mask" "F.Paste")
			(net "SYS_RESET_BTN_A")
			(options
				(clearance outline)
				(anchor circle)
			)
			(primitives
				(gr_poly
					(pts
						(arc
							(start -0.3302 -0.4318)
							(mid -0.402042 -0.402042)
							(end -0.4318 -0.3302)
						)
						(arc
							(start -0.4318 0.3302)
							(mid -0.402042 0.402042)
							(end -0.3302 0.4318)
						)
						(arc
							(start 0.3302 0.4318)
							(mid 0.402042 0.402042)
							(end 0.4318 0.3302)
						)
						(arc
							(start 0.4318 -0.3302)
							(mid 0.402042 -0.402042)
							(end 0.3302 -0.4318)
						)
					)
					(width 0)
					(fill yes)
				)
			)
		)
		(pad "2" smd custom
			(at 0 0.762 90)
			(size 0.2159 0.2159)
			(layers "F.Cu" "F.Mask" "F.Paste")
			(net "GND")
			(options
				(clearance outline)
				(anchor circle)
			)
			(primitives
				(gr_poly
					(pts
						(arc
							(start -0.3302 -0.4318)
							(mid -0.402042 -0.402042)
							(end -0.4318 -0.3302)
						)
						(arc
							(start -0.4318 0.3302)
							(mid -0.402042 0.402042)
							(end -0.3302 0.4318)
						)
						(arc
							(start 0.3302 0.4318)
							(mid 0.402042 0.402042)
							(end 0.4318 0.3302)
						)
						(arc
							(start 0.4318 -0.3302)
							(mid 0.402042 -0.402042)
							(end 0.3302 -0.4318)
						)
					)
					(width 0)
					(fill yes)
				)
			)
		)
	)
	(footprint ""
		(layer "F.Cu")
		(at 13.3604 -6.4262)
		(property "Reference" "C21"
			(at 0 0 0)
			(layer "F.SilkS")
			(hide yes)
			(effects
				(font
					(size 1.27 1.27)
				)
			)
		)
		(property "Value" "SCD1U16V2KX-3GP"
			(at 1.1811 -2.7051 0)
			(unlocked yes)
			(layer "F.Fab")
			(hide yes)
			(effects
				(font
					(size 1.016 1.016)
					(thickness 0.1524)
				)
			)
		)
		(property "Device Type" "C402H22"
			(at 1.1811 -4.2291 0)
			(unlocked yes)
			(layer "F.Fab")
			(hide yes)
			(effects
				(font
					(size 1.016 1.016)
					(thickness 0.1524)
				)
			)
		)
		(duplicate_pad_numbers_are_jumpers no)
		(fp_rect
			(start -0.4318 0.9525)
			(end 0.4318 -0.9525)
			(stroke
				(width 0)
				(type default)
			)
			(fill no)
			(layer "F.CrtYd")
		)
		(fp_rect
			(start -0.4318 0.9525)
			(end 0.4318 -0.9525)
			(stroke
				(width 0)
				(type default)
			)
			(fill no)
			(layer "F.Fab")
		)
		(pad "1" smd custom
			(at 0 -0.4445)
			(size 0.1524 0.1524)
			(layers "F.Cu" "F.Mask" "F.Paste")
			(net "P3V3_STBY_A")
			(options
				(clearance outline)
				(anchor circle)
			)
			(primitives
				(gr_poly
					(pts
						(arc
							(start 0.3048 -0.2032)
							(mid 0.275042 -0.275042)
							(end 0.2032 -0.3048)
						)
						(arc
							(start -0.2032 -0.3048)
							(mid -0.275042 -0.275042)
							(end -0.3048 -0.2032)
						)
						(arc
							(start -0.3048 0.2032)
							(mid -0.275042 0.275042)
							(end -0.2032 0.3048)
						)
						(arc
							(start 0.2032 0.3048)
							(mid 0.275042 0.275042)
							(end 0.3048 0.2032)
						)
					)
					(width 0)
					(fill yes)
				)
			)
		)
		(pad "2" smd custom
			(at 0 0.4445)
			(size 0.1524 0.1524)
			(layers "F.Cu" "F.Mask" "F.Paste")
			(net "GND")
			(options
				(clearance outline)
				(anchor circle)
			)
			(primitives
				(gr_poly
					(pts
						(arc
							(start 0.3048 -0.2032)
							(mid 0.275042 -0.275042)
							(end 0.2032 -0.3048)
						)
						(arc
							(start -0.2032 -0.3048)
							(mid -0.275042 -0.275042)
							(end -0.3048 -0.2032)
						)
						(arc
							(start -0.3048 0.2032)
							(mid -0.275042 0.275042)
							(end -0.2032 0.3048)
						)
						(arc
							(start 0.2032 0.3048)
							(mid 0.275042 0.275042)
							(end 0.3048 0.2032)
						)
					)
					(width 0)
					(fill yes)
				)
			)
		)
	)
	(footprint ""
		(layer "F.Cu")
		(at 4.0386 -21.4884 180)
		(property "Reference" "C20"
			(at 0 0 180)
			(layer "F.SilkS")
			(hide yes)
			(effects
				(font
					(size 1.27 1.27)
				)
			)
		)
		(property "Value" "SCD1U16V2KX-3GP"
			(at 1.1811 -2.7051 180)
			(unlocked yes)
			(layer "F.Fab")
			(hide yes)
			(effects
				(font
					(size 1.016 1.016)
					(thickness 0.1524)
				)
			)
		)
		(property "Device Type" "C402H22"
			(at 1.1811 -4.2291 180)
			(unlocked yes)
			(layer "F.Fab")
			(hide yes)
			(effects
				(font
					(size 1.016 1.016)
					(thickness 0.1524)
				)
			)
		)
		(duplicate_pad_numbers_are_jumpers no)
		(fp_rect
			(start -0.4318 0.9525)
			(end 0.4318 -0.9525)
			(stroke
				(width 0)
				(type default)
			)
			(fill no)
			(layer "F.CrtYd")
		)
		(fp_rect
			(start -0.4318 0.9525)
			(end 0.4318 -0.9525)
			(stroke
				(width 0)
				(type default)
			)
			(fill no)
			(layer "F.Fab")
		)
		(pad "1" smd custom
			(at 0 -0.4445 180)
			(size 0.1524 0.1524)
			(layers "F.Cu" "F.Mask" "F.Paste")
			(net "P3V3_STBY_A")
			(options
				(clearance outline)
				(anchor circle)
			)
			(primitives
				(gr_poly
					(pts
						(arc
							(start 0.3048 -0.2032)
							(mid 0.275042 -0.275042)
							(end 0.2032 -0.3048)
						)
						(arc
							(start -0.2032 -0.3048)
							(mid -0.275042 -0.275042)
							(end -0.3048 -0.2032)
						)
						(arc
							(start -0.3048 0.2032)
							(mid -0.275042 0.275042)
							(end -0.2032 0.3048)
						)
						(arc
							(start 0.2032 0.3048)
							(mid 0.275042 0.275042)
							(end 0.3048 0.2032)
						)
					)
					(width 0)
					(fill yes)
				)
			)
		)
		(pad "2" smd custom
			(at 0 0.4445 180)
			(size 0.1524 0.1524)
			(layers "F.Cu" "F.Mask" "F.Paste")
			(net "GND")
			(options
				(clearance outline)
				(anchor circle)
			)
			(primitives
				(gr_poly
					(pts
						(arc
							(start 0.3048 -0.2032)
							(mid 0.275042 -0.275042)
							(end 0.2032 -0.3048)
						)
						(arc
							(start -0.2032 -0.3048)
							(mid -0.275042 -0.275042)
							(end -0.3048 -0.2032)
						)
						(arc
							(start -0.3048 0.2032)
							(mid -0.275042 0.275042)
							(end -0.2032 0.3048)
						)
						(arc
							(start 0.2032 0.3048)
							(mid 0.275042 0.275042)
							(end 0.3048 0.2032)
						)
					)
					(width 0)
					(fill yes)
				)
			)
		)
	)
	(footprint ""
		(layer "F.Cu")
		(at 8.9408 -15.9004 -90)
		(property "Reference" "R5"
			(at 0 0 270)
			(layer "F.SilkS")
			(hide yes)
			(effects
				(font
					(size 1.27 1.27)
				)
			)
		)
		(property "Value" "0R2J-2-GP"
			(at 0.064008 -4.679696 270)
			(unlocked yes)
			(layer "F.Fab")
			(hide yes)
			(effects
				(font
					(size 2.54 2.54)
					(thickness 0.381)
				)
			)
		)
		(property "Device Type" "R402H16"
			(at 0.064008 -6.203696 270)
			(unlocked yes)
			(layer "F.Fab")
			(hide yes)
			(effects
				(font
					(size 2.54 2.54)
					(thickness 0.381)
				)
			)
		)
		(duplicate_pad_numbers_are_jumpers no)
		(fp_line
			(start -0.508 -0.9398)
			(end -0.508 0.9398)
			(stroke
				(width 0.1524)
				(type default)
			)
			(layer "F.SilkS")
		)
		(fp_line
			(start 0.508 -0.9398)
			(end -0.508 -0.9398)
			(stroke
				(width 0.1524)
				(type default)
			)
			(layer "F.SilkS")
		)
		(fp_rect
			(start -0.508 0.9398)
			(end 0.508 -0.9398)
			(stroke
				(width 0)
				(type default)
			)
			(fill no)
			(layer "F.CrtYd")
		)
		(fp_rect
			(start -0.508 0.9398)
			(end 0.508 -0.9398)
			(stroke
				(width 0)
				(type default)
			)
			(fill no)
			(layer "F.Fab")
		)
		(pad "1" smd custom
			(at 0 -0.4445 270)
			(size 0.1397 0.1397)
			(layers "F.Cu" "F.Mask" "F.Paste")
			(net "I2C_DEBUG_A_SDA_R")
			(options
				(clearance outline)
				(anchor circle)
			)
			(primitives
				(gr_poly
					(pts
						(arc
							(start -0.1778 -0.2794)
							(mid -0.249642 -0.249642)
							(end -0.2794 -0.1778)
						)
						(arc
							(start -0.2794 0.1778)
							(mid -0.249642 0.249642)
							(end -0.1778 0.2794)
						)
						(arc
							(start 0.1778 0.2794)
							(mid 0.249642 0.249642)
							(end 0.2794 0.1778)
						)
						(arc
							(start 0.2794 -0.1778)
							(mid 0.249642 -0.249642)
							(end 0.1778 -0.2794)
						)
					)
					(width 0)
					(fill yes)
				)
			)
		)
		(pad "2" smd custom
			(at 0 0.4445 270)
			(size 0.1397 0.1397)
			(layers "F.Cu" "F.Mask" "F.Paste")
			(net "I2C_DEBUG_A_SDA_L")
			(options
				(clearance outline)
				(anchor circle)
			)
			(primitives
				(gr_poly
					(pts
						(arc
							(start -0.1778 -0.2794)
							(mid -0.249642 -0.249642)
							(end -0.2794 -0.1778)
						)
						(arc
							(start -0.2794 0.1778)
							(mid -0.249642 0.249642)
							(end -0.1778 0.2794)
						)
						(arc
							(start 0.1778 0.2794)
							(mid 0.249642 0.249642)
							(end 0.2794 0.1778)
						)
						(arc
							(start 0.2794 -0.1778)
							(mid 0.249642 -0.249642)
							(end 0.1778 -0.2794)
						)
					)
					(width 0)
					(fill yes)
				)
			)
		)
	)
	(footprint ""
		(layer "F.Cu")
		(at 45.38853 -47.028862 90)
		(property "Reference" "TP4"
			(at 0 0 90)
			(layer "F.SilkS")
			(hide yes)
			(effects
				(font
					(size 1.27 1.27)
				)
			)
		)
		(property "Value" "TPAD28-2-GP"
			(at -0.0127 -2.3495 90)
			(unlocked yes)
			(layer "F.Fab")
			(hide yes)
			(effects
				(font
					(size 2.54 2.54)
					(thickness 0.381)
				)
			)
		)
		(property "Device Type" "TPAD28"
			(at -0.0127 -3.8735 90)
			(unlocked yes)
			(layer "F.Fab")
			(hide yes)
			(effects
				(font
					(size 2.54 2.54)
					(thickness 0.381)
				)
			)
		)
		(duplicate_pad_numbers_are_jumpers no)
		(fp_poly
			(pts
				(arc
					(start 0 0.3556)
					(mid 0 -0.3556)
					(end 0 0.3556)
				)
			)
			(stroke
				(width 0)
				(type default)
			)
			(fill no)
			(layer "F.CrtYd")
		)
		(fp_poly
			(pts
				(arc
					(start 0 0.6096)
					(mid 0 -0.6096)
					(end 0 0.6096)
				)
			)
			(stroke
				(width 0)
				(type default)
			)
			(fill no)
			(layer "F.Fab")
		)
		(pad "1" smd circle
			(at 0 0 90)
			(size 0.7112 0.7112)
			(layers "F.Cu" "F.Mask" "F.Paste")
			(net "DEBUG_USB_B_DN")
		)
	)
	(footprint ""
		(layer "F.Cu")
		(at 25.222454 -8.264398 -90)
		(property "Reference" "R19"
			(at 0 0 270)
			(layer "F.SilkS")
			(hide yes)
			(effects
				(font
					(size 1.27 1.27)
				)
			)
		)
		(property "Value" "0R2J-2-GP"
			(at 0.064008 -3.993896 270)
			(unlocked yes)
			(layer "F.Fab")
			(hide yes)
			(effects
				(font
					(size 1.016 1.016)
					(thickness 0.1524)
				)
			)
		)
		(property "Device Type" "R402H16"
			(at 0.064008 -5.517896 270)
			(unlocked yes)
			(layer "F.Fab")
			(hide yes)
			(effects
				(font
					(size 1.016 1.016)
					(thickness 0.1524)
				)
			)
		)
		(duplicate_pad_numbers_are_jumpers no)
		(fp_line
			(start -0.508 -0.9398)
			(end -0.508 0.9398)
			(stroke
				(width 0.1524)
				(type default)
			)
			(layer "F.SilkS")
		)
		(fp_line
			(start 0.508 -0.9398)
			(end -0.508 -0.9398)
			(stroke
				(width 0.1524)
				(type default)
			)
			(layer "F.SilkS")
		)
		(fp_rect
			(start -0.508 0.9398)
			(end 0.508 -0.9398)
			(stroke
				(width 0)
				(type default)
			)
			(fill no)
			(layer "F.CrtYd")
		)
		(fp_rect
			(start -0.508 0.9398)
			(end 0.508 -0.9398)
			(stroke
				(width 0)
				(type default)
			)
			(fill no)
			(layer "F.Fab")
		)
		(pad "1" smd custom
			(at 0 -0.4445 270)
			(size 0.1397 0.1397)
			(layers "F.Cu" "F.Mask" "F.Paste")
			(net "D_FLIP_PRE_A#")
			(options
				(clearance outline)
				(anchor circle)
			)
			(primitives
				(gr_poly
					(pts
						(arc
							(start -0.1778 -0.2794)
							(mid -0.249642 -0.249642)
							(end -0.2794 -0.1778)
						)
						(arc
							(start -0.2794 0.1778)
							(mid -0.249642 0.249642)
							(end -0.1778 0.2794)
						)
						(arc
							(start 0.1778 0.2794)
							(mid 0.249642 0.249642)
							(end 0.2794 0.1778)
						)
						(arc
							(start 0.2794 -0.1778)
							(mid 0.249642 -0.249642)
							(end 0.1778 -0.2794)
						)
					)
					(width 0)
					(fill yes)
				)
			)
		)
		(pad "2" smd custom
			(at 0 0.4445 270)
			(size 0.1397 0.1397)
			(layers "F.Cu" "F.Mask" "F.Paste")
			(net "P3V3_STBY_A")
			(options
				(clearance outline)
				(anchor circle)
			)
			(primitives
				(gr_poly
					(pts
						(arc
							(start -0.1778 -0.2794)
							(mid -0.249642 -0.249642)
							(end -0.2794 -0.1778)
						)
						(arc
							(start -0.2794 0.1778)
							(mid -0.249642 0.249642)
							(end -0.1778 0.2794)
						)
						(arc
							(start 0.1778 0.2794)
							(mid 0.249642 0.249642)
							(end 0.2794 0.1778)
						)
						(arc
							(start 0.2794 -0.1778)
							(mid 0.249642 -0.249642)
							(end 0.1778 -0.2794)
						)
					)
					(width 0)
					(fill yes)
				)
			)
		)
	)
	(footprint ""
		(layer "F.Cu")
		(at 13.97 -8.2042 90)
		(property "Reference" "R59"
			(at 0 0 90)
			(layer "F.SilkS")
			(hide yes)
			(effects
				(font
					(size 1.27 1.27)
				)
			)
		)
		(property "Value" "100KR2F-L1-GP"
			(at 0.064008 -3.993896 90)
			(unlocked yes)
			(layer "F.Fab")
			(hide yes)
			(effects
				(font
					(size 1.016 1.016)
					(thickness 0.1524)
				)
			)
		)
		(property "Device Type" "R402H16"
			(at 0.064008 -5.517896 90)
			(unlocked yes)
			(layer "F.Fab")
			(hide yes)
			(effects
				(font
					(size 1.016 1.016)
					(thickness 0.1524)
				)
			)
		)
		(duplicate_pad_numbers_are_jumpers no)
		(fp_line
			(start 0.508 -0.9398)
			(end -0.508 -0.9398)
			(stroke
				(width 0.1524)
				(type default)
			)
			(layer "F.SilkS")
		)
		(fp_line
			(start -0.508 -0.9398)
			(end -0.508 0.9398)
			(stroke
				(width 0.1524)
				(type default)
			)
			(layer "F.SilkS")
		)
		(fp_rect
			(start -0.508 0.9398)
			(end 0.508 -0.9398)
			(stroke
				(width 0)
				(type default)
			)
			(fill no)
			(layer "F.CrtYd")
		)
		(fp_rect
			(start -0.508 0.9398)
			(end 0.508 -0.9398)
			(stroke
				(width 0)
				(type default)
			)
			(fill no)
			(layer "F.Fab")
		)
		(pad "1" smd custom
			(at 0 -0.4445 90)
			(size 0.1397 0.1397)
			(layers "F.Cu" "F.Mask" "F.Paste")
			(net "DEBUG_CARD_A_PRSNT")
			(options
				(clearance outline)
				(anchor circle)
			)
			(primitives
				(gr_poly
					(pts
						(arc
							(start -0.1778 -0.2794)
							(mid -0.249642 -0.249642)
							(end -0.2794 -0.1778)
						)
						(arc
							(start -0.2794 0.1778)
							(mid -0.249642 0.249642)
							(end -0.1778 0.2794)
						)
						(arc
							(start 0.1778 0.2794)
							(mid 0.249642 0.249642)
							(end 0.2794 0.1778)
						)
						(arc
							(start 0.2794 -0.1778)
							(mid 0.249642 -0.249642)
							(end 0.1778 -0.2794)
						)
					)
					(width 0)
					(fill yes)
				)
			)
		)
		(pad "2" smd custom
			(at 0 0.4445 90)
			(size 0.1397 0.1397)
			(layers "F.Cu" "F.Mask" "F.Paste")
			(net "GND")
			(options
				(clearance outline)
				(anchor circle)
			)
			(primitives
				(gr_poly
					(pts
						(arc
							(start -0.1778 -0.2794)
							(mid -0.249642 -0.249642)
							(end -0.2794 -0.1778)
						)
						(arc
							(start -0.2794 0.1778)
							(mid -0.249642 0.249642)
							(end -0.1778 0.2794)
						)
						(arc
							(start 0.1778 0.2794)
							(mid 0.249642 0.249642)
							(end 0.2794 0.1778)
						)
						(arc
							(start 0.2794 -0.1778)
							(mid 0.249642 -0.249642)
							(end 0.1778 -0.2794)
						)
					)
					(width 0)
					(fill yes)
				)
			)
		)
	)
	(footprint ""
		(layer "F.Cu")
		(at 2.131568 -52.79644 90)
		(property "Reference" "TP2"
			(at 0 0 90)
			(layer "F.SilkS")
			(hide yes)
			(effects
				(font
					(size 1.27 1.27)
				)
			)
		)
		(property "Value" "TPAD28-2-GP"
			(at -0.0127 -2.3495 90)
			(unlocked yes)
			(layer "F.Fab")
			(hide yes)
			(effects
				(font
					(size 2.54 2.54)
					(thickness 0.381)
				)
			)
		)
		(property "Device Type" "TPAD28"
			(at -0.0127 -3.8735 90)
			(unlocked yes)
			(layer "F.Fab")
			(hide yes)
			(effects
				(font
					(size 2.54 2.54)
					(thickness 0.381)
				)
			)
		)
		(duplicate_pad_numbers_are_jumpers no)
		(fp_poly
			(pts
				(arc
					(start 0 0.3556)
					(mid 0 -0.3556)
					(end 0 0.3556)
				)
			)
			(stroke
				(width 0)
				(type default)
			)
			(fill no)
			(layer "F.CrtYd")
		)
		(fp_poly
			(pts
				(arc
					(start 0 0.6096)
					(mid 0 -0.6096)
					(end 0 0.6096)
				)
			)
			(stroke
				(width 0)
				(type default)
			)
			(fill no)
			(layer "F.Fab")
		)
		(pad "1" smd circle
			(at 0 0 90)
			(size 0.7112 0.7112)
			(layers "F.Cu" "F.Mask" "F.Paste")
			(net "DEBUG_USB_A_DP")
		)
	)
	(footprint ""
		(layer "F.Cu")
		(at 30.0482 -5.969 -90)
		(property "Reference" "R80"
			(at 0 0 270)
			(layer "F.SilkS")
			(hide yes)
			(effects
				(font
					(size 1.27 1.27)
				)
			)
		)
		(property "Value" "4K7R2F-GP"
			(at 0.064008 -3.993896 270)
			(unlocked yes)
			(layer "F.Fab")
			(hide yes)
			(effects
				(font
					(size 1.016 1.016)
					(thickness 0.1524)
				)
			)
		)
		(property "Device Type" "R402H16"
			(at 0.064008 -5.517896 270)
			(unlocked yes)
			(layer "F.Fab")
			(hide yes)
			(effects
				(font
					(size 1.016 1.016)
					(thickness 0.1524)
				)
			)
		)
		(duplicate_pad_numbers_are_jumpers no)
		(fp_line
			(start -0.508 -0.9398)
			(end -0.508 0.9398)
			(stroke
				(width 0.1524)
				(type default)
			)
			(layer "F.SilkS")
		)
		(fp_line
			(start 0.508 -0.9398)
			(end -0.508 -0.9398)
			(stroke
				(width 0.1524)
				(type default)
			)
			(layer "F.SilkS")
		)
		(fp_rect
			(start -0.508 0.9398)
			(end 0.508 -0.9398)
			(stroke
				(width 0)
				(type default)
			)
			(fill no)
			(layer "F.CrtYd")
		)
		(fp_rect
			(start -0.508 0.9398)
			(end 0.508 -0.9398)
			(stroke
				(width 0)
				(type default)
			)
			(fill no)
			(layer "F.Fab")
		)
		(pad "1" smd custom
			(at 0 -0.4445 270)
			(size 0.1397 0.1397)
			(layers "F.Cu" "F.Mask" "F.Paste")
			(net "P3V3_STBY_B")
			(options
				(clearance outline)
				(anchor circle)
			)
			(primitives
				(gr_poly
					(pts
						(arc
							(start -0.1778 -0.2794)
							(mid -0.249642 -0.249642)
							(end -0.2794 -0.1778)
						)
						(arc
							(start -0.2794 0.1778)
							(mid -0.249642 0.249642)
							(end -0.1778 0.2794)
						)
						(arc
							(start 0.1778 0.2794)
							(mid 0.249642 0.249642)
							(end 0.2794 0.1778)
						)
						(arc
							(start 0.2794 -0.1778)
							(mid 0.249642 -0.249642)
							(end 0.1778 -0.2794)
						)
					)
					(width 0)
					(fill yes)
				)
			)
		)
		(pad "2" smd custom
			(at 0 0.4445 270)
			(size 0.1397 0.1397)
			(layers "F.Cu" "F.Mask" "F.Paste")
			(net "D_FLIP_CLR_B#")
			(options
				(clearance outline)
				(anchor circle)
			)
			(primitives
				(gr_poly
					(pts
						(arc
							(start -0.1778 -0.2794)
							(mid -0.249642 -0.249642)
							(end -0.2794 -0.1778)
						)
						(arc
							(start -0.2794 0.1778)
							(mid -0.249642 0.249642)
							(end -0.1778 0.2794)
						)
						(arc
							(start 0.1778 0.2794)
							(mid 0.249642 0.249642)
							(end 0.2794 0.1778)
						)
						(arc
							(start 0.2794 -0.1778)
							(mid 0.249642 -0.249642)
							(end 0.1778 -0.2794)
						)
					)
					(width 0)
					(fill yes)
				)
			)
		)
	)
	(footprint ""
		(layer "F.Cu")
		(at 50.546 -9.779 90)
		(property "Reference" "U3"
			(at 0 0 90)
			(layer "F.SilkS")
			(hide yes)
			(effects
				(font
					(size 1.27 1.27)
				)
			)
		)
		(property "Value" "TS5A23157DGSR-GP"
			(at 0 -11.811 90)
			(unlocked yes)
			(layer "F.Fab")
			(hide yes)
			(effects
				(font
					(size 2.54 2.54)
					(thickness 0.381)
				)
			)
		)
		(property "Device Type" "MSOP10H44"
			(at 0 -13.335 90)
			(unlocked yes)
			(layer "F.Fab")
			(hide yes)
			(effects
				(font
					(size 2.54 2.54)
					(thickness 0.381)
				)
			)
		)
		(duplicate_pad_numbers_are_jumpers no)
		(fp_line
			(start 1.143 -1.016)
			(end 1.143 1.016)
			(stroke
				(width 0.1524)
				(type default)
			)
			(layer "F.SilkS")
		)
		(fp_line
			(start -2.0066 -1.016)
			(end 1.143 -1.016)
			(stroke
				(width 0.1524)
				(type default)
			)
			(layer "F.SilkS")
		)
		(fp_line
			(start -1.5748 0)
			(end -1.9558 -0.381)
			(stroke
				(width 0.1524)
				(type default)
			)
			(layer "F.SilkS")
		)
		(fp_line
			(start -1.5748 0)
			(end -1.9558 0.381)
			(stroke
				(width 0.1524)
				(type default)
			)
			(layer "F.SilkS")
		)
		(fp_line
			(start 1.143 1.016)
			(end -2.0066 1.016)
			(stroke
				(width 0.1524)
				(type default)
			)
			(layer "F.SilkS")
		)
		(fp_line
			(start -1.8288 1.016)
			(end -1.8288 3.048)
			(stroke
				(width 0.508)
				(type default)
			)
			(layer "F.SilkS")
		)
		(fp_line
			(start -2.0066 1.016)
			(end -2.0066 -1.016)
			(stroke
				(width 0.1524)
				(type default)
			)
			(layer "F.SilkS")
		)
		(fp_poly
			(pts
				(xy -2.0828 3.3401) (xy 2.0828 3.3401) (xy 2.0828 -3.3401) (xy -2.0828 -3.3401)
			)
			(stroke
				(width 0)
				(type default)
			)
			(fill no)
			(layer "F.CrtYd")
		)
		(fp_poly
			(pts
				(xy -2.0828 3.3401) (xy 2.0828 3.3401) (xy 2.0828 -3.3401) (xy -2.0828 -3.3401)
			)
			(stroke
				(width 0)
				(type default)
			)
			(fill no)
			(layer "F.Fab")
		)
		(pad "1" smd rect
			(at -0.99949 2.0701 90)
			(size 0.3048 1.524)
			(layers "F.Cu" "F.Mask" "F.Paste")
			(net "UART_SEL_B_MUX_R")
		)
		(pad "2" smd rect
			(at -0.50038 2.0701 90)
			(size 0.3048 1.524)
			(layers "F.Cu" "F.Mask" "F.Paste")
			(net "UART_EXP_B_TX")
		)
		(pad "3" smd rect
			(at 0 2.0701 90)
			(size 0.3048 1.524)
			(layers "F.Cu" "F.Mask" "F.Paste")
			(net "GND")
		)
		(pad "4" smd rect
			(at 0.50038 2.0701 90)
			(size 0.3048 1.524)
			(layers "F.Cu" "F.Mask" "F.Paste")
			(net "UART_EXP_B_RX")
		)
		(pad "5" smd rect
			(at 0.99949 2.0701 90)
			(size 0.3048 1.524)
			(layers "F.Cu" "F.Mask" "F.Paste")
			(net "UART_SEL_B_MUX_R")
		)
		(pad "6" smd rect
			(at 0.99949 -2.0701 90)
			(size 0.3048 1.524)
			(layers "F.Cu" "F.Mask" "F.Paste")
			(net "UART_B_RX")
		)
		(pad "7" smd rect
			(at 0.50038 -2.0701 90)
			(size 0.3048 1.524)
			(layers "F.Cu" "F.Mask" "F.Paste")
			(net "UART_IOC_B_RX")
		)
		(pad "8" smd rect
			(at 0 -2.0701 90)
			(size 0.3048 1.524)
			(layers "F.Cu" "F.Mask" "F.Paste")
			(net "P3V3_STBY_B")
		)
		(pad "9" smd rect
			(at -0.50038 -2.0701 90)
			(size 0.3048 1.524)
			(layers "F.Cu" "F.Mask" "F.Paste")
			(net "UART_IOC_B_TX")
		)
		(pad "10" smd rect
			(at -0.99949 -2.0701 90)
			(size 0.3048 1.524)
			(layers "F.Cu" "F.Mask" "F.Paste")
			(net "UART_B_TX")
		)
	)
	(footprint ""
		(layer "F.Cu")
		(at 2.2987 -49.149)
		(property "Reference" "R31"
			(at 0 0 0)
			(layer "F.SilkS")
			(hide yes)
			(effects
				(font
					(size 1.27 1.27)
				)
			)
		)
		(property "Value" "0R2J-2-GP"
			(at 0.064008 -4.679696 0)
			(unlocked yes)
			(layer "F.Fab")
			(hide yes)
			(effects
				(font
					(size 2.54 2.54)
					(thickness 0.381)
				)
			)
		)
		(property "Device Type" "R402H16"
			(at 0.064008 -6.203696 0)
			(unlocked yes)
			(layer "F.Fab")
			(hide yes)
			(effects
				(font
					(size 2.54 2.54)
					(thickness 0.381)
				)
			)
		)
		(duplicate_pad_numbers_are_jumpers no)
		(fp_line
			(start -0.508 -0.9398)
			(end -0.508 0.9398)
			(stroke
				(width 0.1524)
				(type default)
			)
			(layer "F.SilkS")
		)
		(fp_line
			(start 0.508 -0.9398)
			(end -0.508 -0.9398)
			(stroke
				(width 0.1524)
				(type default)
			)
			(layer "F.SilkS")
		)
		(fp_rect
			(start -0.508 0.9398)
			(end 0.508 -0.9398)
			(stroke
				(width 0)
				(type default)
			)
			(fill no)
			(layer "F.CrtYd")
		)
		(fp_rect
			(start -0.508 0.9398)
			(end 0.508 -0.9398)
			(stroke
				(width 0)
				(type default)
			)
			(fill no)
			(layer "F.Fab")
		)
		(pad "1" smd custom
			(at 0 -0.4445)
			(size 0.1397 0.1397)
			(layers "F.Cu" "F.Mask" "F.Paste")
			(net "TEMP_1_SDA")
			(options
				(clearance outline)
				(anchor circle)
			)
			(primitives
				(gr_poly
					(pts
						(arc
							(start -0.1778 -0.2794)
							(mid -0.249642 -0.249642)
							(end -0.2794 -0.1778)
						)
						(arc
							(start -0.2794 0.1778)
							(mid -0.249642 0.249642)
							(end -0.1778 0.2794)
						)
						(arc
							(start 0.1778 0.2794)
							(mid 0.249642 0.249642)
							(end 0.2794 0.1778)
						)
						(arc
							(start 0.2794 -0.1778)
							(mid 0.249642 -0.249642)
							(end 0.1778 -0.2794)
						)
					)
					(width 0)
					(fill yes)
				)
			)
		)
		(pad "2" smd custom
			(at 0 0.4445)
			(size 0.1397 0.1397)
			(layers "F.Cu" "F.Mask" "F.Paste")
			(net "I2C_DPB_A_SDA")
			(options
				(clearance outline)
				(anchor circle)
			)
			(primitives
				(gr_poly
					(pts
						(arc
							(start -0.1778 -0.2794)
							(mid -0.249642 -0.249642)
							(end -0.2794 -0.1778)
						)
						(arc
							(start -0.2794 0.1778)
							(mid -0.249642 0.249642)
							(end -0.1778 0.2794)
						)
						(arc
							(start 0.1778 0.2794)
							(mid 0.249642 0.249642)
							(end 0.2794 0.1778)
						)
						(arc
							(start 0.2794 -0.1778)
							(mid 0.249642 -0.249642)
							(end 0.1778 -0.2794)
						)
					)
					(width 0)
					(fill yes)
				)
			)
		)
	)
	(gr_line
		(start 1.86563 -70.375526)
		(end 4.565904 -73.0758)
		(stroke
			(width 0.381)
			(type default)
		)
		(layer "In2.Cu")
	)
	(gr_line
		(start 1.86563 -62.011306)
		(end 1.86563 -70.375526)
		(stroke
			(width 0.381)
			(type default)
		)
		(layer "In2.Cu")
	)
	(gr_line
		(start 2.690114 -61.186822)
		(end 1.86563 -62.011306)
		(stroke
			(width 0.381)
			(type default)
		)
		(layer "In2.Cu")
	)
	(gr_line
		(start 3.865626 -68.145914)
		(end 3.865626 -65.402968)
		(stroke
			(width 0.381)
			(type default)
		)
		(layer "In2.Cu")
	)
	(gr_line
		(start 3.865626 -65.402968)
		(end 5.189982 -64.078612)
		(stroke
			(width 0.381)
			(type default)
		)
		(layer "In2.Cu")
	)
	(gr_line
		(start 4.565904 -73.0758)
		(end 16.297656 -73.0758)
		(stroke
			(width 0.381)
			(type default)
		)
		(layer "In2.Cu")
	)
	(gr_line
		(start 4.622292 -61.186822)
		(end 2.690114 -61.186822)
		(stroke
			(width 0.381)
			(type default)
		)
		(layer "In2.Cu")
	)
	(gr_line
		(start 4.879086 -69.159374)
		(end 3.865626 -68.145914)
		(stroke
			(width 0.381)
			(type default)
		)
		(layer "In2.Cu")
	)
	(gr_line
		(start 5.189982 -64.078612)
		(end 5.189982 -61.754512)
		(stroke
			(width 0.381)
			(type default)
		)
		(layer "In2.Cu")
	)
	(gr_line
		(start 5.189982 -61.754512)
		(end 4.622292 -61.186822)
		(stroke
			(width 0.381)
			(type default)
		)
		(layer "In2.Cu")
	)
	(gr_line
		(start 5.461 -31.242)
		(end 10.033 -35.814)
		(stroke
			(width 0.381)
			(type default)
		)
		(layer "In2.Cu")
	)
	(gr_line
		(start 5.461 -30.226)
		(end 5.461 -31.242)
		(stroke
			(width 0.381)
			(type default)
		)
		(layer "In2.Cu")
	)
	(gr_line
		(start 6.35 -29.337)
		(end 5.461 -30.226)
		(stroke
			(width 0.381)
			(type default)
		)
		(layer "In2.Cu")
	)
	(gr_line
		(start 6.35 -19.431)
		(end 6.35 -29.337)
		(stroke
			(width 0.381)
			(type default)
		)
		(layer "In2.Cu")
	)
	(gr_line
		(start 9.652 -16.129)
		(end 10.16 -15.621)
		(stroke
			(width 0.381)
			(type default)
		)
		(layer "In2.Cu")
	)
	(gr_line
		(start 10.033 -50.7746)
		(end 11.7348 -52.4764)
		(stroke
			(width 0.381)
			(type default)
		)
		(layer "In2.Cu")
	)
	(gr_line
		(start 10.033 -35.814)
		(end 10.033 -50.7746)
		(stroke
			(width 0.381)
			(type default)
		)
		(layer "In2.Cu")
	)
	(gr_line
		(start 10.16 -15.621)
		(end 6.35 -19.431)
		(stroke
			(width 0.381)
			(type default)
		)
		(layer "In2.Cu")
	)
	(gr_line
		(start 10.16 -15.621)
		(end 10.16 -13.843)
		(stroke
			(width 0.381)
			(type default)
		)
		(layer "In2.Cu")
	)
	(gr_line
		(start 10.16 -12.827)
		(end 10.16 -15.621)
		(stroke
			(width 0.381)
			(type default)
		)
		(layer "In2.Cu")
	)
	(gr_line
		(start 10.668 -12.319)
		(end 10.16 -12.827)
		(stroke
			(width 0.381)
			(type default)
		)
		(layer "In2.Cu")
	)
	(gr_line
		(start 11.537442 -12.319)
		(end 10.668 -12.319)
		(stroke
			(width 0.381)
			(type default)
		)
		(layer "In2.Cu")
	)
	(gr_line
		(start 11.649202 -69.159374)
		(end 4.879086 -69.159374)
		(stroke
			(width 0.381)
			(type default)
		)
		(layer "In2.Cu")
	)
	(gr_line
		(start 11.7348 -52.4764)
		(end 13.6144 -52.4764)
		(stroke
			(width 0.381)
			(type default)
		)
		(layer "In2.Cu")
	)
	(gr_circle
		(center 13.614146 -67.194176)
		(end 13.6144 -67.194176)
		(stroke
			(width 0.381)
			(type default)
		)
		(fill no)
		(layer "In2.Cu")
	)
	(gr_line
		(start 13.6144 -67.194176)
		(end 11.649202 -69.159374)
		(stroke
			(width 0.381)
			(type default)
		)
		(layer "In2.Cu")
	)
	(gr_line
		(start 13.6144 -30.0482)
		(end 13.6144 -67.194176)
		(stroke
			(width 0.381)
			(type default)
		)
		(layer "In2.Cu")
	)
	(gr_line
		(start 13.843 -10.040366)
		(end 11.537442 -12.319)
		(stroke
			(width 0.381)
			(type default)
		)
		(layer "In2.Cu")
	)
	(gr_line
		(start 13.843 -9.821418)
		(end 13.843 -9.017)
		(stroke
			(width 0.381)
			(type default)
		)
		(layer "In2.Cu")
	)
	(gr_line
		(start 13.843 -6.223)
		(end 13.843 -10.040366)
		(stroke
			(width 0.381)
			(type default)
		)
		(layer "In2.Cu")
	)
	(gr_line
		(start 14.478 -5.588)
		(end 13.843 -6.223)
		(stroke
			(width 0.381)
			(type default)
		)
		(layer "In2.Cu")
	)
	(gr_line
		(start 16.0782 -34.5186)
		(end 17.0688 -35.5092)
		(stroke
			(width 0.381)
			(type default)
		)
		(layer "In2.Cu")
	)
	(gr_line
		(start 16.0782 -32.004)
		(end 16.0782 -34.5186)
		(stroke
			(width 0.381)
			(type default)
		)
		(layer "In2.Cu")
	)
	(gr_line
		(start 18.923 -5.588)
		(end 14.478 -5.588)
		(stroke
			(width 0.381)
			(type default)
		)
		(layer "In2.Cu")
	)
	(gr_line
		(start 20.2438 -16.7894)
		(end 21.0058 -17.5514)
		(stroke
			(width 0.381)
			(type default)
		)
		(layer "In2.Cu")
	)
	(gr_line
		(start 20.2438 -15.0876)
		(end 20.2438 -16.7894)
		(stroke
			(width 0.381)
			(type default)
		)
		(layer "In2.Cu")
	)
	(gr_line
		(start 21.0058 -22.6568)
		(end 13.6144 -30.0482)
		(stroke
			(width 0.381)
			(type default)
		)
		(layer "In2.Cu")
	)
	(gr_line
		(start 21.0058 -17.5514)
		(end 21.0058 -22.6568)
		(stroke
			(width 0.381)
			(type default)
		)
		(layer "In2.Cu")
	)
	(gr_line
		(start 21.1074 -3.4036)
		(end 18.923 -5.588)
		(stroke
			(width 0.381)
			(type default)
		)
		(layer "In2.Cu")
	)
	(gr_line
		(start 23.8506 -24.2316)
		(end 16.0782 -32.004)
		(stroke
			(width 0.381)
			(type default)
		)
		(layer "In2.Cu")
	)
	(gr_line
		(start 23.8506 -17.1196)
		(end 23.8506 -24.2316)
		(stroke
			(width 0.381)
			(type default)
		)
		(layer "In2.Cu")
	)
	(gr_line
		(start 25.3238 -3.4036)
		(end 21.1074 -3.4036)
		(stroke
			(width 0.381)
			(type default)
		)
		(layer "In2.Cu")
	)
	(gr_line
		(start 25.7302 -9.6012)
		(end 20.2438 -15.0876)
		(stroke
			(width 0.381)
			(type default)
		)
		(layer "In2.Cu")
	)
	(gr_line
		(start 25.7302 -3.81)
		(end 25.3238 -3.4036)
		(stroke
			(width 0.381)
			(type default)
		)
		(layer "In2.Cu")
	)
	(gr_line
		(start 25.7302 -3.81)
		(end 25.7302 -9.6012)
		(stroke
			(width 0.381)
			(type default)
		)
		(layer "In2.Cu")
	)
	(gr_line
		(start 26.1366 -3.4036)
		(end 25.3238 -3.4036)
		(stroke
			(width 0.381)
			(type default)
		)
		(layer "In2.Cu")
	)
	(gr_line
		(start 26.1366 -3.4036)
		(end 25.7302 -3.81)
		(stroke
			(width 0.381)
			(type default)
		)
		(layer "In2.Cu")
	)
	(gr_line
		(start 27.7876 -3.4036)
		(end 26.1366 -3.4036)
		(stroke
			(width 0.381)
			(type default)
		)
		(layer "In2.Cu")
	)
	(gr_line
		(start 27.7876 -3.4036)
		(end 28.3464 -3.4036)
		(stroke
			(width 0.381)
			(type default)
		)
		(layer "In2.Cu")
	)
	(gr_line
		(start 28.3464 -12.6238)
		(end 23.8506 -17.1196)
		(stroke
			(width 0.381)
			(type default)
		)
		(layer "In2.Cu")
	)
	(gr_line
		(start 28.3464 -12.6238)
		(end 36.2458 -12.6238)
		(stroke
			(width 0.381)
			(type default)
		)
		(layer "In2.Cu")
	)
	(gr_line
		(start 28.3464 -3.9624)
		(end 27.7876 -3.4036)
		(stroke
			(width 0.381)
			(type default)
		)
		(layer "In2.Cu")
	)
	(gr_line
		(start 28.3464 -3.9624)
		(end 28.9052 -3.4036)
		(stroke
			(width 0.381)
			(type default)
		)
		(layer "In2.Cu")
	)
	(gr_line
		(start 28.3464 -3.4036)
		(end 28.3464 -12.6238)
		(stroke
			(width 0.381)
			(type default)
		)
		(layer "In2.Cu")
	)
	(gr_line
		(start 28.9052 -3.4036)
		(end 28.3464 -3.4036)
		(stroke
			(width 0.381)
			(type default)
		)
		(layer "In2.Cu")
	)
	(gr_line
		(start 28.9052 -3.4036)
		(end 30.2006 -3.4036)
		(stroke
			(width 0.381)
			(type default)
		)
		(layer "In2.Cu")
	)
	(gr_line
		(start 30.2006 -3.4036)
		(end 30.988 -4.191)
		(stroke
			(width 0.381)
			(type default)
		)
		(layer "In2.Cu")
	)
	(gr_line
		(start 30.988 -7.112)
		(end 32.639 -8.763)
		(stroke
			(width 0.381)
			(type default)
		)
		(layer "In2.Cu")
	)
	(gr_line
		(start 30.988 -4.191)
		(end 30.988 -7.112)
		(stroke
			(width 0.381)
			(type default)
		)
		(layer "In2.Cu")
	)
	(gr_line
		(start 31.238444 -4.695444)
		(end 30.991556 -4.448556)
		(stroke
			(width 0.381)
			(type default)
		)
		(layer "In2.Cu")
	)
	(gr_line
		(start 31.304992 -4.769104)
		(end 31.058104 -5.015992)
		(stroke
			(width 0.381)
			(type default)
		)
		(layer "In2.Cu")
	)
	(gr_line
		(start 32.512 -4.699)
		(end 30.988 -4.699)
		(stroke
			(width 0.381)
			(type default)
		)
		(layer "In2.Cu")
	)
	(gr_line
		(start 32.639 -8.763)
		(end 38.2524 -8.763)
		(stroke
			(width 0.381)
			(type default)
		)
		(layer "In2.Cu")
	)
	(gr_line
		(start 33.274 -3.937)
		(end 32.512 -4.699)
		(stroke
			(width 0.381)
			(type default)
		)
		(layer "In2.Cu")
	)
	(gr_line
		(start 34.29 -3.937)
		(end 33.274 -3.937)
		(stroke
			(width 0.381)
			(type default)
		)
		(layer "In2.Cu")
	)
	(gr_line
		(start 35.0012 -4.6482)
		(end 34.29 -3.937)
		(stroke
			(width 0.381)
			(type default)
		)
		(layer "In2.Cu")
	)
	(gr_line
		(start 36.2458 -12.6238)
		(end 43.18 -19.558)
		(stroke
			(width 0.381)
			(type default)
		)
		(layer "In2.Cu")
	)
	(gr_line
		(start 38.2524 -8.763)
		(end 47.625 -18.1356)
		(stroke
			(width 0.381)
			(type default)
		)
		(layer "In2.Cu")
	)
	(gr_line
		(start 43.18 -22.0726)
		(end 49.8094 -28.702)
		(stroke
			(width 0.381)
			(type default)
		)
		(layer "In2.Cu")
	)
	(gr_line
		(start 43.18 -19.558)
		(end 43.18 -22.0726)
		(stroke
			(width 0.381)
			(type default)
		)
		(layer "In2.Cu")
	)
	(gr_line
		(start 47.625 -20.955)
		(end 53.975 -27.305)
		(stroke
			(width 0.381)
			(type default)
		)
		(layer "In2.Cu")
	)
	(gr_line
		(start 47.625 -18.1356)
		(end 47.625 -20.955)
		(stroke
			(width 0.381)
			(type default)
		)
		(layer "In2.Cu")
	)
	(gr_line
		(start 47.80915 -71.659242)
		(end 48.782224 -72.632316)
		(stroke
			(width 0.381)
			(type default)
		)
		(layer "In2.Cu")
	)
	(gr_line
		(start 47.80915 -70.456806)
		(end 47.80915 -71.659242)
		(stroke
			(width 0.381)
			(type default)
		)
		(layer "In2.Cu")
	)
	(gr_line
		(start 48.241712 -70.024244)
		(end 47.80915 -70.456806)
		(stroke
			(width 0.381)
			(type default)
		)
		(layer "In2.Cu")
	)
	(gr_line
		(start 48.782224 -72.632316)
		(end 53.836316 -72.632316)
		(stroke
			(width 0.381)
			(type default)
		)
		(layer "In2.Cu")
	)
	(gr_line
		(start 49.8094 -42.799)
		(end 50.3682 -43.3578)
		(stroke
			(width 0.381)
			(type default)
		)
		(layer "In2.Cu")
	)
	(gr_line
		(start 49.8094 -28.702)
		(end 49.8094 -42.799)
		(stroke
			(width 0.381)
			(type default)
		)
		(layer "In2.Cu")
	)
	(gr_line
		(start 50.3682 -45.339)
		(end 56.134 -51.1048)
		(stroke
			(width 0.381)
			(type default)
		)
		(layer "In2.Cu")
	)
	(gr_line
		(start 50.3682 -43.3578)
		(end 50.3682 -45.339)
		(stroke
			(width 0.381)
			(type default)
		)
		(layer "In2.Cu")
	)
	(gr_line
		(start 52.160424 -70.024244)
		(end 48.241712 -70.024244)
		(stroke
			(width 0.381)
			(type default)
		)
		(layer "In2.Cu")
	)
	(gr_line
		(start 52.832 -35.052)
		(end 52.832254 -35.051746)
		(stroke
			(width 0.381)
			(type default)
		)
		(layer "In2.Cu")
	)
	(gr_line
		(start 52.832254 -40.386254)
		(end 53.975 -41.529)
		(stroke
			(width 0.381)
			(type default)
		)
		(layer "In2.Cu")
	)
	(gr_line
		(start 52.832254 -35.051746)
		(end 52.832254 -40.386254)
		(stroke
			(width 0.381)
			(type default)
		)
		(layer "In2.Cu")
	)
	(gr_line
		(start 53.5432 -4.6482)
		(end 35.0012 -4.6482)
		(stroke
			(width 0.381)
			(type default)
		)
		(layer "In2.Cu")
	)
	(gr_circle
		(center 53.836316 -72.63257)
		(end 53.83657 -72.63257)
		(stroke
			(width 0.381)
			(type default)
		)
		(fill no)
		(layer "In2.Cu")
	)
	(gr_line
		(start 53.836316 -72.632316)
		(end 54.7624 -73.5584)
		(stroke
			(width 0.381)
			(type default)
		)
		(layer "In2.Cu")
	)
	(gr_line
		(start 53.975 -45.0088)
		(end 56.1594 -47.1932)
		(stroke
			(width 0.381)
			(type default)
		)
		(layer "In2.Cu")
	)
	(gr_line
		(start 53.975 -41.529)
		(end 53.975 -45.0088)
		(stroke
			(width 0.381)
			(type default)
		)
		(layer "In2.Cu")
	)
	(gr_line
		(start 53.975 -33.909)
		(end 52.832254 -35.051746)
		(stroke
			(width 0.381)
			(type default)
		)
		(layer "In2.Cu")
	)
	(gr_line
		(start 53.975 -27.305)
		(end 53.975 -33.909)
		(stroke
			(width 0.381)
			(type default)
		)
		(layer "In2.Cu")
	)
	(gr_circle
		(center 54.177946 -68.006468)
		(end 54.1782 -68.006468)
		(stroke
			(width 0.381)
			(type default)
		)
		(fill no)
		(layer "In2.Cu")
	)
	(gr_line
		(start 54.1782 -68.006468)
		(end 52.160424 -70.024244)
		(stroke
			(width 0.381)
			(type default)
		)
		(layer "In2.Cu")
	)
	(gr_line
		(start 54.1782 -61.696092)
		(end 54.1782 -68.006468)
		(stroke
			(width 0.381)
			(type default)
		)
		(layer "In2.Cu")
	)
	(gr_circle
		(center 54.178454 -61.696092)
		(end 54.178708 -61.696092)
		(stroke
			(width 0.381)
			(type default)
		)
		(fill no)
		(layer "In2.Cu")
	)
	(gr_line
		(start 54.7624 -73.5584)
		(end 59.6138 -73.5584)
		(stroke
			(width 0.381)
			(type default)
		)
		(layer "In2.Cu")
	)
	(gr_line
		(start 55.245 -37.973)
		(end 55.245254 -37.972746)
		(stroke
			(width 0.381)
			(type default)
		)
		(layer "In2.Cu")
	)
	(gr_line
		(start 55.245254 -39.116254)
		(end 55.245254 -37.972746)
		(stroke
			(width 0.381)
			(type default)
		)
		(layer "In2.Cu")
	)
	(gr_line
		(start 55.245254 -37.972746)
		(end 57.1754 -36.0426)
		(stroke
			(width 0.381)
			(type default)
		)
		(layer "In2.Cu")
	)
	(gr_line
		(start 56.134 -59.740292)
		(end 54.1782 -61.696092)
		(stroke
			(width 0.381)
			(type default)
		)
		(layer "In2.Cu")
	)
	(gr_line
		(start 56.134 -51.1048)
		(end 56.134 -59.740292)
		(stroke
			(width 0.381)
			(type default)
		)
		(layer "In2.Cu")
	)
	(gr_line
		(start 56.1594 -47.1932)
		(end 56.769 -47.1932)
		(stroke
			(width 0.381)
			(type default)
		)
		(layer "In2.Cu")
	)
	(gr_line
		(start 56.769 -47.1932)
		(end 56.9214 -47.1932)
		(stroke
			(width 0.381)
			(type default)
		)
		(layer "In2.Cu")
	)
	(gr_line
		(start 56.769 -47.1932)
		(end 57.1754 -46.7868)
		(stroke
			(width 0.381)
			(type default)
		)
		(layer "In2.Cu")
	)
	(gr_line
		(start 56.9214 -47.1932)
		(end 59.1312 -49.403)
		(stroke
			(width 0.381)
			(type default)
		)
		(layer "In2.Cu")
	)
	(gr_line
		(start 57.1754 -46.7868)
		(end 57.1754 -41.0464)
		(stroke
			(width 0.381)
			(type default)
		)
		(layer "In2.Cu")
	)
	(gr_line
		(start 57.1754 -41.0464)
		(end 55.245254 -39.116254)
		(stroke
			(width 0.381)
			(type default)
		)
		(layer "In2.Cu")
	)
	(gr_line
		(start 57.1754 -36.0426)
		(end 57.1754 -8.2804)
		(stroke
			(width 0.381)
			(type default)
		)
		(layer "In2.Cu")
	)
	(gr_line
		(start 57.1754 -8.2804)
		(end 53.5432 -4.6482)
		(stroke
			(width 0.381)
			(type default)
		)
		(layer "In2.Cu")
	)
	(gr_line
		(start 59.1312 -54.3306)
		(end 59.9186 -55.118)
		(stroke
			(width 0.381)
			(type default)
		)
		(layer "In2.Cu")
	)
	(gr_line
		(start 59.1312 -49.403)
		(end 59.1312 -54.3306)
		(stroke
			(width 0.381)
			(type default)
		)
		(layer "In2.Cu")
	)
	(gr_line
		(start -2.999994 -52.279296)
		(end -2.999994 -47.720758)
		(stroke
			(width 0.05)
			(type default)
		)
		(layer "Edge.Cuts")
	)
	(gr_arc
		(start -2.999994 -52.279296)
		(mid -2.811243 -52.864012)
		(end -2.316226 -53.227986)
		(stroke
			(width 0.05)
			(type default)
		)
		(layer "Edge.Cuts")
	)
	(gr_arc
		(start -2.316226 -46.772068)
		(mid -2.811236 -47.136048)
		(end -2.999994 -47.720758)
		(stroke
			(width 0.05)
			(type default)
		)
		(layer "Edge.Cuts")
	)
	(gr_line
		(start -2.316226 -46.772068)
		(end -0.683768 -46.228)
		(stroke
			(width 0.05)
			(type default)
		)
		(layer "Edge.Cuts")
	)
	(gr_line
		(start -0.683768 -53.772054)
		(end -2.316226 -53.227986)
		(stroke
			(width 0.05)
			(type default)
		)
		(layer "Edge.Cuts")
	)
	(gr_arc
		(start -0.683768 -46.228)
		(mid -0.18875 -45.864024)
		(end 0 -45.27931)
		(stroke
			(width 0.05)
			(type default)
		)
		(layer "Edge.Cuts")
	)
	(gr_line
		(start 0 -89.000076)
		(end 0 -54.720744)
		(stroke
			(width 0.05)
			(type default)
		)
		(layer "Edge.Cuts")
	)
	(gr_arc
		(start 0 -89.000076)
		(mid 0.292895 -89.707178)
		(end 0.999998 -90.000074)
		(stroke
			(width 0.05)
			(type default)
		)
		(layer "Edge.Cuts")
	)
	(gr_arc
		(start 0 -54.720744)
		(mid -0.188757 -54.136035)
		(end -0.683768 -53.772054)
		(stroke
			(width 0.05)
			(type default)
		)
		(layer "Edge.Cuts")
	)
	(gr_line
		(start 0 -45.27931)
		(end 0 5.700014)
		(stroke
			(width 0.05)
			(type default)
		)
		(layer "Edge.Cuts")
	)
	(gr_arc
		(start 0.999998 6.700012)
		(mid 0.292893 6.407119)
		(end 0 5.700014)
		(stroke
			(width 0.05)
			(type default)
		)
		(layer "Edge.Cuts")
	)
	(gr_line
		(start 0.999998 6.700012)
		(end 7.38505 6.700012)
		(stroke
			(width 0.05)
			(type default)
		)
		(layer "Edge.Cuts")
	)
	(gr_arc
		(start 7.884922 0.199898)
		(mid 8.031495 -0.15358)
		(end 8.385048 -0.299974)
		(stroke
			(width 0.05)
			(type default)
		)
		(layer "Edge.Cuts")
	)
	(gr_arc
		(start 7.884922 6.199886)
		(mid 7.738603 6.553513)
		(end 7.38505 6.700012)
		(stroke
			(width 0.05)
			(type default)
		)
		(layer "Edge.Cuts")
	)
	(gr_line
		(start 7.884922 6.199886)
		(end 7.884922 0.199898)
		(stroke
			(width 0.05)
			(type default)
		)
		(layer "Edge.Cuts")
	)
	(gr_line
		(start 8.385048 -0.299974)
		(end 50.71491 -0.299974)
		(stroke
			(width 0.05)
			(type default)
		)
		(layer "Edge.Cuts")
	)
	(gr_arc
		(start 9.92505 -1.299972)
		(mid 10.600182 -1.975104)
		(end 11.27506 -1.299972)
		(stroke
			(width 0.05)
			(type default)
		)
		(layer "Edge.Cuts")
	)
	(gr_arc
		(start 11.27506 -1.299972)
		(mid 10.600182 -0.625094)
		(end 9.92505 -1.299972)
		(stroke
			(width 0.05)
			(type default)
		)
		(layer "Edge.Cuts")
	)
	(gr_line
		(start 15.40002 -90.000074)
		(end 0.999998 -90.000074)
		(stroke
			(width 0.05)
			(type default)
		)
		(layer "Edge.Cuts")
	)
	(gr_arc
		(start 15.40002 -90.000074)
		(mid 16.107127 -89.707182)
		(end 16.400018 -89.000076)
		(stroke
			(width 0.05)
			(type default)
		)
		(layer "Edge.Cuts")
	)
	(gr_line
		(start 16.400018 -72.720708)
		(end 16.400018 -89.000076)
		(stroke
			(width 0.05)
			(type default)
		)
		(layer "Edge.Cuts")
	)
	(gr_arc
		(start 16.400018 -63.279274)
		(mid 16.588775 -63.863983)
		(end 17.083786 -64.227964)
		(stroke
			(width 0.05)
			(type default)
		)
		(layer "Edge.Cuts")
	)
	(gr_line
		(start 16.400018 -34.914332)
		(end 16.400018 -63.279274)
		(stroke
			(width 0.05)
			(type default)
		)
		(layer "Edge.Cuts")
	)
	(gr_arc
		(start 16.69288 -34.207196)
		(mid 16.476098 -34.531633)
		(end 16.400018 -34.914332)
		(stroke
			(width 0.05)
			(type default)
		)
		(layer "Edge.Cuts")
	)
	(gr_arc
		(start 17.083786 -71.772018)
		(mid 16.588768 -72.135994)
		(end 16.400018 -72.720708)
		(stroke
			(width 0.05)
			(type default)
		)
		(layer "Edge.Cuts")
	)
	(gr_line
		(start 17.083786 -64.227964)
		(end 18.716244 -64.772032)
		(stroke
			(width 0.05)
			(type default)
		)
		(layer "Edge.Cuts")
	)
	(gr_line
		(start 18.716244 -71.22795)
		(end 17.083786 -71.772018)
		(stroke
			(width 0.05)
			(type default)
		)
		(layer "Edge.Cuts")
	)
	(gr_arc
		(start 18.716244 -71.22795)
		(mid 19.211255 -70.863971)
		(end 19.400012 -70.27926)
		(stroke
			(width 0.05)
			(type default)
		)
		(layer "Edge.Cuts")
	)
	(gr_arc
		(start 19.400012 -65.720722)
		(mid 19.211264 -65.136)
		(end 18.716244 -64.772032)
		(stroke
			(width 0.05)
			(type default)
		)
		(layer "Edge.Cuts")
	)
	(gr_line
		(start 19.400012 -65.720722)
		(end 19.400012 -70.27926)
		(stroke
			(width 0.05)
			(type default)
		)
		(layer "Edge.Cuts")
	)
	(gr_line
		(start 24.10714 -26.792936)
		(end 16.69288 -34.207196)
		(stroke
			(width 0.05)
			(type default)
		)
		(layer "Edge.Cuts")
	)
	(gr_arc
		(start 24.814276 -26.500074)
		(mid 24.431593 -26.576194)
		(end 24.10714 -26.792936)
		(stroke
			(width 0.05)
			(type default)
		)
		(layer "Edge.Cuts")
	)
	(gr_arc
		(start 26.75001 -19.99996)
		(mid 29.550106 -22.800056)
		(end 32.349948 -19.99996)
		(stroke
			(width 0.05)
			(type default)
		)
		(layer "Edge.Cuts")
	)
	(gr_arc
		(start 32.349948 -19.99996)
		(mid 29.550106 -17.200118)
		(end 26.75001 -19.99996)
		(stroke
			(width 0.05)
			(type default)
		)
		(layer "Edge.Cuts")
	)
	(gr_line
		(start 34.285682 -26.500074)
		(end 24.814276 -26.500074)
		(stroke
			(width 0.05)
			(type default)
		)
		(layer "Edge.Cuts")
	)
	(gr_arc
		(start 34.992818 -26.792936)
		(mid 34.668381 -26.576154)
		(end 34.285682 -26.500074)
		(stroke
			(width 0.05)
			(type default)
		)
		(layer "Edge.Cuts")
	)
	(gr_line
		(start 39.699946 -70.27926)
		(end 39.699946 -65.720722)
		(stroke
			(width 0.05)
			(type default)
		)
		(layer "Edge.Cuts")
	)
	(gr_arc
		(start 39.699946 -70.27926)
		(mid 39.888692 -70.863979)
		(end 40.383714 -71.22795)
		(stroke
			(width 0.05)
			(type default)
		)
		(layer "Edge.Cuts")
	)
	(gr_arc
		(start 40.383714 -64.772032)
		(mid 39.888731 -65.136021)
		(end 39.699946 -65.720722)
		(stroke
			(width 0.05)
			(type default)
		)
		(layer "Edge.Cuts")
	)
	(gr_line
		(start 40.383714 -64.772032)
		(end 42.016172 -64.227964)
		(stroke
			(width 0.05)
			(type default)
		)
		(layer "Edge.Cuts")
	)
	(gr_line
		(start 42.016172 -71.772018)
		(end 40.383714 -71.22795)
		(stroke
			(width 0.05)
			(type default)
		)
		(layer "Edge.Cuts")
	)
	(gr_arc
		(start 42.016172 -64.227964)
		(mid 42.51119 -63.863988)
		(end 42.69994 -63.279274)
		(stroke
			(width 0.05)
			(type default)
		)
		(layer "Edge.Cuts")
	)
	(gr_line
		(start 42.407078 -34.207196)
		(end 34.992818 -26.792936)
		(stroke
			(width 0.05)
			(type default)
		)
		(layer "Edge.Cuts")
	)
	(gr_line
		(start 42.69994 -89.000076)
		(end 42.69994 -72.720708)
		(stroke
			(width 0.05)
			(type default)
		)
		(layer "Edge.Cuts")
	)
	(gr_arc
		(start 42.69994 -89.000076)
		(mid 42.992826 -89.707183)
		(end 43.699938 -90.000074)
		(stroke
			(width 0.05)
			(type default)
		)
		(layer "Edge.Cuts")
	)
	(gr_arc
		(start 42.69994 -72.720708)
		(mid 42.511183 -72.135999)
		(end 42.016172 -71.772018)
		(stroke
			(width 0.05)
			(type default)
		)
		(layer "Edge.Cuts")
	)
	(gr_line
		(start 42.69994 -63.279274)
		(end 42.69994 -34.914332)
		(stroke
			(width 0.05)
			(type default)
		)
		(layer "Edge.Cuts")
	)
	(gr_arc
		(start 42.69994 -34.914332)
		(mid 42.62382 -34.531649)
		(end 42.407078 -34.207196)
		(stroke
			(width 0.05)
			(type default)
		)
		(layer "Edge.Cuts")
	)
	(gr_arc
		(start 47.824898 -1.299972)
		(mid 48.50003 -1.975104)
		(end 49.174908 -1.299972)
		(stroke
			(width 0.05)
			(type default)
		)
		(layer "Edge.Cuts")
	)
	(gr_arc
		(start 49.174908 -1.299972)
		(mid 48.50003 -0.625094)
		(end 47.824898 -1.299972)
		(stroke
			(width 0.05)
			(type default)
		)
		(layer "Edge.Cuts")
	)
	(gr_arc
		(start 50.71491 -0.299974)
		(mid 51.068463 -0.15358)
		(end 51.215036 0.199898)
		(stroke
			(width 0.05)
			(type default)
		)
		(layer "Edge.Cuts")
	)
	(gr_line
		(start 51.215036 0.199898)
		(end 51.215036 6.199886)
		(stroke
			(width 0.05)
			(type default)
		)
		(layer "Edge.Cuts")
	)
	(gr_arc
		(start 51.714908 6.700012)
		(mid 51.361336 6.553518)
		(end 51.215036 6.199886)
		(stroke
			(width 0.05)
			(type default)
		)
		(layer "Edge.Cuts")
	)
	(gr_line
		(start 51.714908 6.700012)
		(end 58.09996 6.700012)
		(stroke
			(width 0.05)
			(type default)
		)
		(layer "Edge.Cuts")
	)
	(gr_line
		(start 58.09996 -90.000074)
		(end 43.699938 -90.000074)
		(stroke
			(width 0.05)
			(type default)
		)
		(layer "Edge.Cuts")
	)
	(gr_arc
		(start 58.09996 -90.000074)
		(mid 58.807083 -89.707194)
		(end 59.099958 -89.000076)
		(stroke
			(width 0.05)
			(type default)
		)
		(layer "Edge.Cuts")
	)
	(gr_line
		(start 59.099958 -54.618128)
		(end 59.099958 -89.000076)
		(stroke
			(width 0.05)
			(type default)
		)
		(layer "Edge.Cuts")
	)
	(gr_arc
		(start 59.099958 -45.381926)
		(mid 59.249367 -45.907753)
		(end 59.652916 -46.276514)
		(stroke
			(width 0.05)
			(type default)
		)
		(layer "Edge.Cuts")
	)
	(gr_arc
		(start 59.099958 5.700014)
		(mid 58.807058 6.407096)
		(end 58.09996 6.700012)
		(stroke
			(width 0.05)
			(type default)
		)
		(layer "Edge.Cuts")
	)
	(gr_line
		(start 59.099958 5.700014)
		(end 59.099958 -45.381926)
		(stroke
			(width 0.05)
			(type default)
		)
		(layer "Edge.Cuts")
	)
	(gr_arc
		(start 59.652916 -53.72354)
		(mid 59.249309 -54.092265)
		(end 59.099958 -54.618128)
		(stroke
			(width 0.05)
			(type default)
		)
		(layer "Edge.Cuts")
	)
	(gr_line
		(start 59.652916 -46.276514)
		(end 60.54725 -46.723554)
		(stroke
			(width 0.05)
			(type default)
		)
		(layer "Edge.Cuts")
	)
	(gr_line
		(start 60.54725 -53.2765)
		(end 59.652916 -53.72354)
		(stroke
			(width 0.05)
			(type default)
		)
		(layer "Edge.Cuts")
	)
	(gr_arc
		(start 60.54725 -53.2765)
		(mid 60.950706 -52.907734)
		(end 61.099954 -52.381912)
		(stroke
			(width 0.05)
			(type default)
		)
		(layer "Edge.Cuts")
	)
	(gr_arc
		(start 61.099954 -47.618142)
		(mid 60.950673 -47.092335)
		(end 60.54725 -46.723554)
		(stroke
			(width 0.05)
			(type default)
		)
		(layer "Edge.Cuts")
	)
	(gr_line
		(start 61.099954 -47.618142)
		(end 61.099954 -52.381912)
		(stroke
			(width 0.05)
			(type default)
		)
		(layer "Edge.Cuts")
	)
	(segment
		(start 54.6862 -13.5001)
		(end 54.8513 -13.5001)
		(width 0.17145)
		(layer "F.Cu")
		(net "UART_SEL_B_MUX_R")
	)
	(segment
		(start 54.3687 -13.5001)
		(end 54.6862 -13.5001)
		(width 0.17145)
		(layer "F.Cu")
		(net "UART_SEL_B_MUX_R")
	)
	(segment
		(start 52.58181 -10.7442)
		(end 52.6161 -10.77849)
		(width 0.17145)
		(layer "F.Cu")
		(net "UART_SEL_B_MUX_R")
	)
	(segment
		(start 51.3842 -9.033256)
		(end 51.3842 -10.390886)
		(width 0.17145)
		(layer "F.Cu")
		(net "UART_SEL_B_MUX_R")
	)
	(segment
		(start 53.92166 -11.42746)
		(end 54.364382 -11.42746)
		(width 0.17145)
		(layer "F.Cu")
		(net "UART_SEL_B_MUX_R")
	)
	(segment
		(start 51.637946 -8.77951)
		(end 51.3842 -9.033256)
		(width 0.17145)
		(layer "F.Cu")
		(net "UART_SEL_B_MUX_R")
	)
	(segment
		(start 53.27269 -10.77849)
		(end 53.92166 -11.42746)
		(width 0.17145)
		(layer "F.Cu")
		(net "UART_SEL_B_MUX_R")
	)
	(segment
		(start 54.45506 -11.42746)
		(end 54.364382 -11.42746)
		(width 0.17145)
		(layer "F.Cu")
		(net "UART_SEL_B_MUX_R")
	)
	(segment
		(start 52.6161 -10.77849)
		(end 53.27269 -10.77849)
		(width 0.17145)
		(layer "F.Cu")
		(net "UART_SEL_B_MUX_R")
	)
	(segment
		(start 55.176928 -13.174472)
		(end 55.176928 -12.481306)
		(width 0.17145)
		(layer "F.Cu")
		(net "UART_SEL_B_MUX_R")
	)
	(segment
		(start 51.737514 -10.7442)
		(end 52.58181 -10.7442)
		(width 0.17145)
		(layer "F.Cu")
		(net "UART_SEL_B_MUX_R")
	)
	(segment
		(start 53.218588 -13.274548)
		(end 54.143148 -13.274548)
		(width 0.17145)
		(layer "F.Cu")
		(net "UART_SEL_B_MUX_R")
	)
	(segment
		(start 51.3842 -10.390886)
		(end 51.737514 -10.7442)
		(width 0.17145)
		(layer "F.Cu")
		(net "UART_SEL_B_MUX_R")
	)
	(segment
		(start 52.6161 -8.77951)
		(end 51.637946 -8.77951)
		(width 0.17145)
		(layer "F.Cu")
		(net "UART_SEL_B_MUX_R")
	)
	(segment
		(start 55.176928 -12.481306)
		(end 55.176928 -12.149328)
		(width 0.17145)
		(layer "F.Cu")
		(net "UART_SEL_B_MUX_R")
	)
	(segment
		(start 55.176928 -12.149328)
		(end 54.45506 -11.42746)
		(width 0.17145)
		(layer "F.Cu")
		(net "UART_SEL_B_MUX_R")
	)
	(segment
		(start 54.8513 -13.5001)
		(end 55.176928 -13.174472)
		(width 0.17145)
		(layer "F.Cu")
		(net "UART_SEL_B_MUX_R")
	)
	(segment
		(start 54.143148 -13.274548)
		(end 54.3687 -13.5001)
		(width 0.17145)
		(layer "F.Cu")
		(net "UART_SEL_B_MUX_R")
	)
	(via
		(at 54.364382 -11.42746)
		(size 0.6604)
		(drill 0.3302)
		(layers "F.Cu" "B.Cu")
		(net "UART_SEL_B_MUX_R")
	)
	(segment
		(start 53.0606 -14.986)
		(end 53.0606 -14.7828)
		(width 0.17145)
		(layer "F.Cu")
		(net "UART_SEL_B_MUX")
	)
	(segment
		(start 31.9278 -6.731)
		(end 31.9278 -6.985)
		(width 0.17145)
		(layer "F.Cu")
		(net "UART_SEL_B_MUX")
	)
	(segment
		(start 54.5465 -14.2494)
		(end 53.6702 -14.2494)
		(width 0.17145)
		(layer "F.Cu")
		(net "UART_SEL_B_MUX")
	)
	(segment
		(start 30.95244 -7.96036)
		(end 30.95244 -8.735314)
		(width 0.17145)
		(layer "F.Cu")
		(net "UART_SEL_B_MUX")
	)
	(segment
		(start 53.0606 -14.7828)
		(end 53.594 -14.2494)
		(width 0.17145)
		(layer "F.Cu")
		(net "UART_SEL_B_MUX")
	)
	(segment
		(start 53.594 -14.2494)
		(end 53.6702 -14.2494)
		(width 0.17145)
		(layer "F.Cu")
		(net "UART_SEL_B_MUX")
	)
	(segment
		(start 54.6862 -14.3891)
		(end 54.5465 -14.2494)
		(width 0.17145)
		(layer "F.Cu")
		(net "UART_SEL_B_MUX")
	)
	(segment
		(start 31.9278 -6.985)
		(end 30.95244 -7.96036)
		(width 0.17145)
		(layer "F.Cu")
		(net "UART_SEL_B_MUX")
	)
	(via
		(at 31.9278 -6.731)
		(size 0.508)
		(drill 0.254)
		(layers "F.Cu" "B.Cu")
		(net "UART_SEL_B_MUX")
	)
	(via
		(at 53.0606 -14.986)
		(size 0.508)
		(drill 0.254)
		(layers "F.Cu" "B.Cu")
		(net "UART_SEL_B_MUX")
	)
	(via
		(at 53.6702 -14.2494)
		(size 0.6604)
		(drill 0.3302)
		(layers "F.Cu" "B.Cu")
		(net "UART_SEL_B_MUX")
	)
	(segment
		(start 44.8056 -6.731)
		(end 53.0606 -14.986)
		(width 0.17145)
		(layer "B.Cu")
		(net "UART_SEL_B_MUX")
	)
	(segment
		(start 31.9278 -6.731)
		(end 44.8056 -6.731)
		(width 0.17145)
		(layer "B.Cu")
		(net "UART_SEL_B_MUX")
	)
	(segment
		(start 19.2151 -11.938)
		(end 18.7452 -12.4079)
		(width 0.17145)
		(layer "F.Cu")
		(net "UART_SEL_A_MUX_R")
	)
	(segment
		(start 15.65402 -11.57351)
		(end 16.3703 -11.57351)
		(width 0.17145)
		(layer "F.Cu")
		(net "UART_SEL_A_MUX_R")
	)
	(segment
		(start 19.431 -12.9921)
		(end 19.431 -12.464288)
		(width 0.17145)
		(layer "F.Cu")
		(net "UART_SEL_A_MUX_R")
	)
	(segment
		(start 15.113 -12.11453)
		(end 15.65402 -11.57351)
		(width 0.17145)
		(layer "F.Cu")
		(net "UART_SEL_A_MUX_R")
	)
	(segment
		(start 15.50289 -13.57249)
		(end 15.113 -13.1826)
		(width 0.17145)
		(layer "F.Cu")
		(net "UART_SEL_A_MUX_R")
	)
	(segment
		(start 16.3703 -13.57249)
		(end 15.50289 -13.57249)
		(width 0.17145)
		(layer "F.Cu")
		(net "UART_SEL_A_MUX_R")
	)
	(segment
		(start 18.7452 -12.4079)
		(end 18.7452 -12.9286)
		(width 0.17145)
		(layer "F.Cu")
		(net "UART_SEL_A_MUX_R")
	)
	(segment
		(start 19.256248 -12.289536)
		(end 19.256248 -11.979148)
		(width 0.17145)
		(layer "F.Cu")
		(net "UART_SEL_A_MUX_R")
	)
	(segment
		(start 18.161 -13.5128)
		(end 18.10131 -13.57249)
		(width 0.17145)
		(layer "F.Cu")
		(net "UART_SEL_A_MUX_R")
	)
	(segment
		(start 20.4724 -12.9921)
		(end 19.431 -12.9921)
		(width 0.17145)
		(layer "F.Cu")
		(net "UART_SEL_A_MUX_R")
	)
	(segment
		(start 18.10131 -13.57249)
		(end 16.3703 -13.57249)
		(width 0.17145)
		(layer "F.Cu")
		(net "UART_SEL_A_MUX_R")
	)
	(segment
		(start 18.7452 -12.9286)
		(end 18.161 -13.5128)
		(width 0.17145)
		(layer "F.Cu")
		(net "UART_SEL_A_MUX_R")
	)
	(segment
		(start 19.431 -12.464288)
		(end 19.256248 -12.289536)
		(width 0.17145)
		(layer "F.Cu")
		(net "UART_SEL_A_MUX_R")
	)
	(segment
		(start 15.113 -13.1826)
		(end 15.113 -12.11453)
		(width 0.17145)
		(layer "F.Cu")
		(net "UART_SEL_A_MUX_R")
	)
	(segment
		(start 19.256248 -11.979148)
		(end 19.2151 -11.938)
		(width 0.17145)
		(layer "F.Cu")
		(net "UART_SEL_A_MUX_R")
	)
	(via
		(at 18.161 -13.5128)
		(size 0.6604)
		(drill 0.3302)
		(layers "F.Cu" "B.Cu")
		(net "UART_SEL_A_MUX_R")
	)
	(segment
		(start 25.6794 -14.0462)
		(end 28.7782 -14.0462)
		(width 0.17145)
		(layer "F.Cu")
		(net "UART_SEL_A_MUX")
	)
	(segment
		(start 29.2862 -12.8778)
		(end 28.437332 -12.028932)
		(width 0.17145)
		(layer "F.Cu")
		(net "UART_SEL_A_MUX")
	)
	(segment
		(start 28.7782 -14.0462)
		(end 29.2862 -13.5382)
		(width 0.17145)
		(layer "F.Cu")
		(net "UART_SEL_A_MUX")
	)
	(segment
		(start 19.9644 -14.3891)
		(end 19.9644 -14.859)
		(width 0.17145)
		(layer "F.Cu")
		(net "UART_SEL_A_MUX")
	)
	(segment
		(start 25.4254 -14.3002)
		(end 25.6794 -14.0462)
		(width 0.17145)
		(layer "F.Cu")
		(net "UART_SEL_A_MUX")
	)
	(segment
		(start 20.5486 -15.4432)
		(end 19.9644 -14.859)
		(width 0.17145)
		(layer "F.Cu")
		(net "UART_SEL_A_MUX")
	)
	(segment
		(start 20.4724 -13.8811)
		(end 19.9644 -14.3891)
		(width 0.17145)
		(layer "F.Cu")
		(net "UART_SEL_A_MUX")
	)
	(segment
		(start 20.8788 -15.4432)
		(end 20.5486 -15.4432)
		(width 0.17145)
		(layer "F.Cu")
		(net "UART_SEL_A_MUX")
	)
	(segment
		(start 29.2862 -13.5382)
		(end 29.2862 -12.8778)
		(width 0.17145)
		(layer "F.Cu")
		(net "UART_SEL_A_MUX")
	)
	(segment
		(start 28.437332 -12.028932)
		(end 28.437332 -11.40079)
		(width 0.17145)
		(layer "F.Cu")
		(net "UART_SEL_A_MUX")
	)
	(via
		(at 20.8788 -15.4432)
		(size 0.508)
		(drill 0.254)
		(layers "F.Cu" "B.Cu")
		(net "UART_SEL_A_MUX")
	)
	(via
		(at 25.4254 -14.3002)
		(size 0.508)
		(drill 0.254)
		(layers "F.Cu" "B.Cu")
		(net "UART_SEL_A_MUX")
	)
	(via
		(at 19.9644 -14.859)
		(size 0.6604)
		(drill 0.3302)
		(layers "F.Cu" "B.Cu")
		(net "UART_SEL_A_MUX")
	)
	(segment
		(start 20.8788 -15.4432)
		(end 24.2824 -15.4432)
		(width 0.17145)
		(layer "B.Cu")
		(net "UART_SEL_A_MUX")
	)
	(segment
		(start 24.2824 -15.4432)
		(end 25.4254 -14.3002)
		(width 0.17145)
		(layer "B.Cu")
		(net "UART_SEL_A_MUX")
	)
	(segment
		(start 33.0073 -6.096)
		(end 33.0073 -6.8707)
		(width 0.17145)
		(layer "F.Cu")
		(net "D_FLIP_PRE_B#")
	)
	(segment
		(start 33.0073 -6.8707)
		(end 32.8168 -7.0612)
		(width 0.17145)
		(layer "F.Cu")
		(net "D_FLIP_PRE_B#")
	)
	(segment
		(start 31.9532 -7.9248)
		(end 32.8168 -7.0612)
		(width 0.17145)
		(layer "F.Cu")
		(net "D_FLIP_PRE_B#")
	)
	(segment
		(start 31.9532 -8.735314)
		(end 31.9532 -7.9248)
		(width 0.17145)
		(layer "F.Cu")
		(net "D_FLIP_PRE_B#")
	)
	(via
		(at 32.8168 -7.0612)
		(size 0.6604)
		(drill 0.3302)
		(layers "F.Cu" "B.Cu")
		(net "D_FLIP_PRE_B#")
	)
	(segment
		(start 25.710388 -9.271254)
		(end 25.705054 -9.271254)
		(width 0.17145)
		(layer "F.Cu")
		(net "D_FLIP_PRE_A#")
	)
	(segment
		(start 26.561288 -10.0584)
		(end 25.980136 -9.477248)
		(width 0.17145)
		(layer "F.Cu")
		(net "D_FLIP_PRE_A#")
	)
	(segment
		(start 27.051 -10.0584)
		(end 26.561288 -10.0584)
		(width 0.17145)
		(layer "F.Cu")
		(net "D_FLIP_PRE_A#")
	)
	(segment
		(start 25.666954 -8.264398)
		(end 25.666954 -9.233154)
		(width 0.17145)
		(layer "F.Cu")
		(net "D_FLIP_PRE_A#")
	)
	(segment
		(start 27.436572 -10.443972)
		(end 27.051 -10.0584)
		(width 0.17145)
		(layer "F.Cu")
		(net "D_FLIP_PRE_A#")
	)
	(segment
		(start 25.666954 -9.233154)
		(end 25.7048 -9.271)
		(width 0.17145)
		(layer "F.Cu")
		(net "D_FLIP_PRE_A#")
	)
	(segment
		(start 25.916382 -9.477248)
		(end 25.710388 -9.271254)
		(width 0.17145)
		(layer "F.Cu")
		(net "D_FLIP_PRE_A#")
	)
	(segment
		(start 25.980136 -9.477248)
		(end 25.916382 -9.477248)
		(width 0.17145)
		(layer "F.Cu")
		(net "D_FLIP_PRE_A#")
	)
	(segment
		(start 25.705054 -9.271254)
		(end 25.7048 -9.271)
		(width 0.17145)
		(layer "F.Cu")
		(net "D_FLIP_PRE_A#")
	)
	(segment
		(start 27.436572 -11.40079)
		(end 27.436572 -10.443972)
		(width 0.17145)
		(layer "F.Cu")
		(net "D_FLIP_PRE_A#")
	)
	(via
		(at 25.7048 -9.271)
		(size 0.6604)
		(drill 0.3302)
		(layers "F.Cu" "B.Cu")
		(net "D_FLIP_PRE_A#")
	)
	(segment
		(start 29.6037 -8.5852)
		(end 29.6799 -8.6614)
		(width 0.17145)
		(layer "F.Cu")
		(net "D_FLIP_CLR_B#")
	)
	(segment
		(start 31.45282 -9.54659)
		(end 31.19501 -9.8044)
		(width 0.17145)
		(layer "F.Cu")
		(net "D_FLIP_CLR_B#")
	)
	(segment
		(start 29.6799 -9.3091)
		(end 29.6799 -8.6614)
		(width 0.17145)
		(layer "F.Cu")
		(net "D_FLIP_CLR_B#")
	)
	(segment
		(start 29.6037 -5.969)
		(end 29.6037 -6.9596)
		(width 0.17145)
		(layer "F.Cu")
		(net "D_FLIP_CLR_B#")
	)
	(segment
		(start 30.1752 -9.8044)
		(end 29.6799 -9.3091)
		(width 0.17145)
		(layer "F.Cu")
		(net "D_FLIP_CLR_B#")
	)
	(segment
		(start 29.6037 -6.9596)
		(end 29.6037 -8.5852)
		(width 0.17145)
		(layer "F.Cu")
		(net "D_FLIP_CLR_B#")
	)
	(segment
		(start 31.19501 -9.8044)
		(end 30.1752 -9.8044)
		(width 0.17145)
		(layer "F.Cu")
		(net "D_FLIP_CLR_B#")
	)
	(segment
		(start 31.45282 -8.735314)
		(end 31.45282 -9.54659)
		(width 0.17145)
		(layer "F.Cu")
		(net "D_FLIP_CLR_B#")
	)
	(via
		(at 29.6799 -8.6614)
		(size 0.6604)
		(drill 0.3302)
		(layers "F.Cu" "B.Cu")
		(net "D_FLIP_CLR_B#")
	)
	(segment
		(start 26.9367 -13.1572)
		(end 25.8572 -13.1572)
		(width 0.17145)
		(layer "F.Cu")
		(net "D_FLIP_CLR_A#")
	)
	(segment
		(start 24.910034 -13.12545)
		(end 24.941784 -13.1572)
		(width 0.17145)
		(layer "F.Cu")
		(net "D_FLIP_CLR_A#")
	)
	(segment
		(start 27.936952 -12.220448)
		(end 27.6352 -12.5222)
		(width 0.17145)
		(layer "F.Cu")
		(net "D_FLIP_CLR_A#")
	)
	(segment
		(start 27.0002 -12.827)
		(end 27.0002 -13.0937)
		(width 0.17145)
		(layer "F.Cu")
		(net "D_FLIP_CLR_A#")
	)
	(segment
		(start 27.0002 -13.0937)
		(end 26.9367 -13.1572)
		(width 0.17145)
		(layer "F.Cu")
		(net "D_FLIP_CLR_A#")
	)
	(segment
		(start 27.936952 -11.40079)
		(end 27.936952 -12.220448)
		(width 0.17145)
		(layer "F.Cu")
		(net "D_FLIP_CLR_A#")
	)
	(segment
		(start 27.6352 -12.5222)
		(end 27.305 -12.5222)
		(width 0.17145)
		(layer "F.Cu")
		(net "D_FLIP_CLR_A#")
	)
	(segment
		(start 24.941784 -13.1572)
		(end 25.8572 -13.1572)
		(width 0.17145)
		(layer "F.Cu")
		(net "D_FLIP_CLR_A#")
	)
	(segment
		(start 27.305 -12.5222)
		(end 27.0002 -12.827)
		(width 0.17145)
		(layer "F.Cu")
		(net "D_FLIP_CLR_A#")
	)
	(via
		(at 25.8572 -13.1572)
		(size 0.6604)
		(drill 0.3302)
		(layers "F.Cu" "B.Cu")
		(net "D_FLIP_CLR_A#")
	)
	(segment
		(start 31.0515 -13.716)
		(end 31.0515 -12.9159)
		(width 0.17145)
		(layer "F.Cu")
		(net "D_FLIP_B_Q#")
	)
	(segment
		(start 31.45282 -11.072114)
		(end 31.45282 -11.87958)
		(width 0.17145)
		(layer "F.Cu")
		(net "D_FLIP_B_Q#")
	)
	(segment
		(start 31.45282 -11.87958)
		(end 30.9118 -12.4206)
		(width 0.17145)
		(layer "F.Cu")
		(net "D_FLIP_B_Q#")
	)
	(segment
		(start 31.0515 -12.9159)
		(end 30.9118 -12.7762)
		(width 0.17145)
		(layer "F.Cu")
		(net "D_FLIP_B_Q#")
	)
	(segment
		(start 30.9118 -12.4206)
		(end 30.9118 -12.7762)
		(width 0.17145)
		(layer "F.Cu")
		(net "D_FLIP_B_Q#")
	)
	(via
		(at 30.9118 -12.7762)
		(size 0.6604)
		(drill 0.3302)
		(layers "F.Cu" "B.Cu")
		(net "D_FLIP_B_Q#")
	)
	(segment
		(start 31.9532 -12.7)
		(end 32.0294 -12.7762)
		(width 0.17145)
		(layer "F.Cu")
		(net "D_FLIP_B_D")
	)
	(segment
		(start 31.9532 -11.072114)
		(end 31.9532 -12.7)
		(width 0.17145)
		(layer "F.Cu")
		(net "D_FLIP_B_D")
	)
	(segment
		(start 32.0294 -13.6271)
		(end 31.9405 -13.716)
		(width 0.17145)
		(layer "F.Cu")
		(net "D_FLIP_B_D")
	)
	(segment
		(start 32.0294 -12.7762)
		(end 32.0294 -13.6271)
		(width 0.17145)
		(layer "F.Cu")
		(net "D_FLIP_B_D")
	)
	(via
		(at 32.0294 -12.7762)
		(size 0.6604)
		(drill 0.3302)
		(layers "F.Cu" "B.Cu")
		(net "D_FLIP_B_D")
	)
	(segment
		(start 28.6004 -7.6708)
		(end 28.6004 -7.2898)
		(width 0.17145)
		(layer "F.Cu")
		(net "D_FLIP_A_Q#")
	)
	(segment
		(start 28.6004 -6.5659)
		(end 28.6004 -7.2898)
		(width 0.17145)
		(layer "F.Cu")
		(net "D_FLIP_A_Q#")
	)
	(segment
		(start 27.936952 -9.06399)
		(end 27.936952 -8.334248)
		(width 0.17145)
		(layer "F.Cu")
		(net "D_FLIP_A_Q#")
	)
	(segment
		(start 27.936952 -8.334248)
		(end 28.6004 -7.6708)
		(width 0.17145)
		(layer "F.Cu")
		(net "D_FLIP_A_Q#")
	)
	(segment
		(start 28.3591 -6.3246)
		(end 28.6004 -6.5659)
		(width 0.17145)
		(layer "F.Cu")
		(net "D_FLIP_A_Q#")
	)
	(via
		(at 28.6004 -7.2898)
		(size 0.6604)
		(drill 0.3302)
		(layers "F.Cu" "B.Cu")
		(net "D_FLIP_A_Q#")
	)
	(segment
		(start 27.436572 -9.06399)
		(end 27.436572 -7.8994)
		(width 0.17145)
		(layer "F.Cu")
		(net "D_FLIP_A_D")
	)
	(segment
		(start 27.5082 -7.827772)
		(end 27.5082 -7.2898)
		(width 0.17145)
		(layer "F.Cu")
		(net "D_FLIP_A_D")
	)
	(segment
		(start 27.4701 -6.3246)
		(end 27.4701 -7.2517)
		(width 0.17145)
		(layer "F.Cu")
		(net "D_FLIP_A_D")
	)
	(segment
		(start 27.4701 -7.2517)
		(end 27.5082 -7.2898)
		(width 0.17145)
		(layer "F.Cu")
		(net "D_FLIP_A_D")
	)
	(segment
		(start 27.436572 -7.8994)
		(end 27.5082 -7.827772)
		(width 0.17145)
		(layer "F.Cu")
		(net "D_FLIP_A_D")
	)
	(via
		(at 27.5082 -7.2898)
		(size 0.6604)
		(drill 0.3302)
		(layers "F.Cu" "B.Cu")
		(net "D_FLIP_A_D")
	)
	(segment
		(start 57.521348 -8.64362)
		(end 57.517792 -8.640064)
		(width 0.17145)
		(layer "F.Cu")
		(net "TCA9555_B_A2")
	)
	(segment
		(start 56.412892 -7.45617)
		(end 56.738012 -7.78129)
		(width 0.17145)
		(layer "F.Cu")
		(net "TCA9555_B_A2")
	)
	(segment
		(start 54.706012 -7.45617)
		(end 55.722012 -7.45617)
		(width 0.17145)
		(layer "F.Cu")
		(net "TCA9555_B_A2")
	)
	(segment
		(start 57.517792 -8.640064)
		(end 57.517792 -8.56107)
		(width 0.17145)
		(layer "F.Cu")
		(net "TCA9555_B_A2")
	)
	(segment
		(start 57.7342 -11.176)
		(end 57.521348 -10.963148)
		(width 0.17145)
		(layer "F.Cu")
		(net "TCA9555_B_A2")
	)
	(segment
		(start 57.08904 -16.90116)
		(end 57.7342 -16.256)
		(width 0.17145)
		(layer "F.Cu")
		(net "TCA9555_B_A2")
	)
	(segment
		(start 57.7342 -16.256)
		(end 57.7342 -11.176)
		(width 0.17145)
		(layer "F.Cu")
		(net "TCA9555_B_A2")
	)
	(segment
		(start 57.521348 -10.963148)
		(end 57.521348 -8.64362)
		(width 0.17145)
		(layer "F.Cu")
		(net "TCA9555_B_A2")
	)
	(segment
		(start 56.0324 -16.90116)
		(end 57.08904 -16.90116)
		(width 0.17145)
		(layer "F.Cu")
		(net "TCA9555_B_A2")
	)
	(segment
		(start 55.722012 -7.45617)
		(end 56.412892 -7.45617)
		(width 0.17145)
		(layer "F.Cu")
		(net "TCA9555_B_A2")
	)
	(segment
		(start 57.517792 -8.56107)
		(end 56.738012 -7.78129)
		(width 0.17145)
		(layer "F.Cu")
		(net "TCA9555_B_A2")
	)
	(via
		(at 56.738012 -7.78129)
		(size 0.6604)
		(drill 0.3302)
		(layers "F.Cu" "B.Cu")
		(net "TCA9555_B_A2")
	)
	(segment
		(start 56.62295 -16.25092)
		(end 56.0324 -16.25092)
		(width 0.17145)
		(layer "F.Cu")
		(net "TCA9555_B_A1")
	)
	(segment
		(start 56.841898 -11.270488)
		(end 57.034938 -11.463528)
		(width 0.17145)
		(layer "F.Cu")
		(net "TCA9555_B_A1")
	)
	(segment
		(start 55.4482 -9.9695)
		(end 55.303928 -10.113772)
		(width 0.17145)
		(layer "F.Cu")
		(net "TCA9555_B_A1")
	)
	(segment
		(start 56.841898 -11.058398)
		(end 56.841898 -11.270488)
		(width 0.17145)
		(layer "F.Cu")
		(net "TCA9555_B_A1")
	)
	(segment
		(start 55.303928 -10.8966)
		(end 55.329328 -10.922)
		(width 0.17145)
		(layer "F.Cu")
		(net "TCA9555_B_A1")
	)
	(segment
		(start 55.329328 -10.922)
		(end 55.88 -10.922)
		(width 0.17145)
		(layer "F.Cu")
		(net "TCA9555_B_A1")
	)
	(segment
		(start 57.034938 -11.463528)
		(end 57.034938 -15.838932)
		(width 0.17145)
		(layer "F.Cu")
		(net "TCA9555_B_A1")
	)
	(segment
		(start 56.0705 -10.7315)
		(end 56.515 -10.7315)
		(width 0.17145)
		(layer "F.Cu")
		(net "TCA9555_B_A1")
	)
	(segment
		(start 56.515 -10.7315)
		(end 56.841898 -11.058398)
		(width 0.17145)
		(layer "F.Cu")
		(net "TCA9555_B_A1")
	)
	(segment
		(start 55.303928 -10.113772)
		(end 55.303928 -10.8966)
		(width 0.17145)
		(layer "F.Cu")
		(net "TCA9555_B_A1")
	)
	(segment
		(start 55.88 -10.922)
		(end 56.0705 -10.7315)
		(width 0.17145)
		(layer "F.Cu")
		(net "TCA9555_B_A1")
	)
	(segment
		(start 57.034938 -15.838932)
		(end 56.62295 -16.25092)
		(width 0.17145)
		(layer "F.Cu")
		(net "TCA9555_B_A1")
	)
	(via
		(at 55.303928 -10.8966)
		(size 0.6604)
		(drill 0.3302)
		(layers "F.Cu" "B.Cu")
		(net "TCA9555_B_A1")
	)
	(segment
		(start 49.168304 -16.9545)
		(end 48.895 -16.9545)
		(width 0.17145)
		(layer "F.Cu")
		(net "TCA9555_B_A0")
	)
	(segment
		(start 48.895 -16.9545)
		(end 48.860964 -16.920464)
		(width 0.17145)
		(layer "F.Cu")
		(net "TCA9555_B_A0")
	)
	(segment
		(start 47.8155 -14.997684)
		(end 48.474884 -14.997684)
		(width 0.17145)
		(layer "F.Cu")
		(net "TCA9555_B_A0")
	)
	(segment
		(start 49.765204 -17.5514)
		(end 49.168304 -16.9545)
		(width 0.17145)
		(layer "F.Cu")
		(net "TCA9555_B_A0")
	)
	(segment
		(start 48.860964 -16.920464)
		(end 48.860964 -15.728188)
		(width 0.17145)
		(layer "F.Cu")
		(net "TCA9555_B_A0")
	)
	(segment
		(start 48.860964 -15.383764)
		(end 48.860964 -15.728188)
		(width 0.17145)
		(layer "F.Cu")
		(net "TCA9555_B_A0")
	)
	(segment
		(start 50.3936 -17.5514)
		(end 49.765204 -17.5514)
		(width 0.17145)
		(layer "F.Cu")
		(net "TCA9555_B_A0")
	)
	(segment
		(start 48.474884 -14.997684)
		(end 48.860964 -15.383764)
		(width 0.17145)
		(layer "F.Cu")
		(net "TCA9555_B_A0")
	)
	(via
		(at 48.860964 -15.728188)
		(size 0.6604)
		(drill 0.3302)
		(layers "F.Cu" "B.Cu")
		(net "TCA9555_B_A0")
	)
	(segment
		(start 18.29816 -17.91716)
		(end 19.203416 -18.822416)
		(width 0.17145)
		(layer "F.Cu")
		(net "TCA9555_A_A2")
	)
	(segment
		(start 17.653 -17.91716)
		(end 18.29816 -17.91716)
		(width 0.17145)
		(layer "F.Cu")
		(net "TCA9555_A_A2")
	)
	(segment
		(start 19.203416 -18.822416)
		(end 19.203416 -19.4056)
		(width 0.17145)
		(layer "F.Cu")
		(net "TCA9555_A_A2")
	)
	(segment
		(start 19.203416 -20.401026)
		(end 19.203416 -19.4056)
		(width 0.17145)
		(layer "F.Cu")
		(net "TCA9555_A_A2")
	)
	(segment
		(start 20.219416 -20.401026)
		(end 19.203416 -20.401026)
		(width 0.17145)
		(layer "F.Cu")
		(net "TCA9555_A_A2")
	)
	(via
		(at 19.203416 -19.4056)
		(size 0.6604)
		(drill 0.3302)
		(layers "F.Cu" "B.Cu")
		(net "TCA9555_A_A2")
	)
	(segment
		(start 19.207734 -17.3482)
		(end 19.0754 -17.3482)
		(width 0.17145)
		(layer "F.Cu")
		(net "TCA9555_A_A1")
	)
	(segment
		(start 17.653 -17.26692)
		(end 18.5928 -17.26692)
		(width 0.17145)
		(layer "F.Cu")
		(net "TCA9555_A_A1")
	)
	(segment
		(start 18.67408 -17.3482)
		(end 19.0754 -17.3482)
		(width 0.17145)
		(layer "F.Cu")
		(net "TCA9555_A_A1")
	)
	(segment
		(start 20.1168 -16.7767)
		(end 19.779234 -16.7767)
		(width 0.17145)
		(layer "F.Cu")
		(net "TCA9555_A_A1")
	)
	(segment
		(start 19.779234 -16.7767)
		(end 19.207734 -17.3482)
		(width 0.17145)
		(layer "F.Cu")
		(net "TCA9555_A_A1")
	)
	(segment
		(start 20.1168 -17.7927)
		(end 20.1168 -16.7767)
		(width 0.17145)
		(layer "F.Cu")
		(net "TCA9555_A_A1")
	)
	(segment
		(start 18.5928 -17.26692)
		(end 18.67408 -17.3482)
		(width 0.17145)
		(layer "F.Cu")
		(net "TCA9555_A_A1")
	)
	(via
		(at 19.0754 -17.3482)
		(size 0.6604)
		(drill 0.3302)
		(layers "F.Cu" "B.Cu")
		(net "TCA9555_A_A1")
	)
	(segment
		(start 9.393174 -16.942816)
		(end 10.218674 -16.942816)
		(width 0.17145)
		(layer "F.Cu")
		(net "TCA9555_A_A0")
	)
	(segment
		(start 10.358374 -17.984216)
		(end 10.358374 -17.082516)
		(width 0.17145)
		(layer "F.Cu")
		(net "TCA9555_A_A0")
	)
	(segment
		(start 10.218674 -16.942816)
		(end 10.320274 -17.044416)
		(width 0.17145)
		(layer "F.Cu")
		(net "TCA9555_A_A0")
	)
	(segment
		(start 12.0142 -18.5674)
		(end 10.941558 -18.5674)
		(width 0.17145)
		(layer "F.Cu")
		(net "TCA9555_A_A0")
	)
	(segment
		(start 10.941558 -18.5674)
		(end 10.358374 -17.984216)
		(width 0.17145)
		(layer "F.Cu")
		(net "TCA9555_A_A0")
	)
	(segment
		(start 10.358374 -17.082516)
		(end 10.320274 -17.044416)
		(width 0.17145)
		(layer "F.Cu")
		(net "TCA9555_A_A0")
	)
	(via
		(at 10.320274 -17.044416)
		(size 0.6604)
		(drill 0.3302)
		(layers "F.Cu" "B.Cu")
		(net "TCA9555_A_A0")
	)
	(segment
		(start 51.054 -27.44724)
		(end 50.76444 -27.7368)
		(width 0.17145)
		(layer "F.Cu")
		(net "SYS_RESET_BTN_B_N_R")
	)
	(segment
		(start 50.245518 -30.06725)
		(end 50.759868 -30.5816)
		(width 0.17145)
		(layer "F.Cu")
		(net "SYS_RESET_BTN_B_N_R")
	)
	(segment
		(start 49.43475 -30.06725)
		(end 50.245518 -30.06725)
		(width 0.17145)
		(layer "F.Cu")
		(net "SYS_RESET_BTN_B_N_R")
	)
	(segment
		(start 51.5747 -27.44724)
		(end 51.054 -27.44724)
		(width 0.17145)
		(layer "F.Cu")
		(net "SYS_RESET_BTN_B_N_R")
	)
	(segment
		(start 50.76444 -27.7368)
		(end 46.740064 -27.7368)
		(width 0.17145)
		(layer "F.Cu")
		(net "SYS_RESET_BTN_B_N_R")
	)
	(segment
		(start 46.740064 -27.7368)
		(end 46.524164 -27.5209)
		(width 0.17145)
		(layer "F.Cu")
		(net "SYS_RESET_BTN_B_N_R")
	)
	(segment
		(start 45.9232 -29.9974)
		(end 46.7868 -30.861)
		(width 0.17145)
		(layer "F.Cu")
		(net "SYS_RESET_BTN_B_N_R")
	)
	(segment
		(start 45.9232 -27.5209)
		(end 45.9232 -29.0322)
		(width 0.17145)
		(layer "F.Cu")
		(net "SYS_RESET_BTN_B_N_R")
	)
	(segment
		(start 46.524164 -27.5209)
		(end 45.9232 -27.5209)
		(width 0.17145)
		(layer "F.Cu")
		(net "SYS_RESET_BTN_B_N_R")
	)
	(segment
		(start 48.992028 -30.820106)
		(end 48.992028 -30.509972)
		(width 0.17145)
		(layer "F.Cu")
		(net "SYS_RESET_BTN_B_N_R")
	)
	(segment
		(start 50.759868 -30.5816)
		(end 52.452016 -30.5816)
		(width 0.17145)
		(layer "F.Cu")
		(net "SYS_RESET_BTN_B_N_R")
	)
	(segment
		(start 48.951134 -30.861)
		(end 48.992028 -30.820106)
		(width 0.17145)
		(layer "F.Cu")
		(net "SYS_RESET_BTN_B_N_R")
	)
	(segment
		(start 46.7868 -30.861)
		(end 48.951134 -30.861)
		(width 0.17145)
		(layer "F.Cu")
		(net "SYS_RESET_BTN_B_N_R")
	)
	(segment
		(start 45.9232 -29.0322)
		(end 45.9232 -29.9974)
		(width 0.17145)
		(layer "F.Cu")
		(net "SYS_RESET_BTN_B_N_R")
	)
	(segment
		(start 48.992028 -30.509972)
		(end 49.43475 -30.06725)
		(width 0.17145)
		(layer "F.Cu")
		(net "SYS_RESET_BTN_B_N_R")
	)
	(segment
		(start 52.452016 -30.5816)
		(end 52.713636 -30.31998)
		(width 0.17145)
		(layer "F.Cu")
		(net "SYS_RESET_BTN_B_N_R")
	)
	(via
		(at 45.9232 -29.0322)
		(size 0.6604)
		(drill 0.3302)
		(layers "F.Cu" "B.Cu")
		(net "SYS_RESET_BTN_B_N_R")
	)
	(segment
		(start 9.344914 -30.68955)
		(end 8.640064 -29.9847)
		(width 0.17145)
		(layer "F.Cu")
		(net "SYS_RESET_BTN_A_N_R")
	)
	(segment
		(start 8.640064 -29.9847)
		(end 8.5598 -29.9847)
		(width 0.17145)
		(layer "F.Cu")
		(net "SYS_RESET_BTN_A_N_R")
	)
	(segment
		(start 12.45616 -28.71724)
		(end 11.6586 -29.5148)
		(width 0.17145)
		(layer "F.Cu")
		(net "SYS_RESET_BTN_A_N_R")
	)
	(segment
		(start 11.181842 -30.68955)
		(end 9.344914 -30.68955)
		(width 0.17145)
		(layer "F.Cu")
		(net "SYS_RESET_BTN_A_N_R")
	)
	(segment
		(start 7.1628 -29.9339)
		(end 7.1628 -29.2608)
		(width 0.17145)
		(layer "F.Cu")
		(net "SYS_RESET_BTN_A_N_R")
	)
	(segment
		(start 7.2136 -29.9847)
		(end 7.1628 -29.9339)
		(width 0.17145)
		(layer "F.Cu")
		(net "SYS_RESET_BTN_A_N_R")
	)
	(segment
		(start 7.1628 -29.2608)
		(end 7.380732 -29.042868)
		(width 0.17145)
		(layer "F.Cu")
		(net "SYS_RESET_BTN_A_N_R")
	)
	(segment
		(start 13.1445 -28.71724)
		(end 12.45616 -28.71724)
		(width 0.17145)
		(layer "F.Cu")
		(net "SYS_RESET_BTN_A_N_R")
	)
	(segment
		(start 7.380732 -29.042868)
		(end 7.380732 -28.504388)
		(width 0.17145)
		(layer "F.Cu")
		(net "SYS_RESET_BTN_A_N_R")
	)
	(segment
		(start 11.6586 -29.5148)
		(end 11.6586 -30.1498)
		(width 0.17145)
		(layer "F.Cu")
		(net "SYS_RESET_BTN_A_N_R")
	)
	(segment
		(start 11.6586 -30.1498)
		(end 11.6586 -30.212792)
		(width 0.17145)
		(layer "F.Cu")
		(net "SYS_RESET_BTN_A_N_R")
	)
	(segment
		(start 8.5598 -29.9847)
		(end 7.2136 -29.9847)
		(width 0.17145)
		(layer "F.Cu")
		(net "SYS_RESET_BTN_A_N_R")
	)
	(segment
		(start 11.6586 -30.212792)
		(end 11.181842 -30.68955)
		(width 0.17145)
		(layer "F.Cu")
		(net "SYS_RESET_BTN_A_N_R")
	)
	(via
		(at 11.6586 -30.1498)
		(size 0.6604)
		(drill 0.3302)
		(layers "F.Cu" "B.Cu")
		(net "SYS_RESET_BTN_A_N_R")
	)
	(segment
		(start 55.753 -14.3891)
		(end 55.753 -14.859)
		(width 0.17145)
		(layer "F.Cu")
		(net "IO_EXP_B_RESET#_FLT")
	)
	(segment
		(start 55.753 -14.859)
		(end 56.0324 -15.1384)
		(width 0.17145)
		(layer "F.Cu")
		(net "IO_EXP_B_RESET#_FLT")
	)
	(segment
		(start 56.0324 -15.1384)
		(end 56.0324 -15.60068)
		(width 0.17145)
		(layer "F.Cu")
		(net "IO_EXP_B_RESET#_FLT")
	)
	(segment
		(start 16.637 -16.3576)
		(end 16.637 -15.4686)
		(width 0.17145)
		(layer "F.Cu")
		(net "IO_EXP_A_RESET#_FLT")
	)
	(segment
		(start 16.637 -15.4686)
		(end 16.8148 -15.2908)
		(width 0.17145)
		(layer "F.Cu")
		(net "IO_EXP_A_RESET#_FLT")
	)
	(segment
		(start 16.8656 -15.24)
		(end 16.8148 -15.2908)
		(width 0.17145)
		(layer "F.Cu")
		(net "IO_EXP_A_RESET#_FLT")
	)
	(segment
		(start 16.89608 -16.61668)
		(end 16.637 -16.3576)
		(width 0.17145)
		(layer "F.Cu")
		(net "IO_EXP_A_RESET#_FLT")
	)
	(segment
		(start 17.6657 -15.24)
		(end 16.8656 -15.24)
		(width 0.17145)
		(layer "F.Cu")
		(net "IO_EXP_A_RESET#_FLT")
	)
	(segment
		(start 17.653 -16.61668)
		(end 16.89608 -16.61668)
		(width 0.17145)
		(layer "F.Cu")
		(net "IO_EXP_A_RESET#_FLT")
	)
	(segment
		(start 17.7927 -15.367)
		(end 17.6657 -15.24)
		(width 0.17145)
		(layer "F.Cu")
		(net "IO_EXP_A_RESET#_FLT")
	)
	(via
		(at 16.8148 -15.2908)
		(size 0.6604)
		(drill 0.3302)
		(layers "F.Cu" "B.Cu")
		(net "IO_EXP_A_RESET#_FLT")
	)
	(segment
		(start 50.3936 -22.75332)
		(end 48.93818 -22.75332)
		(width 0.17145)
		(layer "F.Cu")
		(net "DEBUG_RST_B_BTN_N")
	)
	(segment
		(start 47.421546 -27.000454)
		(end 49.674526 -27.000454)
		(width 0.17145)
		(layer "F.Cu")
		(net "DEBUG_RST_B_BTN_N")
	)
	(segment
		(start 43.694604 -23.7744)
		(end 45.38472 -23.7744)
		(width 0.17145)
		(layer "F.Cu")
		(net "DEBUG_RST_B_BTN_N")
	)
	(segment
		(start 48.8315 -23.0378)
		(end 48.26635 -23.60295)
		(width 0.17145)
		(layer "F.Cu")
		(net "DEBUG_RST_B_BTN_N")
	)
	(segment
		(start 47.276512 -23.3934)
		(end 46.4312 -23.3934)
		(width 0.17145)
		(layer "F.Cu")
		(net "DEBUG_RST_B_BTN_N")
	)
	(segment
		(start 47.486062 -23.60295)
		(end 47.276512 -23.3934)
		(width 0.17145)
		(layer "F.Cu")
		(net "DEBUG_RST_B_BTN_N")
	)
	(segment
		(start 47.421292 -27.0002)
		(end 47.421546 -27.000454)
		(width 0.17145)
		(layer "F.Cu")
		(net "DEBUG_RST_B_BTN_N")
	)
	(segment
		(start 51.0286 -26.797)
		(end 51.5747 -26.797)
		(width 0.17145)
		(layer "F.Cu")
		(net "DEBUG_RST_B_BTN_N")
	)
	(segment
		(start 48.93818 -22.75332)
		(end 48.8315 -22.86)
		(width 0.17145)
		(layer "F.Cu")
		(net "DEBUG_RST_B_BTN_N")
	)
	(segment
		(start 46.9646 -27.0002)
		(end 47.421292 -27.0002)
		(width 0.17145)
		(layer "F.Cu")
		(net "DEBUG_RST_B_BTN_N")
	)
	(segment
		(start 45.38472 -23.7744)
		(end 45.76572 -23.3934)
		(width 0.17145)
		(layer "F.Cu")
		(net "DEBUG_RST_B_BTN_N")
	)
	(segment
		(start 45.76572 -23.3934)
		(end 46.4312 -23.3934)
		(width 0.17145)
		(layer "F.Cu")
		(net "DEBUG_RST_B_BTN_N")
	)
	(segment
		(start 49.67478 -27.0002)
		(end 50.8254 -27.0002)
		(width 0.17145)
		(layer "F.Cu")
		(net "DEBUG_RST_B_BTN_N")
	)
	(segment
		(start 50.8254 -27.0002)
		(end 51.0286 -26.797)
		(width 0.17145)
		(layer "F.Cu")
		(net "DEBUG_RST_B_BTN_N")
	)
	(segment
		(start 48.26635 -23.60295)
		(end 47.486062 -23.60295)
		(width 0.17145)
		(layer "F.Cu")
		(net "DEBUG_RST_B_BTN_N")
	)
	(segment
		(start 43.500802 -23.580598)
		(end 43.694604 -23.7744)
		(width 0.17145)
		(layer "F.Cu")
		(net "DEBUG_RST_B_BTN_N")
	)
	(segment
		(start 49.674526 -27.000454)
		(end 49.67478 -27.0002)
		(width 0.17145)
		(layer "F.Cu")
		(net "DEBUG_RST_B_BTN_N")
	)
	(segment
		(start 48.8315 -22.86)
		(end 48.8315 -23.0378)
		(width 0.17145)
		(layer "F.Cu")
		(net "DEBUG_RST_B_BTN_N")
	)
	(via
		(at 46.9646 -27.0002)
		(size 0.508)
		(drill 0.254)
		(layers "F.Cu" "B.Cu")
		(net "DEBUG_RST_B_BTN_N")
	)
	(via
		(at 46.4312 -23.3934)
		(size 0.6604)
		(drill 0.3302)
		(layers "F.Cu" "B.Cu")
		(net "DEBUG_RST_B_BTN_N")
	)
	(via
		(at 43.500802 -23.580598)
		(size 0.508)
		(drill 0.254)
		(layers "F.Cu" "B.Cu")
		(net "DEBUG_RST_B_BTN_N")
	)
	(segment
		(start 46.920404 -27.0002)
		(end 43.500802 -23.580598)
		(width 0.17145)
		(layer "B.Cu")
		(net "DEBUG_RST_B_BTN_N")
	)
	(segment
		(start 46.9646 -27.0002)
		(end 46.920404 -27.0002)
		(width 0.17145)
		(layer "B.Cu")
		(net "DEBUG_RST_B_BTN_N")
	)
	(segment
		(start 10.3886 -22.7965)
		(end 10.3886 -22.4536)
		(width 0.17145)
		(layer "F.Cu")
		(net "DEBUG_RST_A_BTN_N")
	)
	(segment
		(start 11.7348 -28.2448)
		(end 11.9126 -28.067)
		(width 0.17145)
		(layer "F.Cu")
		(net "DEBUG_RST_A_BTN_N")
	)
	(segment
		(start 11.9126 -28.067)
		(end 13.1445 -28.067)
		(width 0.17145)
		(layer "F.Cu")
		(net "DEBUG_RST_A_BTN_N")
	)
	(segment
		(start 9.9695 -23.2156)
		(end 10.3886 -22.7965)
		(width 0.17145)
		(layer "F.Cu")
		(net "DEBUG_RST_A_BTN_N")
	)
	(segment
		(start 12.0142 -23.76932)
		(end 11.35888 -23.76932)
		(width 0.17145)
		(layer "F.Cu")
		(net "DEBUG_RST_A_BTN_N")
	)
	(segment
		(start 9.9695 -23.6601)
		(end 9.9695 -23.2156)
		(width 0.17145)
		(layer "F.Cu")
		(net "DEBUG_RST_A_BTN_N")
	)
	(segment
		(start 11.35888 -23.76932)
		(end 10.8966 -24.2316)
		(width 0.17145)
		(layer "F.Cu")
		(net "DEBUG_RST_A_BTN_N")
	)
	(segment
		(start 10.541 -24.2316)
		(end 10.4648 -24.1554)
		(width 0.17145)
		(layer "F.Cu")
		(net "DEBUG_RST_A_BTN_N")
	)
	(segment
		(start 10.4648 -24.1554)
		(end 9.9695 -23.6601)
		(width 0.17145)
		(layer "F.Cu")
		(net "DEBUG_RST_A_BTN_N")
	)
	(segment
		(start 10.8966 -24.2316)
		(end 10.541 -24.2316)
		(width 0.17145)
		(layer "F.Cu")
		(net "DEBUG_RST_A_BTN_N")
	)
	(via
		(at 10.3886 -22.4536)
		(size 0.508)
		(drill 0.254)
		(layers "F.Cu" "B.Cu")
		(net "DEBUG_RST_A_BTN_N")
	)
	(via
		(at 10.4648 -24.1554)
		(size 0.6604)
		(drill 0.3302)
		(layers "F.Cu" "B.Cu")
		(net "DEBUG_RST_A_BTN_N")
	)
	(via
		(at 11.7348 -28.2448)
		(size 0.508)
		(drill 0.254)
		(layers "F.Cu" "B.Cu")
		(net "DEBUG_RST_A_BTN_N")
	)
	(segment
		(start 10.3886 -22.4536)
		(end 10.3886 -25.015698)
		(width 0.17145)
		(layer "B.Cu")
		(net "DEBUG_RST_A_BTN_N")
	)
	(segment
		(start 11.2268 -25.853898)
		(end 11.2268 -27.7368)
		(width 0.17145)
		(layer "B.Cu")
		(net "DEBUG_RST_A_BTN_N")
	)
	(segment
		(start 10.3886 -25.015698)
		(end 11.2268 -25.853898)
		(width 0.17145)
		(layer "B.Cu")
		(net "DEBUG_RST_A_BTN_N")
	)
	(segment
		(start 11.2268 -27.7368)
		(end 11.7348 -28.2448)
		(width 0.17145)
		(layer "B.Cu")
		(net "DEBUG_RST_A_BTN_N")
	)
	(segment
		(start 44.58589 -8.77951)
		(end 45.119798 -8.77951)
		(width 0.17145)
		(layer "F.Cu")
		(net "UART_B_TX")
	)
	(segment
		(start 45.119798 -8.77951)
		(end 48.4759 -8.77951)
		(width 0.17145)
		(layer "F.Cu")
		(net "UART_B_TX")
	)
	(segment
		(start 43.692572 -9.672828)
		(end 44.58589 -8.77951)
		(width 0.17145)
		(layer "F.Cu")
		(net "UART_B_TX")
	)
	(segment
		(start 41.516808 -9.672828)
		(end 43.692572 -9.672828)
		(width 0.17145)
		(layer "F.Cu")
		(net "UART_B_TX")
	)
	(via
		(at 45.119798 -8.77951)
		(size 0.6604)
		(drill 0.3302)
		(layers "F.Cu" "B.Cu")
		(net "UART_B_TX")
	)
	(segment
		(start 46.853094 -12.786106)
		(end 45.938694 -12.786106)
		(width 0.17145)
		(layer "F.Cu")
		(net "UART_B_RX")
	)
	(segment
		(start 44.3738 -16.17853)
		(end 44.3738 -14.7574)
		(width 0.17145)
		(layer "F.Cu")
		(net "UART_B_RX")
	)
	(segment
		(start 45.3898 -13.7414)
		(end 45.3898 -13.335)
		(width 0.17145)
		(layer "F.Cu")
		(net "UART_B_RX")
	)
	(segment
		(start 43.99153 -16.5608)
		(end 44.3738 -16.17853)
		(width 0.17145)
		(layer "F.Cu")
		(net "UART_B_RX")
	)
	(segment
		(start 45.938694 -12.786106)
		(end 45.3898 -13.335)
		(width 0.17145)
		(layer "F.Cu")
		(net "UART_B_RX")
	)
	(segment
		(start 41.7195 -15.12824)
		(end 41.7195 -15.9131)
		(width 0.17145)
		(layer "F.Cu")
		(net "UART_B_RX")
	)
	(segment
		(start 48.4759 -10.77849)
		(end 48.4759 -11.1633)
		(width 0.17145)
		(layer "F.Cu")
		(net "UART_B_RX")
	)
	(segment
		(start 44.3738 -14.7574)
		(end 45.3898 -13.7414)
		(width 0.17145)
		(layer "F.Cu")
		(net "UART_B_RX")
	)
	(segment
		(start 41.7195 -15.9131)
		(end 42.3672 -16.5608)
		(width 0.17145)
		(layer "F.Cu")
		(net "UART_B_RX")
	)
	(segment
		(start 42.3672 -16.5608)
		(end 43.99153 -16.5608)
		(width 0.17145)
		(layer "F.Cu")
		(net "UART_B_RX")
	)
	(segment
		(start 48.4759 -11.1633)
		(end 46.853094 -12.786106)
		(width 0.17145)
		(layer "F.Cu")
		(net "UART_B_RX")
	)
	(via
		(at 45.3898 -13.335)
		(size 0.6604)
		(drill 0.3302)
		(layers "F.Cu" "B.Cu")
		(net "UART_B_RX")
	)
	(segment
		(start 12.2301 -11.1887)
		(end 11.281664 -10.240264)
		(width 0.17145)
		(layer "F.Cu")
		(net "UART_A_TX")
	)
	(segment
		(start 11.281664 -10.240264)
		(end 11.281664 -9.886188)
		(width 0.17145)
		(layer "F.Cu")
		(net "UART_A_TX")
	)
	(segment
		(start 11.281664 -9.8806)
		(end 11.281664 -9.886188)
		(width 0.17145)
		(layer "F.Cu")
		(net "UART_A_TX")
	)
	(segment
		(start 12.2301 -11.57351)
		(end 12.2301 -11.1887)
		(width 0.17145)
		(layer "F.Cu")
		(net "UART_A_TX")
	)
	(segment
		(start 11.303 -9.859264)
		(end 11.281664 -9.8806)
		(width 0.17145)
		(layer "F.Cu")
		(net "UART_A_TX")
	)
	(segment
		(start 11.303 -8.2423)
		(end 11.303 -9.859264)
		(width 0.17145)
		(layer "F.Cu")
		(net "UART_A_TX")
	)
	(via
		(at 11.281664 -9.886188)
		(size 0.6604)
		(drill 0.3302)
		(layers "F.Cu" "B.Cu")
		(net "UART_A_TX")
	)
	(segment
		(start 16.23314 -10.76706)
		(end 17.0942 -9.906)
		(width 0.17145)
		(layer "F.Cu")
		(net "UART_A_RX")
	)
	(segment
		(start 12.2301 -13.57249)
		(end 13.85951 -13.57249)
		(width 0.17145)
		(layer "F.Cu")
		(net "UART_A_RX")
	)
	(segment
		(start 17.16024 -9.77392)
		(end 17.0942 -9.83996)
		(width 0.17145)
		(layer "F.Cu")
		(net "UART_A_RX")
	)
	(segment
		(start 17.16024 -8.1915)
		(end 17.16024 -9.77392)
		(width 0.17145)
		(layer "F.Cu")
		(net "UART_A_RX")
	)
	(segment
		(start 14.1732 -13.2588)
		(end 14.1732 -11.913616)
		(width 0.17145)
		(layer "F.Cu")
		(net "UART_A_RX")
	)
	(segment
		(start 14.1732 -11.913616)
		(end 15.319756 -10.76706)
		(width 0.17145)
		(layer "F.Cu")
		(net "UART_A_RX")
	)
	(segment
		(start 15.319756 -10.76706)
		(end 16.23314 -10.76706)
		(width 0.17145)
		(layer "F.Cu")
		(net "UART_A_RX")
	)
	(segment
		(start 13.85951 -13.57249)
		(end 14.1732 -13.2588)
		(width 0.17145)
		(layer "F.Cu")
		(net "UART_A_RX")
	)
	(segment
		(start 17.0942 -9.906)
		(end 17.0942 -9.83996)
		(width 0.17145)
		(layer "F.Cu")
		(net "UART_A_RX")
	)
	(via
		(at 17.0942 -9.83996)
		(size 0.6604)
		(drill 0.3302)
		(layers "F.Cu" "B.Cu")
		(net "UART_A_RX")
	)
	(segment
		(start 47.5996 -18.5039)
		(end 47.5996 -19.21764)
		(width 0.17145)
		(layer "F.Cu")
		(net "I2C_DEBUG_B_SDA_L")
	)
	(segment
		(start 49.3903 -12.3825)
		(end 46.967648 -14.805152)
		(width 0.17145)
		(layer "F.Cu")
		(net "I2C_DEBUG_B_SDA_L")
	)
	(segment
		(start 46.967648 -17.256252)
		(end 46.9265 -17.2974)
		(width 0.17145)
		(layer "F.Cu")
		(net "I2C_DEBUG_B_SDA_L")
	)
	(segment
		(start 46.9265 -17.8308)
		(end 47.5996 -18.5039)
		(width 0.17145)
		(layer "F.Cu")
		(net "I2C_DEBUG_B_SDA_L")
	)
	(segment
		(start 46.967648 -14.805152)
		(end 46.967648 -17.256252)
		(width 0.17145)
		(layer "F.Cu")
		(net "I2C_DEBUG_B_SDA_L")
	)
	(segment
		(start 46.9265 -17.2974)
		(end 46.9265 -17.8308)
		(width 0.17145)
		(layer "F.Cu")
		(net "I2C_DEBUG_B_SDA_L")
	)
	(segment
		(start 50.165 -12.3825)
		(end 49.3903 -12.3825)
		(width 0.17145)
		(layer "F.Cu")
		(net "I2C_DEBUG_B_SDA_L")
	)
	(segment
		(start 50.165 -12.3825)
		(end 51.181 -12.3825)
		(width 0.17145)
		(layer "F.Cu")
		(net "I2C_DEBUG_B_SDA_L")
	)
	(via
		(at 50.165 -12.3825)
		(size 0.6604)
		(drill 0.3302)
		(layers "F.Cu" "B.Cu")
		(net "I2C_DEBUG_B_SDA_L")
	)
	(segment
		(start 51.3461 -11.5316)
		(end 49.2506 -11.5316)
		(width 0.17145)
		(layer "F.Cu")
		(net "I2C_DEBUG_B_SCL_L")
	)
	(segment
		(start 46.859444 -13.592556)
		(end 46.5582 -13.8938)
		(width 0.17145)
		(layer "F.Cu")
		(net "I2C_DEBUG_B_SCL_L")
	)
	(segment
		(start 52.197 -12.3825)
		(end 51.3461 -11.5316)
		(width 0.17145)
		(layer "F.Cu")
		(net "I2C_DEBUG_B_SCL_L")
	)
	(segment
		(start 45.9105 -17.264634)
		(end 46.288198 -16.886936)
		(width 0.17145)
		(layer "F.Cu")
		(net "I2C_DEBUG_B_SCL_L")
	)
	(segment
		(start 45.9105 -18.8595)
		(end 45.9105 -17.8308)
		(width 0.17145)
		(layer "F.Cu")
		(net "I2C_DEBUG_B_SCL_L")
	)
	(segment
		(start 47.5996 -19.86788)
		(end 46.91888 -19.86788)
		(width 0.17145)
		(layer "F.Cu")
		(net "I2C_DEBUG_B_SCL_L")
	)
	(segment
		(start 46.288198 -16.886936)
		(end 46.288198 -14.163802)
		(width 0.17145)
		(layer "F.Cu")
		(net "I2C_DEBUG_B_SCL_L")
	)
	(segment
		(start 46.91888 -19.86788)
		(end 45.9105 -18.8595)
		(width 0.17145)
		(layer "F.Cu")
		(net "I2C_DEBUG_B_SCL_L")
	)
	(segment
		(start 47.189644 -13.592556)
		(end 46.859444 -13.592556)
		(width 0.17145)
		(layer "F.Cu")
		(net "I2C_DEBUG_B_SCL_L")
	)
	(segment
		(start 45.9105 -17.8308)
		(end 45.9105 -17.264634)
		(width 0.17145)
		(layer "F.Cu")
		(net "I2C_DEBUG_B_SCL_L")
	)
	(segment
		(start 46.288198 -14.163802)
		(end 46.5582 -13.8938)
		(width 0.17145)
		(layer "F.Cu")
		(net "I2C_DEBUG_B_SCL_L")
	)
	(segment
		(start 49.2506 -11.5316)
		(end 47.189644 -13.592556)
		(width 0.17145)
		(layer "F.Cu")
		(net "I2C_DEBUG_B_SCL_L")
	)
	(via
		(at 46.5582 -13.8938)
		(size 0.6604)
		(drill 0.3302)
		(layers "F.Cu" "B.Cu")
		(net "I2C_DEBUG_B_SCL_L")
	)
	(segment
		(start 7.5311 -19.0119)
		(end 7.5311 -17.9832)
		(width 0.17145)
		(layer "F.Cu")
		(net "I2C_DEBUG_A_SDA_L")
	)
	(segment
		(start 8.0518 -15.9004)
		(end 7.5311 -16.4211)
		(width 0.17145)
		(layer "F.Cu")
		(net "I2C_DEBUG_A_SDA_L")
	)
	(segment
		(start 8.7376 -19.47164)
		(end 7.99084 -19.47164)
		(width 0.17145)
		(layer "F.Cu")
		(net "I2C_DEBUG_A_SDA_L")
	)
	(segment
		(start 7.5311 -17.9832)
		(end 7.5311 -16.891)
		(width 0.17145)
		(layer "F.Cu")
		(net "I2C_DEBUG_A_SDA_L")
	)
	(segment
		(start 7.5311 -16.4211)
		(end 7.5311 -16.891)
		(width 0.17145)
		(layer "F.Cu")
		(net "I2C_DEBUG_A_SDA_L")
	)
	(segment
		(start 8.4963 -15.9004)
		(end 8.0518 -15.9004)
		(width 0.17145)
		(layer "F.Cu")
		(net "I2C_DEBUG_A_SDA_L")
	)
	(segment
		(start 7.99084 -19.47164)
		(end 7.5311 -19.0119)
		(width 0.17145)
		(layer "F.Cu")
		(net "I2C_DEBUG_A_SDA_L")
	)
	(via
		(at 7.5311 -16.891)
		(size 0.6604)
		(drill 0.3302)
		(layers "F.Cu" "B.Cu")
		(net "I2C_DEBUG_A_SDA_L")
	)
	(segment
		(start 8.112252 -14.087348)
		(end 7.4676 -14.732)
		(width 0.17145)
		(layer "F.Cu")
		(net "I2C_DEBUG_A_SCL_L")
	)
	(segment
		(start 6.5151 -17.9832)
		(end 6.5151 -15.9131)
		(width 0.17145)
		(layer "F.Cu")
		(net "I2C_DEBUG_A_SCL_L")
	)
	(segment
		(start 7.4676 -14.732)
		(end 7.4676 -14.9606)
		(width 0.17145)
		(layer "F.Cu")
		(net "I2C_DEBUG_A_SCL_L")
	)
	(segment
		(start 7.679944 -20.12188)
		(end 6.5151 -18.957036)
		(width 0.17145)
		(layer "F.Cu")
		(net "I2C_DEBUG_A_SCL_L")
	)
	(segment
		(start 6.5151 -18.957036)
		(end 6.5151 -17.9832)
		(width 0.17145)
		(layer "F.Cu")
		(net "I2C_DEBUG_A_SCL_L")
	)
	(segment
		(start 6.5151 -15.9131)
		(end 7.4676 -14.9606)
		(width 0.17145)
		(layer "F.Cu")
		(net "I2C_DEBUG_A_SCL_L")
	)
	(segment
		(start 12.2555 -14.8463)
		(end 11.496548 -14.087348)
		(width 0.17145)
		(layer "F.Cu")
		(net "I2C_DEBUG_A_SCL_L")
	)
	(segment
		(start 11.496548 -14.087348)
		(end 8.112252 -14.087348)
		(width 0.17145)
		(layer "F.Cu")
		(net "I2C_DEBUG_A_SCL_L")
	)
	(segment
		(start 12.2555 -15.1638)
		(end 12.2555 -14.8463)
		(width 0.17145)
		(layer "F.Cu")
		(net "I2C_DEBUG_A_SCL_L")
	)
	(segment
		(start 8.7376 -20.12188)
		(end 7.679944 -20.12188)
		(width 0.17145)
		(layer "F.Cu")
		(net "I2C_DEBUG_A_SCL_L")
	)
	(via
		(at 7.4676 -14.9606)
		(size 0.6604)
		(drill 0.3302)
		(layers "F.Cu" "B.Cu")
		(net "I2C_DEBUG_A_SCL_L")
	)
	(segment
		(start 53.975 -29.8196)
		(end 54.3814 -30.226)
		(width 0.17145)
		(layer "F.Cu")
		(net "RST_B_TS")
	)
	(segment
		(start 54.3814 -30.226)
		(end 54.5719 -30.226)
		(width 0.17145)
		(layer "F.Cu")
		(net "RST_B_TS")
	)
	(segment
		(start 53.333904 -29.8196)
		(end 53.975 -29.8196)
		(width 0.17145)
		(layer "F.Cu")
		(net "RST_B_TS")
	)
	(segment
		(start 55.094886 -31.701486)
		(end 54.61 -31.2166)
		(width 0.17145)
		(layer "F.Cu")
		(net "RST_B_TS")
	)
	(segment
		(start 54.5719 -31.1785)
		(end 54.61 -31.2166)
		(width 0.17145)
		(layer "F.Cu")
		(net "RST_B_TS")
	)
	(segment
		(start 55.583328 -31.701486)
		(end 55.094886 -31.701486)
		(width 0.17145)
		(layer "F.Cu")
		(net "RST_B_TS")
	)
	(segment
		(start 54.5719 -30.226)
		(end 54.5719 -31.1785)
		(width 0.17145)
		(layer "F.Cu")
		(net "RST_B_TS")
	)
	(via
		(at 54.61 -31.2166)
		(size 0.6604)
		(drill 0.3302)
		(layers "F.Cu" "B.Cu")
		(net "RST_B_TS")
	)
	(segment
		(start 9.309608 -27.776932)
		(end 9.649968 -27.776932)
		(width 0.17145)
		(layer "F.Cu")
		(net "RST_A_TS")
	)
	(segment
		(start 9.3726 -29.7561)
		(end 9.3726 -28.8036)
		(width 0.17145)
		(layer "F.Cu")
		(net "RST_A_TS")
	)
	(segment
		(start 8.001 -28.004008)
		(end 8.673592 -28.004008)
		(width 0.17145)
		(layer "F.Cu")
		(net "RST_A_TS")
	)
	(segment
		(start 8.78078 -27.89682)
		(end 9.18972 -27.89682)
		(width 0.17145)
		(layer "F.Cu")
		(net "RST_A_TS")
	)
	(segment
		(start 9.649968 -27.776932)
		(end 9.649968 -28.526232)
		(width 0.17145)
		(layer "F.Cu")
		(net "RST_A_TS")
	)
	(segment
		(start 9.7155 -30.099)
		(end 9.3726 -29.7561)
		(width 0.17145)
		(layer "F.Cu")
		(net "RST_A_TS")
	)
	(segment
		(start 8.673592 -28.004008)
		(end 8.78078 -27.89682)
		(width 0.17145)
		(layer "F.Cu")
		(net "RST_A_TS")
	)
	(segment
		(start 9.3726 -28.8036)
		(end 9.398 -28.7782)
		(width 0.17145)
		(layer "F.Cu")
		(net "RST_A_TS")
	)
	(segment
		(start 9.18972 -27.89682)
		(end 9.309608 -27.776932)
		(width 0.17145)
		(layer "F.Cu")
		(net "RST_A_TS")
	)
	(segment
		(start 9.649968 -28.526232)
		(end 9.398 -28.7782)
		(width 0.17145)
		(layer "F.Cu")
		(net "RST_A_TS")
	)
	(via
		(at 9.398 -28.7782)
		(size 0.6604)
		(drill 0.3302)
		(layers "F.Cu" "B.Cu")
		(net "RST_A_TS")
	)
	(segment
		(start 37.733732 -3.338068)
		(end 37.733732 -10.933684)
		(width 0.17145)
		(layer "F.Cu")
		(net "I2C_DPB_B_SDA")
	)
	(segment
		(start 45.948092 -25.1333)
		(end 41.757092 -25.1333)
		(width 0.17145)
		(layer "F.Cu")
		(net "I2C_DPB_B_SDA")
	)
	(segment
		(start 48.829468 -24.962104)
		(end 48.266604 -24.962104)
		(width 0.17145)
		(layer "F.Cu")
		(net "I2C_DPB_B_SDA")
	)
	(segment
		(start 37.805106 -1.599946)
		(end 37.805106 -3.266694)
		(width 0.17145)
		(layer "F.Cu")
		(net "I2C_DPB_B_SDA")
	)
	(segment
		(start 48.26635 -24.96185)
		(end 46.119542 -24.96185)
		(width 0.17145)
		(layer "F.Cu")
		(net "I2C_DPB_B_SDA")
	)
	(segment
		(start 37.759894 -21.136102)
		(end 37.759894 -19.821144)
		(width 0.17145)
		(layer "F.Cu")
		(net "I2C_DPB_B_SDA")
	)
	(segment
		(start 49.679352 -24.11222)
		(end 48.829468 -24.962104)
		(width 0.17145)
		(layer "F.Cu")
		(net "I2C_DPB_B_SDA")
	)
	(segment
		(start 37.737796 -19.799046)
		(end 37.737796 -15.564866)
		(width 0.17145)
		(layer "F.Cu")
		(net "I2C_DPB_B_SDA")
	)
	(segment
		(start 53.3146 -43.8531)
		(end 53.3146 -43.056302)
		(width 0.17145)
		(layer "F.Cu")
		(net "I2C_DPB_B_SDA")
	)
	(segment
		(start 37.733732 -13.434314)
		(end 37.733732 -10.933684)
		(width 0.17145)
		(layer "F.Cu")
		(net "I2C_DPB_B_SDA")
	)
	(segment
		(start 46.119542 -24.96185)
		(end 45.948092 -25.1333)
		(width 0.17145)
		(layer "F.Cu")
		(net "I2C_DPB_B_SDA")
	)
	(segment
		(start 56.0578 -24.6888)
		(end 54.3306 -24.6888)
		(width 0.17145)
		(layer "F.Cu")
		(net "I2C_DPB_B_SDA")
	)
	(segment
		(start 53.3146 -43.056302)
		(end 57.47385 -38.897052)
		(width 0.17145)
		(layer "F.Cu")
		(net "I2C_DPB_B_SDA")
	)
	(segment
		(start 37.805106 -3.266694)
		(end 37.733732 -3.338068)
		(width 0.17145)
		(layer "F.Cu")
		(net "I2C_DPB_B_SDA")
	)
	(segment
		(start 54.3306 -24.6888)
		(end 53.75402 -24.11222)
		(width 0.17145)
		(layer "F.Cu")
		(net "I2C_DPB_B_SDA")
	)
	(segment
		(start 37.759894 -19.821144)
		(end 37.737796 -19.799046)
		(width 0.17145)
		(layer "F.Cu")
		(net "I2C_DPB_B_SDA")
	)
	(segment
		(start 48.266604 -24.962104)
		(end 48.26635 -24.96185)
		(width 0.17145)
		(layer "F.Cu")
		(net "I2C_DPB_B_SDA")
	)
	(segment
		(start 37.737796 -15.564866)
		(end 37.759894 -15.542768)
		(width 0.17145)
		(layer "F.Cu")
		(net "I2C_DPB_B_SDA")
	)
	(segment
		(start 57.47385 -38.897052)
		(end 57.47385 -26.10485)
		(width 0.17145)
		(layer "F.Cu")
		(net "I2C_DPB_B_SDA")
	)
	(segment
		(start 37.759894 -15.542768)
		(end 37.759894 -13.460476)
		(width 0.17145)
		(layer "F.Cu")
		(net "I2C_DPB_B_SDA")
	)
	(segment
		(start 41.757092 -25.1333)
		(end 37.759894 -21.136102)
		(width 0.17145)
		(layer "F.Cu")
		(net "I2C_DPB_B_SDA")
	)
	(segment
		(start 53.75402 -24.11222)
		(end 49.679352 -24.11222)
		(width 0.17145)
		(layer "F.Cu")
		(net "I2C_DPB_B_SDA")
	)
	(segment
		(start 37.759894 -13.460476)
		(end 37.733732 -13.434314)
		(width 0.17145)
		(layer "F.Cu")
		(net "I2C_DPB_B_SDA")
	)
	(segment
		(start 57.47385 -26.10485)
		(end 56.0578 -24.6888)
		(width 0.17145)
		(layer "F.Cu")
		(net "I2C_DPB_B_SDA")
	)
	(via
		(at 37.733732 -10.933684)
		(size 0.6604)
		(drill 0.3302)
		(layers "F.Cu" "B.Cu")
		(net "I2C_DPB_B_SDA")
	)
	(segment
		(start 47.984664 -25.6413)
		(end 46.401228 -25.6413)
		(width 0.17145)
		(layer "F.Cu")
		(net "I2C_DPB_B_SCL")
	)
	(segment
		(start 36.535106 -4.556506)
		(end 37.054282 -5.075682)
		(width 0.17145)
		(layer "F.Cu")
		(net "I2C_DPB_B_SCL")
	)
	(segment
		(start 55.7784 -25.3746)
		(end 53.8226 -25.3746)
		(width 0.17145)
		(layer "F.Cu")
		(net "I2C_DPB_B_SCL")
	)
	(segment
		(start 47.984918 -25.641554)
		(end 47.984664 -25.6413)
		(width 0.17145)
		(layer "F.Cu")
		(net "I2C_DPB_B_SCL")
	)
	(segment
		(start 49.111154 -25.641554)
		(end 47.984918 -25.641554)
		(width 0.17145)
		(layer "F.Cu")
		(net "I2C_DPB_B_SCL")
	)
	(segment
		(start 46.401228 -25.6413)
		(end 46.229778 -25.81275)
		(width 0.17145)
		(layer "F.Cu")
		(net "I2C_DPB_B_SCL")
	)
	(segment
		(start 49.961038 -24.79167)
		(end 49.111154 -25.641554)
		(width 0.17145)
		(layer "F.Cu")
		(net "I2C_DPB_B_SCL")
	)
	(segment
		(start 36.535106 -1.599946)
		(end 36.535106 -4.556506)
		(width 0.17145)
		(layer "F.Cu")
		(net "I2C_DPB_B_SCL")
	)
	(segment
		(start 37.054282 -5.075682)
		(end 37.054282 -13.716)
		(width 0.17145)
		(layer "F.Cu")
		(net "I2C_DPB_B_SCL")
	)
	(segment
		(start 52.197 -43.8531)
		(end 52.197 -43.212766)
		(width 0.17145)
		(layer "F.Cu")
		(net "I2C_DPB_B_SCL")
	)
	(segment
		(start 52.197 -43.212766)
		(end 56.7944 -38.615366)
		(width 0.17145)
		(layer "F.Cu")
		(net "I2C_DPB_B_SCL")
	)
	(segment
		(start 56.7944 -26.3906)
		(end 55.7784 -25.3746)
		(width 0.17145)
		(layer "F.Cu")
		(net "I2C_DPB_B_SCL")
	)
	(segment
		(start 41.475406 -25.81275)
		(end 37.054282 -21.391626)
		(width 0.17145)
		(layer "F.Cu")
		(net "I2C_DPB_B_SCL")
	)
	(segment
		(start 37.054282 -21.391626)
		(end 37.054282 -13.716)
		(width 0.17145)
		(layer "F.Cu")
		(net "I2C_DPB_B_SCL")
	)
	(segment
		(start 53.23967 -24.79167)
		(end 49.961038 -24.79167)
		(width 0.17145)
		(layer "F.Cu")
		(net "I2C_DPB_B_SCL")
	)
	(segment
		(start 56.7944 -38.615366)
		(end 56.7944 -26.3906)
		(width 0.17145)
		(layer "F.Cu")
		(net "I2C_DPB_B_SCL")
	)
	(segment
		(start 53.8226 -25.3746)
		(end 53.23967 -24.79167)
		(width 0.17145)
		(layer "F.Cu")
		(net "I2C_DPB_B_SCL")
	)
	(segment
		(start 46.229778 -25.81275)
		(end 41.475406 -25.81275)
		(width 0.17145)
		(layer "F.Cu")
		(net "I2C_DPB_B_SCL")
	)
	(via
		(at 37.054282 -13.716)
		(size 0.6604)
		(drill 0.3302)
		(layers "F.Cu" "B.Cu")
		(net "I2C_DPB_B_SCL")
	)
	(segment
		(start 46.900084 -51.884834)
		(end 46.900084 -53.599842)
		(width 0.381)
		(layer "F.Cu")
		(net "USB_CONN_B_GND")
	)
	(segment
		(start 46.900084 -66.399918)
		(end 48.615092 -66.399918)
		(width 0.381)
		(layer "F.Cu")
		(net "USB_CONN_B_GND")
	)
	(segment
		(start 46.900084 -66.399918)
		(end 46.900084 -68.114926)
		(width 0.381)
		(layer "F.Cu")
		(net "USB_CONN_B_GND")
	)
	(segment
		(start 50.900076 -66.399918)
		(end 50.900076 -68.114926)
		(width 0.381)
		(layer "F.Cu")
		(net "USB_CONN_B_GND")
	)
	(segment
		(start 49.185068 -53.599842)
		(end 50.900076 -53.599842)
		(width 0.381)
		(layer "F.Cu")
		(net "USB_CONN_B_GND")
	)
	(segment
		(start 50.900076 -53.599842)
		(end 52.615084 -53.599842)
		(width 0.381)
		(layer "F.Cu")
		(net "USB_CONN_B_GND")
	)
	(segment
		(start 50.900076 -66.399918)
		(end 52.615084 -66.399918)
		(width 0.381)
		(layer "F.Cu")
		(net "USB_CONN_B_GND")
	)
	(segment
		(start 50.900076 -51.884834)
		(end 50.900076 -53.599842)
		(width 0.381)
		(layer "F.Cu")
		(net "USB_CONN_B_GND")
	)
	(segment
		(start 45.185076 -66.399918)
		(end 46.900084 -66.399918)
		(width 0.381)
		(layer "F.Cu")
		(net "USB_CONN_B_GND")
	)
	(segment
		(start 46.900084 -53.599842)
		(end 48.615092 -53.599842)
		(width 0.381)
		(layer "F.Cu")
		(net "USB_CONN_B_GND")
	)
	(segment
		(start 45.185076 -53.599842)
		(end 46.900084 -53.599842)
		(width 0.381)
		(layer "F.Cu")
		(net "USB_CONN_B_GND")
	)
	(segment
		(start 49.185068 -66.399918)
		(end 50.900076 -66.399918)
		(width 0.381)
		(layer "F.Cu")
		(net "USB_CONN_B_GND")
	)
	(via
		(at 54.295548 -61.241178)
		(size 0.6604)
		(drill 0.3302)
		(layers "F.Cu" "B.Cu")
		(net "USB_CONN_B_GND")
	)
	(segment
		(start 49.63668 -52.336446)
		(end 50.900076 -53.599842)
		(width 0.508)
		(layer "B.Cu")
		(net "USB_CONN_B_GND")
	)
	(segment
		(start 46.900084 -64.68491)
		(end 46.900084 -66.399918)
		(width 0.508)
		(layer "B.Cu")
		(net "USB_CONN_B_GND")
	)
	(segment
		(start 46.900084 -66.399918)
		(end 46.900084 -68.114926)
		(width 0.508)
		(layer "B.Cu")
		(net "USB_CONN_B_GND")
	)
	(segment
		(start 50.900076 -66.399918)
		(end 52.615084 -66.399918)
		(width 0.508)
		(layer "B.Cu")
		(net "USB_CONN_B_GND")
	)
	(segment
		(start 46.900084 -53.599842)
		(end 46.900084 -55.31485)
		(width 0.508)
		(layer "B.Cu")
		(net "USB_CONN_B_GND")
	)
	(segment
		(start 46.900084 -51.884834)
		(end 46.900084 -53.599842)
		(width 0.508)
		(layer "B.Cu")
		(net "USB_CONN_B_GND")
	)
	(segment
		(start 46.900084 -53.599842)
		(end 48.615092 -53.599842)
		(width 0.508)
		(layer "B.Cu")
		(net "USB_CONN_B_GND")
	)
	(segment
		(start 49.185068 -53.599842)
		(end 50.900076 -53.599842)
		(width 0.508)
		(layer "B.Cu")
		(net "USB_CONN_B_GND")
	)
	(segment
		(start 49.185068 -66.399918)
		(end 50.900076 -66.399918)
		(width 0.508)
		(layer "B.Cu")
		(net "USB_CONN_B_GND")
	)
	(segment
		(start 45.185076 -53.599842)
		(end 46.900084 -53.599842)
		(width 0.508)
		(layer "B.Cu")
		(net "USB_CONN_B_GND")
	)
	(segment
		(start 50.900076 -66.399918)
		(end 50.900076 -68.114926)
		(width 0.508)
		(layer "B.Cu")
		(net "USB_CONN_B_GND")
	)
	(segment
		(start 46.900084 -66.399918)
		(end 48.615092 -66.399918)
		(width 0.508)
		(layer "B.Cu")
		(net "USB_CONN_B_GND")
	)
	(segment
		(start 45.185076 -66.399918)
		(end 46.900084 -66.399918)
		(width 0.508)
		(layer "B.Cu")
		(net "USB_CONN_B_GND")
	)
	(segment
		(start 6.199886 -66.399918)
		(end 6.199886 -68.114926)
		(width 0.381)
		(layer "F.Cu")
		(net "USB_CONN_A_GND")
	)
	(segment
		(start 6.199886 -51.884834)
		(end 6.199886 -53.599842)
		(width 0.381)
		(layer "F.Cu")
		(net "USB_CONN_A_GND")
	)
	(segment
		(start 6.199886 -53.599842)
		(end 7.914894 -53.599842)
		(width 0.381)
		(layer "F.Cu")
		(net "USB_CONN_A_GND")
	)
	(segment
		(start 10.199878 -66.399918)
		(end 11.914886 -66.399918)
		(width 0.381)
		(layer "F.Cu")
		(net "USB_CONN_A_GND")
	)
	(segment
		(start 10.199878 -66.399918)
		(end 10.199878 -68.114926)
		(width 0.381)
		(layer "F.Cu")
		(net "USB_CONN_A_GND")
	)
	(segment
		(start 4.484878 -66.399918)
		(end 6.199886 -66.399918)
		(width 0.381)
		(layer "F.Cu")
		(net "USB_CONN_A_GND")
	)
	(segment
		(start 8.936482 -52.336446)
		(end 10.199878 -53.599842)
		(width 0.381)
		(layer "F.Cu")
		(net "USB_CONN_A_GND")
	)
	(segment
		(start 4.484878 -53.599842)
		(end 6.199886 -53.599842)
		(width 0.381)
		(layer "F.Cu")
		(net "USB_CONN_A_GND")
	)
	(segment
		(start 8.48487 -66.399918)
		(end 10.199878 -66.399918)
		(width 0.381)
		(layer "F.Cu")
		(net "USB_CONN_A_GND")
	)
	(segment
		(start 6.199886 -66.399918)
		(end 7.914894 -66.399918)
		(width 0.381)
		(layer "F.Cu")
		(net "USB_CONN_A_GND")
	)
	(segment
		(start 8.48487 -53.599842)
		(end 10.199878 -53.599842)
		(width 0.381)
		(layer "F.Cu")
		(net "USB_CONN_A_GND")
	)
	(via
		(at 11.157204 -70.358)
		(size 0.6604)
		(drill 0.3302)
		(layers "F.Cu" "B.Cu")
		(net "USB_CONN_A_GND")
	)
	(segment
		(start 6.199886 -53.599842)
		(end 7.914894 -53.599842)
		(width 0.508)
		(layer "B.Cu")
		(net "USB_CONN_A_GND")
	)
	(segment
		(start 10.199878 -66.399918)
		(end 11.914886 -66.399918)
		(width 0.508)
		(layer "B.Cu")
		(net "USB_CONN_A_GND")
	)
	(segment
		(start 10.199878 -51.884834)
		(end 10.199878 -53.599842)
		(width 0.508)
		(layer "B.Cu")
		(net "USB_CONN_A_GND")
	)
	(segment
		(start 6.199886 -51.884834)
		(end 6.199886 -53.599842)
		(width 0.508)
		(layer "B.Cu")
		(net "USB_CONN_A_GND")
	)
	(segment
		(start 10.199878 -53.599842)
		(end 11.914886 -53.599842)
		(width 0.508)
		(layer "B.Cu")
		(net "USB_CONN_A_GND")
	)
	(segment
		(start 6.199886 -66.399918)
		(end 7.914894 -66.399918)
		(width 0.508)
		(layer "B.Cu")
		(net "USB_CONN_A_GND")
	)
	(segment
		(start 4.484878 -66.399918)
		(end 6.199886 -66.399918)
		(width 0.508)
		(layer "B.Cu")
		(net "USB_CONN_A_GND")
	)
	(segment
		(start 6.199886 -66.399918)
		(end 6.199886 -68.114926)
		(width 0.508)
		(layer "B.Cu")
		(net "USB_CONN_A_GND")
	)
	(segment
		(start 4.484878 -53.599842)
		(end 6.199886 -53.599842)
		(width 0.508)
		(layer "B.Cu")
		(net "USB_CONN_A_GND")
	)
	(segment
		(start 6.199886 -64.68491)
		(end 6.199886 -66.399918)
		(width 0.508)
		(layer "B.Cu")
		(net "USB_CONN_A_GND")
	)
	(segment
		(start 8.48487 -66.399918)
		(end 10.199878 -66.399918)
		(width 0.508)
		(layer "B.Cu")
		(net "USB_CONN_A_GND")
	)
	(segment
		(start 8.48487 -53.599842)
		(end 10.199878 -53.599842)
		(width 0.508)
		(layer "B.Cu")
		(net "USB_CONN_A_GND")
	)
	(segment
		(start 10.199878 -66.399918)
		(end 10.199878 -68.114926)
		(width 0.508)
		(layer "B.Cu")
		(net "USB_CONN_A_GND")
	)
	(segment
		(start 39.223696 -16.180816)
		(end 39.223696 -18.292064)
		(width 0.17145)
		(layer "F.Cu")
		(net "UART_DEBUG_B_TX")
	)
	(segment
		(start 39.245794 -10.188448)
		(end 39.245794 -16.158718)
		(width 0.17145)
		(layer "F.Cu")
		(net "UART_DEBUG_B_TX")
	)
	(segment
		(start 43.167808 -8.255)
		(end 42.507408 -7.5946)
		(width 0.17145)
		(layer "F.Cu")
		(net "UART_DEBUG_B_TX")
	)
	(segment
		(start 55.31866 -58.508392)
		(end 55.31866 -57.64022)
		(width 0.17145)
		(layer "F.Cu")
		(net "UART_DEBUG_B_TX")
	)
	(segment
		(start 43.167808 -9.022588)
		(end 43.167808 -8.255)
		(width 0.17145)
		(layer "F.Cu")
		(net "UART_DEBUG_B_TX")
	)
	(segment
		(start 39.223696 -18.292064)
		(end 39.228776 -18.297144)
		(width 0.17145)
		(layer "F.Cu")
		(net "UART_DEBUG_B_TX")
	)
	(segment
		(start 39.245794 -16.158718)
		(end 39.223696 -16.180816)
		(width 0.17145)
		(layer "F.Cu")
		(net "UART_DEBUG_B_TX")
	)
	(segment
		(start 42.507408 -7.5946)
		(end 40.0304 -7.5946)
		(width 0.17145)
		(layer "F.Cu")
		(net "UART_DEBUG_B_TX")
	)
	(segment
		(start 39.223696 -10.16635)
		(end 39.245794 -10.188448)
		(width 0.17145)
		(layer "F.Cu")
		(net "UART_DEBUG_B_TX")
	)
	(segment
		(start 39.223696 -8.401304)
		(end 39.223696 -10.166096)
		(width 0.17145)
		(layer "F.Cu")
		(net "UART_DEBUG_B_TX")
	)
	(segment
		(start 40.0304 -7.5946)
		(end 39.223696 -8.401304)
		(width 0.17145)
		(layer "F.Cu")
		(net "UART_DEBUG_B_TX")
	)
	(segment
		(start 39.223696 -10.166096)
		(end 39.223696 -10.16635)
		(width 0.17145)
		(layer "F.Cu")
		(net "UART_DEBUG_B_TX")
	)
	(segment
		(start 54.842664 -58.984388)
		(end 55.31866 -58.508392)
		(width 0.17145)
		(layer "F.Cu")
		(net "UART_DEBUG_B_TX")
	)
	(via
		(at 39.228776 -18.297144)
		(size 0.508)
		(drill 0.254)
		(layers "F.Cu" "B.Cu")
		(net "UART_DEBUG_B_TX")
	)
	(via
		(at 54.842664 -58.984388)
		(size 0.508)
		(drill 0.254)
		(layers "F.Cu" "B.Cu")
		(net "UART_DEBUG_B_TX")
	)
	(via
		(at 39.223696 -10.166096)
		(size 0.6604)
		(drill 0.3302)
		(layers "F.Cu" "B.Cu")
		(net "UART_DEBUG_B_TX")
	)
	(segment
		(start 51.827176 -61.999876)
		(end 50.400204 -61.999876)
		(width 0.17145)
		(layer "B.Cu")
		(net "UART_DEBUG_B_TX")
	)
	(segment
		(start 54.879748 -58.947304)
		(end 54.842664 -58.984388)
		(width 0.17145)
		(layer "B.Cu")
		(net "UART_DEBUG_B_TX")
	)
	(segment
		(start 46.4439 -30.33776)
		(end 46.4439 -41.228264)
		(width 0.17145)
		(layer "B.Cu")
		(net "UART_DEBUG_B_TX")
	)
	(segment
		(start 39.228776 -18.391886)
		(end 41.690544 -20.853654)
		(width 0.17145)
		(layer "B.Cu")
		(net "UART_DEBUG_B_TX")
	)
	(segment
		(start 39.228776 -18.297144)
		(end 39.228776 -18.391886)
		(width 0.17145)
		(layer "B.Cu")
		(net "UART_DEBUG_B_TX")
	)
	(segment
		(start 54.879748 -51.409346)
		(end 54.879748 -58.947304)
		(width 0.17145)
		(layer "B.Cu")
		(net "UART_DEBUG_B_TX")
	)
	(segment
		(start 47.525432 -45.798994)
		(end 49.633378 -47.90694)
		(width 0.17145)
		(layer "B.Cu")
		(net "UART_DEBUG_B_TX")
	)
	(segment
		(start 51.377342 -47.90694)
		(end 54.879748 -51.409346)
		(width 0.17145)
		(layer "B.Cu")
		(net "UART_DEBUG_B_TX")
	)
	(segment
		(start 47.525432 -42.309796)
		(end 47.525432 -45.798994)
		(width 0.17145)
		(layer "B.Cu")
		(net "UART_DEBUG_B_TX")
	)
	(segment
		(start 41.690544 -20.853654)
		(end 41.690544 -25.584404)
		(width 0.17145)
		(layer "B.Cu")
		(net "UART_DEBUG_B_TX")
	)
	(segment
		(start 54.842664 -58.984388)
		(end 51.827176 -61.999876)
		(width 0.17145)
		(layer "B.Cu")
		(net "UART_DEBUG_B_TX")
	)
	(segment
		(start 49.633378 -47.90694)
		(end 51.377342 -47.90694)
		(width 0.17145)
		(layer "B.Cu")
		(net "UART_DEBUG_B_TX")
	)
	(segment
		(start 46.4439 -41.228264)
		(end 47.525432 -42.309796)
		(width 0.17145)
		(layer "B.Cu")
		(net "UART_DEBUG_B_TX")
	)
	(segment
		(start 41.690544 -25.584404)
		(end 46.4439 -30.33776)
		(width 0.17145)
		(layer "B.Cu")
		(net "UART_DEBUG_B_TX")
	)
	(segment
		(start 40.91305 -16.22425)
		(end 40.91305 -16.247618)
		(width 0.17145)
		(layer "F.Cu")
		(net "UART_DEBUG_B_RX")
	)
	(segment
		(start 40.8432 -18.288)
		(end 40.8432 -17.6784)
		(width 0.17145)
		(layer "F.Cu")
		(net "UART_DEBUG_B_RX")
	)
	(segment
		(start 40.8432 -17.6784)
		(end 41.021 -17.5006)
		(width 0.17145)
		(layer "F.Cu")
		(net "UART_DEBUG_B_RX")
	)
	(segment
		(start 40.91305 -16.247618)
		(end 41.021 -16.355568)
		(width 0.17145)
		(layer "F.Cu")
		(net "UART_DEBUG_B_RX")
	)
	(segment
		(start 55.694326 -55.484268)
		(end 55.31866 -55.859934)
		(width 0.17145)
		(layer "F.Cu")
		(net "UART_DEBUG_B_RX")
	)
	(segment
		(start 41.021 -17.5006)
		(end 41.021 -16.6624)
		(width 0.17145)
		(layer "F.Cu")
		(net "UART_DEBUG_B_RX")
	)
	(segment
		(start 55.31866 -55.859934)
		(end 55.31866 -56.19242)
		(width 0.17145)
		(layer "F.Cu")
		(net "UART_DEBUG_B_RX")
	)
	(segment
		(start 43.3705 -14.478)
		(end 41.228518 -14.478)
		(width 0.17145)
		(layer "F.Cu")
		(net "UART_DEBUG_B_RX")
	)
	(segment
		(start 40.858694 -14.847824)
		(end 40.858694 -16.169894)
		(width 0.17145)
		(layer "F.Cu")
		(net "UART_DEBUG_B_RX")
	)
	(segment
		(start 41.228518 -14.478)
		(end 40.858694 -14.847824)
		(width 0.17145)
		(layer "F.Cu")
		(net "UART_DEBUG_B_RX")
	)
	(segment
		(start 41.021 -16.355568)
		(end 41.021 -16.6624)
		(width 0.17145)
		(layer "F.Cu")
		(net "UART_DEBUG_B_RX")
	)
	(segment
		(start 40.858694 -16.169894)
		(end 40.91305 -16.22425)
		(width 0.17145)
		(layer "F.Cu")
		(net "UART_DEBUG_B_RX")
	)
	(segment
		(start 55.694326 -55.02529)
		(end 55.694326 -55.484268)
		(width 0.17145)
		(layer "F.Cu")
		(net "UART_DEBUG_B_RX")
	)
	(via
		(at 40.8432 -18.288)
		(size 0.508)
		(drill 0.254)
		(layers "F.Cu" "B.Cu")
		(net "UART_DEBUG_B_RX")
	)
	(via
		(at 55.694326 -55.02529)
		(size 0.508)
		(drill 0.254)
		(layers "F.Cu" "B.Cu")
		(net "UART_DEBUG_B_RX")
	)
	(via
		(at 41.021 -16.6624)
		(size 0.6604)
		(drill 0.3302)
		(layers "F.Cu" "B.Cu")
		(net "UART_DEBUG_B_RX")
	)
	(segment
		(start 51.021996 -63.999872)
		(end 50.400204 -63.999872)
		(width 0.17145)
		(layer "B.Cu")
		(net "UART_DEBUG_B_RX")
	)
	(segment
		(start 42.496994 -25.25014)
		(end 42.496994 -20.51939)
		(width 0.17145)
		(layer "B.Cu")
		(net "UART_DEBUG_B_RX")
	)
	(segment
		(start 47.25035 -40.894)
		(end 47.25035 -30.003496)
		(width 0.17145)
		(layer "B.Cu")
		(net "UART_DEBUG_B_RX")
	)
	(segment
		(start 48.331882 -45.46473)
		(end 48.331882 -41.975532)
		(width 0.17145)
		(layer "B.Cu")
		(net "UART_DEBUG_B_RX")
	)
	(segment
		(start 55.694326 -55.02529)
		(end 55.694326 -51.08321)
		(width 0.17145)
		(layer "B.Cu")
		(net "UART_DEBUG_B_RX")
	)
	(segment
		(start 51.711606 -47.10049)
		(end 49.967642 -47.10049)
		(width 0.17145)
		(layer "B.Cu")
		(net "UART_DEBUG_B_RX")
	)
	(segment
		(start 49.967642 -47.10049)
		(end 48.331882 -45.46473)
		(width 0.17145)
		(layer "B.Cu")
		(net "UART_DEBUG_B_RX")
	)
	(segment
		(start 55.694326 -51.08321)
		(end 51.711606 -47.10049)
		(width 0.17145)
		(layer "B.Cu")
		(net "UART_DEBUG_B_RX")
	)
	(segment
		(start 42.496994 -20.51939)
		(end 40.8432 -18.865596)
		(width 0.17145)
		(layer "B.Cu")
		(net "UART_DEBUG_B_RX")
	)
	(segment
		(start 48.331882 -41.975532)
		(end 47.25035 -40.894)
		(width 0.17145)
		(layer "B.Cu")
		(net "UART_DEBUG_B_RX")
	)
	(segment
		(start 55.694326 -55.02529)
		(end 55.694326 -59.327542)
		(width 0.17145)
		(layer "B.Cu")
		(net "UART_DEBUG_B_RX")
	)
	(segment
		(start 55.694326 -59.327542)
		(end 51.021996 -63.999872)
		(width 0.17145)
		(layer "B.Cu")
		(net "UART_DEBUG_B_RX")
	)
	(segment
		(start 47.25035 -30.003496)
		(end 42.496994 -25.25014)
		(width 0.17145)
		(layer "B.Cu")
		(net "UART_DEBUG_B_RX")
	)
	(segment
		(start 40.8432 -18.865596)
		(end 40.8432 -18.288)
		(width 0.17145)
		(layer "B.Cu")
		(net "UART_DEBUG_B_RX")
	)
	(segment
		(start 3.2004 -44.940728)
		(end 3.00736 -45.133768)
		(width 0.17145)
		(layer "F.Cu")
		(net "UART_DEBUG_A_TX")
	)
	(segment
		(start 9.2202 -10.2362)
		(end 8.2296 -11.2268)
		(width 0.17145)
		(layer "F.Cu")
		(net "UART_DEBUG_A_TX")
	)
	(segment
		(start 7.1374 -13.1064)
		(end 8.0264 -12.2174)
		(width 0.17145)
		(layer "F.Cu")
		(net "UART_DEBUG_A_TX")
	)
	(segment
		(start 9.2202 -7.366)
		(end 9.2202 -10.2362)
		(width 0.17145)
		(layer "F.Cu")
		(net "UART_DEBUG_A_TX")
	)
	(segment
		(start 3.2004 -43.986958)
		(end 3.2004 -44.940728)
		(width 0.17145)
		(layer "F.Cu")
		(net "UART_DEBUG_A_TX")
	)
	(segment
		(start 10.65276 -6.5913)
		(end 9.9949 -6.5913)
		(width 0.17145)
		(layer "F.Cu")
		(net "UART_DEBUG_A_TX")
	)
	(segment
		(start 6.604 -13.1064)
		(end 7.1374 -13.1064)
		(width 0.17145)
		(layer "F.Cu")
		(net "UART_DEBUG_A_TX")
	)
	(segment
		(start 8.2296 -11.2268)
		(end 8.2296 -12.0142)
		(width 0.17145)
		(layer "F.Cu")
		(net "UART_DEBUG_A_TX")
	)
	(segment
		(start 8.2296 -12.0142)
		(end 8.0264 -12.2174)
		(width 0.17145)
		(layer "F.Cu")
		(net "UART_DEBUG_A_TX")
	)
	(segment
		(start 9.9949 -6.5913)
		(end 9.2202 -7.366)
		(width 0.17145)
		(layer "F.Cu")
		(net "UART_DEBUG_A_TX")
	)
	(via
		(at 3.00736 -45.133768)
		(size 0.508)
		(drill 0.254)
		(layers "F.Cu" "B.Cu")
		(net "UART_DEBUG_A_TX")
	)
	(via
		(at 8.0264 -12.2174)
		(size 0.6604)
		(drill 0.3302)
		(layers "F.Cu" "B.Cu")
		(net "UART_DEBUG_A_TX")
	)
	(via
		(at 6.604 -13.1064)
		(size 0.508)
		(drill 0.254)
		(layers "F.Cu" "B.Cu")
		(net "UART_DEBUG_A_TX")
	)
	(segment
		(start 5.142484 -58.509916)
		(end 5.142484 -59.228228)
		(width 0.17145)
		(layer "B.Cu")
		(net "UART_DEBUG_A_TX")
	)
	(segment
		(start 4.554982 -18.607532)
		(end 2.25044 -18.607532)
		(width 0.17145)
		(layer "B.Cu")
		(net "UART_DEBUG_A_TX")
	)
	(segment
		(start 6.604 -13.1064)
		(end 6.835902 -13.338302)
		(width 0.17145)
		(layer "B.Cu")
		(net "UART_DEBUG_A_TX")
	)
	(segment
		(start 2.949448 -41.711372)
		(end 2.949448 -45.075856)
		(width 0.17145)
		(layer "B.Cu")
		(net "UART_DEBUG_A_TX")
	)
	(segment
		(start 6.835902 -16.326612)
		(end 4.554982 -18.607532)
		(width 0.17145)
		(layer "B.Cu")
		(net "UART_DEBUG_A_TX")
	)
	(segment
		(start 3.541522 -40.092884)
		(end 3.541522 -41.119298)
		(width 0.17145)
		(layer "B.Cu")
		(net "UART_DEBUG_A_TX")
	)
	(segment
		(start 3.541522 -41.119298)
		(end 2.949448 -41.711372)
		(width 0.17145)
		(layer "B.Cu")
		(net "UART_DEBUG_A_TX")
	)
	(segment
		(start 5.142484 -59.228228)
		(end 5.96646 -60.052204)
		(width 0.17145)
		(layer "B.Cu")
		(net "UART_DEBUG_A_TX")
	)
	(segment
		(start 1.766824 -38.318186)
		(end 3.541522 -40.092884)
		(width 0.17145)
		(layer "B.Cu")
		(net "UART_DEBUG_A_TX")
	)
	(segment
		(start 1.766824 -19.091148)
		(end 1.766824 -38.318186)
		(width 0.17145)
		(layer "B.Cu")
		(net "UART_DEBUG_A_TX")
	)
	(segment
		(start 2.949448 -45.075856)
		(end 3.00736 -45.133768)
		(width 0.17145)
		(layer "B.Cu")
		(net "UART_DEBUG_A_TX")
	)
	(segment
		(start 7.752334 -60.052204)
		(end 9.700006 -61.999876)
		(width 0.17145)
		(layer "B.Cu")
		(net "UART_DEBUG_A_TX")
	)
	(segment
		(start 3.00736 -46.13783)
		(end 1.862074 -47.283116)
		(width 0.17145)
		(layer "B.Cu")
		(net "UART_DEBUG_A_TX")
	)
	(segment
		(start 1.862074 -55.229506)
		(end 5.142484 -58.509916)
		(width 0.17145)
		(layer "B.Cu")
		(net "UART_DEBUG_A_TX")
	)
	(segment
		(start 3.00736 -45.133768)
		(end 3.00736 -46.13783)
		(width 0.17145)
		(layer "B.Cu")
		(net "UART_DEBUG_A_TX")
	)
	(segment
		(start 1.862074 -47.283116)
		(end 1.862074 -55.229506)
		(width 0.17145)
		(layer "B.Cu")
		(net "UART_DEBUG_A_TX")
	)
	(segment
		(start 2.25044 -18.607532)
		(end 1.766824 -19.091148)
		(width 0.17145)
		(layer "B.Cu")
		(net "UART_DEBUG_A_TX")
	)
	(segment
		(start 6.835902 -13.338302)
		(end 6.835902 -16.326612)
		(width 0.17145)
		(layer "B.Cu")
		(net "UART_DEBUG_A_TX")
	)
	(segment
		(start 5.96646 -60.052204)
		(end 7.752334 -60.052204)
		(width 0.17145)
		(layer "B.Cu")
		(net "UART_DEBUG_A_TX")
	)
	(segment
		(start 13.169646 -4.152646)
		(end 12.6746 -4.152646)
		(width 0.17145)
		(layer "F.Cu")
		(net "UART_DEBUG_A_RX")
	)
	(segment
		(start 2.433574 -40.657526)
		(end 2.687066 -40.657526)
		(width 0.17145)
		(layer "F.Cu")
		(net "UART_DEBUG_A_RX")
	)
	(segment
		(start 16.51 -5.842)
		(end 16.324326 -5.656326)
		(width 0.17145)
		(layer "F.Cu")
		(net "UART_DEBUG_A_RX")
	)
	(segment
		(start 9.690354 -4.152646)
		(end 12.6746 -4.152646)
		(width 0.17145)
		(layer "F.Cu")
		(net "UART_DEBUG_A_RX")
	)
	(segment
		(start 2.687066 -40.657526)
		(end 3.2004 -41.17086)
		(width 0.17145)
		(layer "F.Cu")
		(net "UART_DEBUG_A_RX")
	)
	(segment
		(start 14.673326 -5.656326)
		(end 13.169646 -4.152646)
		(width 0.17145)
		(layer "F.Cu")
		(net "UART_DEBUG_A_RX")
	)
	(segment
		(start 16.51 -6.5405)
		(end 16.51 -5.842)
		(width 0.17145)
		(layer "F.Cu")
		(net "UART_DEBUG_A_RX")
	)
	(segment
		(start 16.324326 -5.656326)
		(end 14.673326 -5.656326)
		(width 0.17145)
		(layer "F.Cu")
		(net "UART_DEBUG_A_RX")
	)
	(segment
		(start 9.3726 -4.4704)
		(end 9.690354 -4.152646)
		(width 0.17145)
		(layer "F.Cu")
		(net "UART_DEBUG_A_RX")
	)
	(segment
		(start 3.2004 -41.17086)
		(end 3.2004 -42.539158)
		(width 0.17145)
		(layer "F.Cu")
		(net "UART_DEBUG_A_RX")
	)
	(via
		(at 9.3726 -4.4704)
		(size 0.508)
		(drill 0.254)
		(layers "F.Cu" "B.Cu")
		(net "UART_DEBUG_A_RX")
	)
	(via
		(at 2.433574 -40.657526)
		(size 0.508)
		(drill 0.254)
		(layers "F.Cu" "B.Cu")
		(net "UART_DEBUG_A_RX")
	)
	(via
		(at 12.6746 -4.152646)
		(size 0.6604)
		(drill 0.3302)
		(layers "F.Cu" "B.Cu")
		(net "UART_DEBUG_A_RX")
	)
	(segment
		(start 2.142998 -41.377108)
		(end 2.142998 -45.861478)
		(width 0.17145)
		(layer "B.Cu")
		(net "UART_DEBUG_A_RX")
	)
	(segment
		(start 2.433574 -41.086532)
		(end 2.142998 -41.377108)
		(width 0.17145)
		(layer "B.Cu")
		(net "UART_DEBUG_A_RX")
	)
	(segment
		(start 0.960374 -18.756884)
		(end 0.960374 -38.701472)
		(width 0.17145)
		(layer "B.Cu")
		(net "UART_DEBUG_A_RX")
	)
	(segment
		(start 1.055624 -46.948852)
		(end 1.055624 -56.824372)
		(width 0.17145)
		(layer "B.Cu")
		(net "UART_DEBUG_A_RX")
	)
	(segment
		(start 9.372092 -4.470908)
		(end 9.372092 -6.2484)
		(width 0.17145)
		(layer "B.Cu")
		(net "UART_DEBUG_A_RX")
	)
	(segment
		(start 1.916176 -17.801082)
		(end 0.960374 -18.756884)
		(width 0.17145)
		(layer "B.Cu")
		(net "UART_DEBUG_A_RX")
	)
	(segment
		(start 2.433574 -40.657526)
		(end 2.433574 -41.086532)
		(width 0.17145)
		(layer "B.Cu")
		(net "UART_DEBUG_A_RX")
	)
	(segment
		(start 9.371584 -9.602724)
		(end 6.029452 -12.944856)
		(width 0.17145)
		(layer "B.Cu")
		(net "UART_DEBUG_A_RX")
	)
	(segment
		(start 6.029452 -12.944856)
		(end 6.029452 -15.992094)
		(width 0.17145)
		(layer "B.Cu")
		(net "UART_DEBUG_A_RX")
	)
	(segment
		(start 9.3726 -4.4704)
		(end 9.372092 -4.470908)
		(width 0.17145)
		(layer "B.Cu")
		(net "UART_DEBUG_A_RX")
	)
	(segment
		(start 9.371584 -6.248908)
		(end 9.371584 -9.602724)
		(width 0.17145)
		(layer "B.Cu")
		(net "UART_DEBUG_A_RX")
	)
	(segment
		(start 2.142998 -45.861478)
		(end 1.055624 -46.948852)
		(width 0.17145)
		(layer "B.Cu")
		(net "UART_DEBUG_A_RX")
	)
	(segment
		(start 0.960374 -38.701472)
		(end 2.433574 -40.174672)
		(width 0.17145)
		(layer "B.Cu")
		(net "UART_DEBUG_A_RX")
	)
	(segment
		(start 1.055624 -56.824372)
		(end 6.458966 -62.227714)
		(width 0.17145)
		(layer "B.Cu")
		(net "UART_DEBUG_A_RX")
	)
	(segment
		(start 4.220464 -17.801082)
		(end 1.916176 -17.801082)
		(width 0.17145)
		(layer "B.Cu")
		(net "UART_DEBUG_A_RX")
	)
	(segment
		(start 6.029452 -15.992094)
		(end 4.220464 -17.801082)
		(width 0.17145)
		(layer "B.Cu")
		(net "UART_DEBUG_A_RX")
	)
	(segment
		(start 9.372092 -6.2484)
		(end 9.371584 -6.248908)
		(width 0.17145)
		(layer "B.Cu")
		(net "UART_DEBUG_A_RX")
	)
	(segment
		(start 2.433574 -40.174672)
		(end 2.433574 -40.657526)
		(width 0.17145)
		(layer "B.Cu")
		(net "UART_DEBUG_A_RX")
	)
	(segment
		(start 7.927848 -62.227714)
		(end 9.700006 -63.999872)
		(width 0.17145)
		(layer "B.Cu")
		(net "UART_DEBUG_A_RX")
	)
	(segment
		(start 6.458966 -62.227714)
		(end 7.927848 -62.227714)
		(width 0.17145)
		(layer "B.Cu")
		(net "UART_DEBUG_A_RX")
	)
	(segment
		(start 50.9016 -48.0822)
		(end 52.6796 -46.3042)
		(width 0.17145)
		(layer "F.Cu")
		(net "TEMP_2_SDA")
	)
	(segment
		(start 48.61814 -49.76876)
		(end 50.05324 -49.76876)
		(width 0.17145)
		(layer "F.Cu")
		(net "TEMP_2_SDA")
	)
	(segment
		(start 50.9016 -48.9204)
		(end 50.9016 -48.0822)
		(width 0.17145)
		(layer "F.Cu")
		(net "TEMP_2_SDA")
	)
	(segment
		(start 50.05324 -49.76876)
		(end 50.9016 -48.9204)
		(width 0.17145)
		(layer "F.Cu")
		(net "TEMP_2_SDA")
	)
	(segment
		(start 53.3146 -45.6692)
		(end 52.6796 -46.3042)
		(width 0.17145)
		(layer "F.Cu")
		(net "TEMP_2_SDA")
	)
	(segment
		(start 53.3146 -44.7421)
		(end 53.3146 -45.6692)
		(width 0.17145)
		(layer "F.Cu")
		(net "TEMP_2_SDA")
	)
	(via
		(at 52.6796 -46.3042)
		(size 0.6604)
		(drill 0.3302)
		(layers "F.Cu" "B.Cu")
		(net "TEMP_2_SDA")
	)
	(segment
		(start 49.8856 -48.514)
		(end 49.8856 -47.6504)
		(width 0.17145)
		(layer "F.Cu")
		(net "TEMP_2_SCL")
	)
	(segment
		(start 52.197 -44.7421)
		(end 52.197 -45.339)
		(width 0.17145)
		(layer "F.Cu")
		(net "TEMP_2_SCL")
	)
	(segment
		(start 49.28108 -49.11852)
		(end 49.8856 -48.514)
		(width 0.17145)
		(layer "F.Cu")
		(net "TEMP_2_SCL")
	)
	(segment
		(start 49.8856 -47.6504)
		(end 51.2826 -46.2534)
		(width 0.17145)
		(layer "F.Cu")
		(net "TEMP_2_SCL")
	)
	(segment
		(start 48.61814 -49.11852)
		(end 49.28108 -49.11852)
		(width 0.17145)
		(layer "F.Cu")
		(net "TEMP_2_SCL")
	)
	(segment
		(start 52.197 -45.339)
		(end 51.2826 -46.2534)
		(width 0.17145)
		(layer "F.Cu")
		(net "TEMP_2_SCL")
	)
	(via
		(at 51.2826 -46.2534)
		(size 0.6604)
		(drill 0.3302)
		(layers "F.Cu" "B.Cu")
		(net "TEMP_2_SCL")
	)
	(segment
		(start 47.661068 -48.528732)
		(end 47.72152 -48.46828)
		(width 0.17145)
		(layer "F.Cu")
		(net "TEMP_2_ALERT")
	)
	(segment
		(start 46.647862 -48.528732)
		(end 47.661068 -48.528732)
		(width 0.17145)
		(layer "F.Cu")
		(net "TEMP_2_ALERT")
	)
	(segment
		(start 47.72152 -48.46828)
		(end 48.61814 -48.46828)
		(width 0.17145)
		(layer "F.Cu")
		(net "TEMP_2_ALERT")
	)
	(segment
		(start 54.0766 -46.0502)
		(end 54.7751 -46.0502)
		(width 0.17145)
		(layer "F.Cu")
		(net "TEMP_2_A2")
	)
	(segment
		(start 52.72786 -47.81804)
		(end 52.72786 -47.39894)
		(width 0.17145)
		(layer "F.Cu")
		(net "TEMP_2_A2")
	)
	(segment
		(start 54.7751 -46.0502)
		(end 54.7751 -47.0662)
		(width 0.17145)
		(layer "F.Cu")
		(net "TEMP_2_A2")
	)
	(segment
		(start 52.72786 -47.39894)
		(end 53.8226 -46.3042)
		(width 0.17145)
		(layer "F.Cu")
		(net "TEMP_2_A2")
	)
	(segment
		(start 53.8226 -46.3042)
		(end 54.0766 -46.0502)
		(width 0.17145)
		(layer "F.Cu")
		(net "TEMP_2_A2")
	)
	(via
		(at 53.8226 -46.3042)
		(size 0.6604)
		(drill 0.3302)
		(layers "F.Cu" "B.Cu")
		(net "TEMP_2_A2")
	)
	(segment
		(start 56.6928 -48.9839)
		(end 56.4261 -48.9839)
		(width 0.17145)
		(layer "F.Cu")
		(net "TEMP_2_A1")
	)
	(segment
		(start 52.72786 -48.46828)
		(end 53.53812 -48.46828)
		(width 0.17145)
		(layer "F.Cu")
		(net "TEMP_2_A1")
	)
	(segment
		(start 55.8038 -48.3616)
		(end 54.8894 -48.3616)
		(width 0.17145)
		(layer "F.Cu")
		(net "TEMP_2_A1")
	)
	(segment
		(start 56.6928 -47.9552)
		(end 56.6928 -48.9839)
		(width 0.17145)
		(layer "F.Cu")
		(net "TEMP_2_A1")
	)
	(segment
		(start 53.53812 -48.46828)
		(end 53.6194 -48.387)
		(width 0.17145)
		(layer "F.Cu")
		(net "TEMP_2_A1")
	)
	(segment
		(start 53.6194 -48.387)
		(end 54.864 -48.387)
		(width 0.17145)
		(layer "F.Cu")
		(net "TEMP_2_A1")
	)
	(segment
		(start 56.4261 -48.9839)
		(end 55.8038 -48.3616)
		(width 0.17145)
		(layer "F.Cu")
		(net "TEMP_2_A1")
	)
	(segment
		(start 54.864 -48.387)
		(end 54.8894 -48.3616)
		(width 0.17145)
		(layer "F.Cu")
		(net "TEMP_2_A1")
	)
	(via
		(at 54.8894 -48.3616)
		(size 0.6604)
		(drill 0.3302)
		(layers "F.Cu" "B.Cu")
		(net "TEMP_2_A1")
	)
	(segment
		(start 55.507636 -51.985164)
		(end 55.507636 -51.45024)
		(width 0.17145)
		(layer "F.Cu")
		(net "TEMP_2_A0")
	)
	(segment
		(start 55.507636 -51.45024)
		(end 55.507636 -50.935636)
		(width 0.17145)
		(layer "F.Cu")
		(net "TEMP_2_A0")
	)
	(segment
		(start 54.7751 -50.2031)
		(end 54.7751 -50.1142)
		(width 0.17145)
		(layer "F.Cu")
		(net "TEMP_2_A0")
	)
	(segment
		(start 55.507636 -50.935636)
		(end 54.7751 -50.2031)
		(width 0.17145)
		(layer "F.Cu")
		(net "TEMP_2_A0")
	)
	(segment
		(start 53.93563 -49.11852)
		(end 52.72786 -49.11852)
		(width 0.17145)
		(layer "F.Cu")
		(net "TEMP_2_A0")
	)
	(segment
		(start 55.3339 -52.5018)
		(end 55.3339 -52.1589)
		(width 0.17145)
		(layer "F.Cu")
		(net "TEMP_2_A0")
	)
	(segment
		(start 55.3339 -52.1589)
		(end 55.507636 -51.985164)
		(width 0.17145)
		(layer "F.Cu")
		(net "TEMP_2_A0")
	)
	(segment
		(start 54.7751 -49.95799)
		(end 53.93563 -49.11852)
		(width 0.17145)
		(layer "F.Cu")
		(net "TEMP_2_A0")
	)
	(segment
		(start 54.7751 -50.1142)
		(end 54.7751 -49.95799)
		(width 0.17145)
		(layer "F.Cu")
		(net "TEMP_2_A0")
	)
	(via
		(at 55.507636 -51.45024)
		(size 0.6604)
		(drill 0.3302)
		(layers "F.Cu" "B.Cu")
		(net "TEMP_2_A0")
	)
	(segment
		(start 4.65836 -49.99736)
		(end 5.33654 -49.99736)
		(width 0.17145)
		(layer "F.Cu")
		(net "TEMP_1_SDA")
	)
	(segment
		(start 2.2987 -49.5935)
		(end 3.466084 -49.5935)
		(width 0.17145)
		(layer "F.Cu")
		(net "TEMP_1_SDA")
	)
	(segment
		(start 3.466084 -49.5935)
		(end 4.2545 -49.5935)
		(width 0.17145)
		(layer "F.Cu")
		(net "TEMP_1_SDA")
	)
	(segment
		(start 4.2545 -49.5935)
		(end 4.65836 -49.99736)
		(width 0.17145)
		(layer "F.Cu")
		(net "TEMP_1_SDA")
	)
	(via
		(at 3.466084 -49.5935)
		(size 0.6604)
		(drill 0.3302)
		(layers "F.Cu" "B.Cu")
		(net "TEMP_1_SDA")
	)
	(segment
		(start 6.246622 -50.650394)
		(end 3.553206 -50.650394)
		(width 0.17145)
		(layer "F.Cu")
		(net "TEMP_1_SCL")
	)
	(segment
		(start 3.553206 -50.650394)
		(end 3.0988 -51.1048)
		(width 0.17145)
		(layer "F.Cu")
		(net "TEMP_1_SCL")
	)
	(segment
		(start 5.33654 -49.34712)
		(end 6.341364 -49.34712)
		(width 0.17145)
		(layer "F.Cu")
		(net "TEMP_1_SCL")
	)
	(segment
		(start 1.8288 -51.4985)
		(end 2.7051 -51.4985)
		(width 0.17145)
		(layer "F.Cu")
		(net "TEMP_1_SCL")
	)
	(segment
		(start 6.51383 -49.519586)
		(end 6.51383 -50.383186)
		(width 0.17145)
		(layer "F.Cu")
		(net "TEMP_1_SCL")
	)
	(segment
		(start 2.7051 -51.4985)
		(end 3.0988 -51.1048)
		(width 0.17145)
		(layer "F.Cu")
		(net "TEMP_1_SCL")
	)
	(segment
		(start 6.51383 -50.383186)
		(end 6.246622 -50.650394)
		(width 0.17145)
		(layer "F.Cu")
		(net "TEMP_1_SCL")
	)
	(segment
		(start 6.341364 -49.34712)
		(end 6.51383 -49.519586)
		(width 0.17145)
		(layer "F.Cu")
		(net "TEMP_1_SCL")
	)
	(via
		(at 3.0988 -51.1048)
		(size 0.6604)
		(drill 0.3302)
		(layers "F.Cu" "B.Cu")
		(net "TEMP_1_SCL")
	)
	(segment
		(start 5.33654 -48.69688)
		(end 4.32308 -48.69688)
		(width 0.17145)
		(layer "F.Cu")
		(net "TEMP_1_ALERT")
	)
	(segment
		(start 4.32308 -48.69688)
		(end 3.3528 -47.7266)
		(width 0.17145)
		(layer "F.Cu")
		(net "TEMP_1_ALERT")
	)
	(segment
		(start 10.52068 -46.68012)
		(end 10.52068 -47.539148)
		(width 0.17145)
		(layer "F.Cu")
		(net "TEMP_1_A2")
	)
	(segment
		(start 12.2682 -44.5897)
		(end 13.3096 -44.5897)
		(width 0.17145)
		(layer "F.Cu")
		(net "TEMP_1_A2")
	)
	(segment
		(start 10.52068 -47.539148)
		(end 10.013188 -48.04664)
		(width 0.17145)
		(layer "F.Cu")
		(net "TEMP_1_A2")
	)
	(segment
		(start 10.013188 -48.04664)
		(end 9.44626 -48.04664)
		(width 0.17145)
		(layer "F.Cu")
		(net "TEMP_1_A2")
	)
	(segment
		(start 11.295634 -45.905166)
		(end 10.52068 -46.68012)
		(width 0.17145)
		(layer "F.Cu")
		(net "TEMP_1_A2")
	)
	(segment
		(start 12.2682 -45.474382)
		(end 12.115546 -45.627036)
		(width 0.17145)
		(layer "F.Cu")
		(net "TEMP_1_A2")
	)
	(segment
		(start 12.2682 -44.5897)
		(end 12.2682 -45.474382)
		(width 0.17145)
		(layer "F.Cu")
		(net "TEMP_1_A2")
	)
	(segment
		(start 12.115546 -45.627036)
		(end 11.837416 -45.905166)
		(width 0.17145)
		(layer "F.Cu")
		(net "TEMP_1_A2")
	)
	(segment
		(start 11.837416 -45.905166)
		(end 11.295634 -45.905166)
		(width 0.17145)
		(layer "F.Cu")
		(net "TEMP_1_A2")
	)
	(via
		(at 12.115546 -45.627036)
		(size 0.6604)
		(drill 0.3302)
		(layers "F.Cu" "B.Cu")
		(net "TEMP_1_A2")
	)
	(segment
		(start 12.527788 -46.618652)
		(end 12.769342 -46.377098)
		(width 0.17145)
		(layer "F.Cu")
		(net "TEMP_1_A1")
	)
	(segment
		(start 12.951714 -46.195996)
		(end 13.840968 -46.195996)
		(width 0.17145)
		(layer "F.Cu")
		(net "TEMP_1_A1")
	)
	(segment
		(start 9.44626 -48.69688)
		(end 10.44956 -48.69688)
		(width 0.17145)
		(layer "F.Cu")
		(net "TEMP_1_A1")
	)
	(segment
		(start 12.770612 -46.377098)
		(end 12.951714 -46.195996)
		(width 0.17145)
		(layer "F.Cu")
		(net "TEMP_1_A1")
	)
	(segment
		(start 11.3665 -47.071534)
		(end 11.819382 -46.618652)
		(width 0.17145)
		(layer "F.Cu")
		(net "TEMP_1_A1")
	)
	(segment
		(start 10.44956 -48.69688)
		(end 11.3665 -47.77994)
		(width 0.17145)
		(layer "F.Cu")
		(net "TEMP_1_A1")
	)
	(segment
		(start 11.819382 -46.618652)
		(end 12.527788 -46.618652)
		(width 0.17145)
		(layer "F.Cu")
		(net "TEMP_1_A1")
	)
	(segment
		(start 11.3665 -47.65294)
		(end 11.3665 -47.071534)
		(width 0.17145)
		(layer "F.Cu")
		(net "TEMP_1_A1")
	)
	(segment
		(start 11.3665 -47.77994)
		(end 11.3665 -47.65294)
		(width 0.17145)
		(layer "F.Cu")
		(net "TEMP_1_A1")
	)
	(segment
		(start 12.769342 -46.377098)
		(end 12.770612 -46.377098)
		(width 0.17145)
		(layer "F.Cu")
		(net "TEMP_1_A1")
	)
	(via
		(at 12.527788 -46.618652)
		(size 0.6604)
		(drill 0.3302)
		(layers "F.Cu" "B.Cu")
		(net "TEMP_1_A1")
	)
	(segment
		(start 11.3665 -49.68494)
		(end 10.69086 -49.68494)
		(width 0.17145)
		(layer "F.Cu")
		(net "TEMP_1_A0")
	)
	(segment
		(start 10.69086 -49.68494)
		(end 10.35304 -49.34712)
		(width 0.17145)
		(layer "F.Cu")
		(net "TEMP_1_A0")
	)
	(segment
		(start 11.3665 -48.66894)
		(end 11.3665 -49.68494)
		(width 0.17145)
		(layer "F.Cu")
		(net "TEMP_1_A0")
	)
	(segment
		(start 10.35304 -49.34712)
		(end 9.44626 -49.34712)
		(width 0.17145)
		(layer "F.Cu")
		(net "TEMP_1_A0")
	)
	(segment
		(start 43.7007 -26.6319)
		(end 43.6626 -26.67)
		(width 0.17145)
		(layer "F.Cu")
		(net "SYS_RESET_BTN_B_N")
	)
	(segment
		(start 33.995106 -1.599946)
		(end 33.995106 -2.981706)
		(width 0.17145)
		(layer "F.Cu")
		(net "SYS_RESET_BTN_B_N")
	)
	(segment
		(start 50.242724 -25.47112)
		(end 49.39284 -26.321004)
		(width 0.17145)
		(layer "F.Cu")
		(net "SYS_RESET_BTN_B_N")
	)
	(segment
		(start 45.9232 -26.6319)
		(end 43.7007 -26.6319)
		(width 0.17145)
		(layer "F.Cu")
		(net "SYS_RESET_BTN_B_N")
	)
	(segment
		(start 34.8234 -3.81)
		(end 34.8234 -3.8862)
		(width 0.17145)
		(layer "F.Cu")
		(net "SYS_RESET_BTN_B_N")
	)
	(segment
		(start 36.2458 -21.9202)
		(end 40.9956 -26.67)
		(width 0.17145)
		(layer "F.Cu")
		(net "SYS_RESET_BTN_B_N")
	)
	(segment
		(start 36.2458 -5.3086)
		(end 36.2458 -21.9202)
		(width 0.17145)
		(layer "F.Cu")
		(net "SYS_RESET_BTN_B_N")
	)
	(segment
		(start 47.702978 -26.32075)
		(end 46.682914 -26.32075)
		(width 0.17145)
		(layer "F.Cu")
		(net "SYS_RESET_BTN_B_N")
	)
	(segment
		(start 34.8234 -3.8862)
		(end 36.2458 -5.3086)
		(width 0.17145)
		(layer "F.Cu")
		(net "SYS_RESET_BTN_B_N")
	)
	(segment
		(start 46.371764 -26.6319)
		(end 45.9232 -26.6319)
		(width 0.17145)
		(layer "F.Cu")
		(net "SYS_RESET_BTN_B_N")
	)
	(segment
		(start 47.703232 -26.321004)
		(end 47.702978 -26.32075)
		(width 0.17145)
		(layer "F.Cu")
		(net "SYS_RESET_BTN_B_N")
	)
	(segment
		(start 40.9956 -26.67)
		(end 43.6626 -26.67)
		(width 0.17145)
		(layer "F.Cu")
		(net "SYS_RESET_BTN_B_N")
	)
	(segment
		(start 46.682914 -26.32075)
		(end 46.371764 -26.6319)
		(width 0.17145)
		(layer "F.Cu")
		(net "SYS_RESET_BTN_B_N")
	)
	(segment
		(start 49.39284 -26.321004)
		(end 47.703232 -26.321004)
		(width 0.17145)
		(layer "F.Cu")
		(net "SYS_RESET_BTN_B_N")
	)
	(segment
		(start 53.2257 -25.91816)
		(end 52.77866 -25.47112)
		(width 0.17145)
		(layer "F.Cu")
		(net "SYS_RESET_BTN_B_N")
	)
	(segment
		(start 33.995106 -2.981706)
		(end 34.8234 -3.81)
		(width 0.17145)
		(layer "F.Cu")
		(net "SYS_RESET_BTN_B_N")
	)
	(segment
		(start 52.77866 -25.47112)
		(end 50.242724 -25.47112)
		(width 0.17145)
		(layer "F.Cu")
		(net "SYS_RESET_BTN_B_N")
	)
	(segment
		(start 53.2257 -26.14676)
		(end 53.2257 -25.91816)
		(width 0.17145)
		(layer "F.Cu")
		(net "SYS_RESET_BTN_B_N")
	)
	(via
		(at 43.6626 -26.67)
		(size 0.6604)
		(drill 0.3302)
		(layers "F.Cu" "B.Cu")
		(net "SYS_RESET_BTN_B_N")
	)
	(segment
		(start 22.457156 -17.940274)
		(end 22.457156 -23.124922)
		(width 0.17145)
		(layer "F.Cu")
		(net "SYS_RESET_BTN_A_N")
	)
	(segment
		(start 15.0368 -26.8224)
		(end 17.5641 -26.8224)
		(width 0.17145)
		(layer "F.Cu")
		(net "SYS_RESET_BTN_A_N")
	)
	(segment
		(start 14.7955 -27.0637)
		(end 15.0368 -26.8224)
		(width 0.17145)
		(layer "F.Cu")
		(net "SYS_RESET_BTN_A_N")
	)
	(segment
		(start 15.22476 -27.41676)
		(end 14.7955 -27.41676)
		(width 0.17145)
		(layer "F.Cu")
		(net "SYS_RESET_BTN_A_N")
	)
	(segment
		(start 22.532848 -13.631672)
		(end 22.9362 -14.035024)
		(width 0.17145)
		(layer "F.Cu")
		(net "SYS_RESET_BTN_A_N")
	)
	(segment
		(start 15.389352 -29.568648)
		(end 15.7226 -29.2354)
		(width 0.17145)
		(layer "F.Cu")
		(net "SYS_RESET_BTN_A_N")
	)
	(segment
		(start 14.7955 -27.41676)
		(end 14.7955 -27.0637)
		(width 0.17145)
		(layer "F.Cu")
		(net "SYS_RESET_BTN_A_N")
	)
	(segment
		(start 15.7226 -29.2354)
		(end 15.7226 -27.9146)
		(width 0.17145)
		(layer "F.Cu")
		(net "SYS_RESET_BTN_A_N")
	)
	(segment
		(start 22.9362 -16.334486)
		(end 22.456902 -16.813784)
		(width 0.17145)
		(layer "F.Cu")
		(net "SYS_RESET_BTN_A_N")
	)
	(segment
		(start 22.9362 -14.035024)
		(end 22.9362 -16.334486)
		(width 0.17145)
		(layer "F.Cu")
		(net "SYS_RESET_BTN_A_N")
	)
	(segment
		(start 22.457156 -23.124922)
		(end 18.759678 -26.8224)
		(width 0.17145)
		(layer "F.Cu")
		(net "SYS_RESET_BTN_A_N")
	)
	(segment
		(start 22.456902 -17.94002)
		(end 22.457156 -17.940274)
		(width 0.17145)
		(layer "F.Cu")
		(net "SYS_RESET_BTN_A_N")
	)
	(segment
		(start 8.5598 -30.8737)
		(end 9.0551 -31.369)
		(width 0.17145)
		(layer "F.Cu")
		(net "SYS_RESET_BTN_A_N")
	)
	(segment
		(start 18.759678 -26.8224)
		(end 17.5641 -26.8224)
		(width 0.17145)
		(layer "F.Cu")
		(net "SYS_RESET_BTN_A_N")
	)
	(segment
		(start 14.498828 -31.683706)
		(end 15.389352 -30.793182)
		(width 0.17145)
		(layer "F.Cu")
		(net "SYS_RESET_BTN_A_N")
	)
	(segment
		(start 23.670006 -1.599946)
		(end 23.670006 -2.697226)
		(width 0.17145)
		(layer "F.Cu")
		(net "SYS_RESET_BTN_A_N")
	)
	(segment
		(start 22.532848 -4.783328)
		(end 22.532848 -13.631672)
		(width 0.17145)
		(layer "F.Cu")
		(net "SYS_RESET_BTN_A_N")
	)
	(segment
		(start 9.0551 -31.369)
		(end 13.482066 -31.369)
		(width 0.17145)
		(layer "F.Cu")
		(net "SYS_RESET_BTN_A_N")
	)
	(segment
		(start 23.5712 -2.796032)
		(end 23.5712 -3.744976)
		(width 0.17145)
		(layer "F.Cu")
		(net "SYS_RESET_BTN_A_N")
	)
	(segment
		(start 23.670006 -2.697226)
		(end 23.5712 -2.796032)
		(width 0.17145)
		(layer "F.Cu")
		(net "SYS_RESET_BTN_A_N")
	)
	(segment
		(start 22.456902 -16.813784)
		(end 22.456902 -17.94002)
		(width 0.17145)
		(layer "F.Cu")
		(net "SYS_RESET_BTN_A_N")
	)
	(segment
		(start 13.796772 -31.683706)
		(end 14.498828 -31.683706)
		(width 0.17145)
		(layer "F.Cu")
		(net "SYS_RESET_BTN_A_N")
	)
	(segment
		(start 15.389352 -30.793182)
		(end 15.389352 -29.568648)
		(width 0.17145)
		(layer "F.Cu")
		(net "SYS_RESET_BTN_A_N")
	)
	(segment
		(start 23.5712 -3.744976)
		(end 22.532848 -4.783328)
		(width 0.17145)
		(layer "F.Cu")
		(net "SYS_RESET_BTN_A_N")
	)
	(segment
		(start 13.482066 -31.369)
		(end 13.796772 -31.683706)
		(width 0.17145)
		(layer "F.Cu")
		(net "SYS_RESET_BTN_A_N")
	)
	(segment
		(start 15.7226 -27.9146)
		(end 15.22476 -27.41676)
		(width 0.17145)
		(layer "F.Cu")
		(net "SYS_RESET_BTN_A_N")
	)
	(via
		(at 17.5641 -26.8224)
		(size 0.6604)
		(drill 0.3302)
		(layers "F.Cu" "B.Cu")
		(net "SYS_RESET_BTN_A_N")
	)
	(segment
		(start 45.951394 -47.883572)
		(end 47.302166 -46.5328)
		(width 0.17145)
		(layer "F.Cu")
		(net "PWR_LED_B_N")
	)
	(segment
		(start 50.7746 -44.5516)
		(end 50.7746 -43.67403)
		(width 0.17145)
		(layer "F.Cu")
		(net "PWR_LED_B_N")
	)
	(segment
		(start 47.279052 -50.4952)
		(end 45.951394 -49.167542)
		(width 0.17145)
		(layer "F.Cu")
		(net "PWR_LED_B_N")
	)
	(segment
		(start 57.403492 -55.248302)
		(end 56.368442 -54.213252)
		(width 0.17145)
		(layer "F.Cu")
		(net "PWR_LED_B_N")
	)
	(segment
		(start 45.951394 -49.167542)
		(end 45.951394 -47.883572)
		(width 0.17145)
		(layer "F.Cu")
		(net "PWR_LED_B_N")
	)
	(segment
		(start 54.588918 -54.213252)
		(end 53.597048 -53.221382)
		(width 0.17145)
		(layer "F.Cu")
		(net "PWR_LED_B_N")
	)
	(segment
		(start 43.90009 -79.499968)
		(end 43.90009 -77.38491)
		(width 0.17145)
		(layer "F.Cu")
		(net "PWR_LED_B_N")
	)
	(segment
		(start 57.403492 -69.902578)
		(end 57.403492 -55.248302)
		(width 0.17145)
		(layer "F.Cu")
		(net "PWR_LED_B_N")
	)
	(segment
		(start 53.597048 -53.221382)
		(end 53.597048 -52.891182)
		(width 0.17145)
		(layer "F.Cu")
		(net "PWR_LED_B_N")
	)
	(segment
		(start 32.192468 -3.977132)
		(end 31.455106 -3.23977)
		(width 0.17145)
		(layer "F.Cu")
		(net "PWR_LED_B_N")
	)
	(segment
		(start 43.90009 -77.38491)
		(end 46.166532 -75.118468)
		(width 0.17145)
		(layer "F.Cu")
		(net "PWR_LED_B_N")
	)
	(segment
		(start 46.166532 -75.118468)
		(end 52.187602 -75.118468)
		(width 0.17145)
		(layer "F.Cu")
		(net "PWR_LED_B_N")
	)
	(segment
		(start 31.455106 -3.23977)
		(end 31.455106 -1.599946)
		(width 0.17145)
		(layer "F.Cu")
		(net "PWR_LED_B_N")
	)
	(segment
		(start 51.201066 -50.4952)
		(end 47.279052 -50.4952)
		(width 0.17145)
		(layer "F.Cu")
		(net "PWR_LED_B_N")
	)
	(segment
		(start 55.9308 -38.51783)
		(end 55.9308 -38.354)
		(width 0.17145)
		(layer "F.Cu")
		(net "PWR_LED_B_N")
	)
	(segment
		(start 53.597048 -52.891182)
		(end 51.201066 -50.4952)
		(width 0.17145)
		(layer "F.Cu")
		(net "PWR_LED_B_N")
	)
	(segment
		(start 52.187602 -75.118468)
		(end 57.403492 -69.902578)
		(width 0.17145)
		(layer "F.Cu")
		(net "PWR_LED_B_N")
	)
	(segment
		(start 56.368442 -54.213252)
		(end 54.588918 -54.213252)
		(width 0.17145)
		(layer "F.Cu")
		(net "PWR_LED_B_N")
	)
	(segment
		(start 47.302166 -46.5328)
		(end 48.7934 -46.5328)
		(width 0.17145)
		(layer "F.Cu")
		(net "PWR_LED_B_N")
	)
	(segment
		(start 50.7746 -43.67403)
		(end 52.517802 -41.930828)
		(width 0.17145)
		(layer "F.Cu")
		(net "PWR_LED_B_N")
	)
	(segment
		(start 52.517802 -41.930828)
		(end 55.9308 -38.51783)
		(width 0.17145)
		(layer "F.Cu")
		(net "PWR_LED_B_N")
	)
	(segment
		(start 48.7934 -46.5328)
		(end 50.7746 -44.5516)
		(width 0.17145)
		(layer "F.Cu")
		(net "PWR_LED_B_N")
	)
	(via
		(at 55.9308 -38.354)
		(size 0.508)
		(drill 0.254)
		(layers "F.Cu" "B.Cu")
		(net "PWR_LED_B_N")
	)
	(via
		(at 52.517802 -41.930828)
		(size 0.6604)
		(drill 0.3302)
		(layers "F.Cu" "B.Cu")
		(net "PWR_LED_B_N")
	)
	(via
		(at 32.192468 -3.977132)
		(size 0.508)
		(drill 0.254)
		(layers "F.Cu" "B.Cu")
		(net "PWR_LED_B_N")
	)
	(segment
		(start 32.9692 -3.2004)
		(end 32.192468 -3.977132)
		(width 0.17145)
		(layer "B.Cu")
		(net "PWR_LED_B_N")
	)
	(segment
		(start 57.531 -7.6962)
		(end 54.111652 -4.276852)
		(width 0.17145)
		(layer "B.Cu")
		(net "PWR_LED_B_N")
	)
	(segment
		(start 34.4424 -3.2004)
		(end 32.9692 -3.2004)
		(width 0.17145)
		(layer "B.Cu")
		(net "PWR_LED_B_N")
	)
	(segment
		(start 57.531 -36.7538)
		(end 57.531 -7.6962)
		(width 0.17145)
		(layer "B.Cu")
		(net "PWR_LED_B_N")
	)
	(segment
		(start 55.9308 -38.354)
		(end 57.531 -36.7538)
		(width 0.17145)
		(layer "B.Cu")
		(net "PWR_LED_B_N")
	)
	(segment
		(start 35.518852 -4.276852)
		(end 34.4424 -3.2004)
		(width 0.17145)
		(layer "B.Cu")
		(net "PWR_LED_B_N")
	)
	(segment
		(start 54.111652 -4.276852)
		(end 35.518852 -4.276852)
		(width 0.17145)
		(layer "B.Cu")
		(net "PWR_LED_B_N")
	)
	(segment
		(start 16.068802 -30.036262)
		(end 16.068802 -31.074868)
		(width 0.17145)
		(layer "F.Cu")
		(net "PWR_LED_A_N")
	)
	(segment
		(start 7.783576 -39.243)
		(end 6.49351 -40.533066)
		(width 0.17145)
		(layer "F.Cu")
		(net "PWR_LED_A_N")
	)
	(segment
		(start 14.608302 -33.444688)
		(end 14.608302 -38.853364)
		(width 0.17145)
		(layer "F.Cu")
		(net "PWR_LED_A_N")
	)
	(segment
		(start 23.212298 -6.607302)
		(end 23.212298 -13.349986)
		(width 0.17145)
		(layer "F.Cu")
		(net "PWR_LED_A_N")
	)
	(segment
		(start 6.020816 -43.343322)
		(end 6.020816 -44.897294)
		(width 0.17145)
		(layer "F.Cu")
		(net "PWR_LED_A_N")
	)
	(segment
		(start 23.136352 -17.09547)
		(end 23.136352 -17.658334)
		(width 0.17145)
		(layer "F.Cu")
		(net "PWR_LED_A_N")
	)
	(segment
		(start 17.089628 -29.015436)
		(end 16.068802 -30.036262)
		(width 0.17145)
		(layer "F.Cu")
		(net "PWR_LED_A_N")
	)
	(segment
		(start 23.136606 -17.658588)
		(end 23.136606 -23.406608)
		(width 0.17145)
		(layer "F.Cu")
		(net "PWR_LED_A_N")
	)
	(segment
		(start 8.17626 -50.241454)
		(end 8.759952 -50.825146)
		(width 0.17145)
		(layer "F.Cu")
		(net "PWR_LED_A_N")
	)
	(segment
		(start 6.390386 -73.99655)
		(end 3.199892 -77.187044)
		(width 0.17145)
		(layer "F.Cu")
		(net "PWR_LED_A_N")
	)
	(segment
		(start 23.136352 -17.658334)
		(end 23.136606 -17.658588)
		(width 0.17145)
		(layer "F.Cu")
		(net "PWR_LED_A_N")
	)
	(segment
		(start 10.126726 -51.324764)
		(end 11.618976 -51.324764)
		(width 0.17145)
		(layer "F.Cu")
		(net "PWR_LED_A_N")
	)
	(segment
		(start 8.17626 -47.052738)
		(end 8.17626 -50.241454)
		(width 0.17145)
		(layer "F.Cu")
		(net "PWR_LED_A_N")
	)
	(segment
		(start 18.044414 -28.4988)
		(end 17.606264 -28.4988)
		(width 0.17145)
		(layer "F.Cu")
		(net "PWR_LED_A_N")
	)
	(segment
		(start 6.49351 -40.533066)
		(end 6.49351 -42.870628)
		(width 0.17145)
		(layer "F.Cu")
		(net "PWR_LED_A_N")
	)
	(segment
		(start 14.918944 -69.078856)
		(end 10.00125 -73.99655)
		(width 0.17145)
		(layer "F.Cu")
		(net "PWR_LED_A_N")
	)
	(segment
		(start 11.618976 -51.324764)
		(end 14.918944 -54.624732)
		(width 0.17145)
		(layer "F.Cu")
		(net "PWR_LED_A_N")
	)
	(segment
		(start 10.00125 -73.99655)
		(end 6.390386 -73.99655)
		(width 0.17145)
		(layer "F.Cu")
		(net "PWR_LED_A_N")
	)
	(segment
		(start 16.068802 -31.074868)
		(end 14.601698 -32.541972)
		(width 0.17145)
		(layer "F.Cu")
		(net "PWR_LED_A_N")
	)
	(segment
		(start 14.601698 -32.541972)
		(end 14.601698 -33.438084)
		(width 0.17145)
		(layer "F.Cu")
		(net "PWR_LED_A_N")
	)
	(segment
		(start 14.608302 -38.853364)
		(end 13.455396 -40.00627)
		(width 0.17145)
		(layer "F.Cu")
		(net "PWR_LED_A_N")
	)
	(segment
		(start 23.212298 -13.349986)
		(end 23.6474 -13.785088)
		(width 0.17145)
		(layer "F.Cu")
		(net "PWR_LED_A_N")
	)
	(segment
		(start 25.270206 -1.599946)
		(end 25.270206 -4.549394)
		(width 0.17145)
		(layer "F.Cu")
		(net "PWR_LED_A_N")
	)
	(segment
		(start 23.136606 -23.406608)
		(end 18.044414 -28.4988)
		(width 0.17145)
		(layer "F.Cu")
		(net "PWR_LED_A_N")
	)
	(segment
		(start 17.606264 -28.4988)
		(end 17.089628 -29.015436)
		(width 0.17145)
		(layer "F.Cu")
		(net "PWR_LED_A_N")
	)
	(segment
		(start 13.455396 -40.00627)
		(end 10.849864 -40.00627)
		(width 0.17145)
		(layer "F.Cu")
		(net "PWR_LED_A_N")
	)
	(segment
		(start 10.849864 -40.00627)
		(end 10.086594 -39.243)
		(width 0.17145)
		(layer "F.Cu")
		(net "PWR_LED_A_N")
	)
	(segment
		(start 23.6474 -13.785088)
		(end 23.6474 -16.584422)
		(width 0.17145)
		(layer "F.Cu")
		(net "PWR_LED_A_N")
	)
	(segment
		(start 9.627108 -50.825146)
		(end 10.126726 -51.324764)
		(width 0.17145)
		(layer "F.Cu")
		(net "PWR_LED_A_N")
	)
	(segment
		(start 14.918944 -54.624732)
		(end 14.918944 -69.078856)
		(width 0.17145)
		(layer "F.Cu")
		(net "PWR_LED_A_N")
	)
	(segment
		(start 3.199892 -77.187044)
		(end 3.199892 -79.499968)
		(width 0.17145)
		(layer "F.Cu")
		(net "PWR_LED_A_N")
	)
	(segment
		(start 8.759952 -50.825146)
		(end 9.627108 -50.825146)
		(width 0.17145)
		(layer "F.Cu")
		(net "PWR_LED_A_N")
	)
	(segment
		(start 25.270206 -4.549394)
		(end 23.212298 -6.607302)
		(width 0.17145)
		(layer "F.Cu")
		(net "PWR_LED_A_N")
	)
	(segment
		(start 23.6474 -16.584422)
		(end 23.136352 -17.09547)
		(width 0.17145)
		(layer "F.Cu")
		(net "PWR_LED_A_N")
	)
	(segment
		(start 14.601698 -33.438084)
		(end 14.608302 -33.444688)
		(width 0.17145)
		(layer "F.Cu")
		(net "PWR_LED_A_N")
	)
	(segment
		(start 6.49351 -42.870628)
		(end 6.020816 -43.343322)
		(width 0.17145)
		(layer "F.Cu")
		(net "PWR_LED_A_N")
	)
	(segment
		(start 10.086594 -39.243)
		(end 7.783576 -39.243)
		(width 0.17145)
		(layer "F.Cu")
		(net "PWR_LED_A_N")
	)
	(segment
		(start 6.020816 -44.897294)
		(end 8.17626 -47.052738)
		(width 0.17145)
		(layer "F.Cu")
		(net "PWR_LED_A_N")
	)
	(via
		(at 17.089628 -29.015436)
		(size 0.6604)
		(drill 0.3302)
		(layers "F.Cu" "B.Cu")
		(net "PWR_LED_A_N")
	)
	(segment
		(start 48.90008 -76.999846)
		(end 48.90008 -78.016354)
		(width 0.508)
		(layer "F.Cu")
		(net "PWR_BTN_B_CONN")
	)
	(segment
		(start 47.883572 -76.999846)
		(end 48.90008 -76.999846)
		(width 0.508)
		(layer "F.Cu")
		(net "PWR_BTN_B_CONN")
	)
	(segment
		(start 48.90008 -75.983338)
		(end 48.90008 -76.999846)
		(width 0.508)
		(layer "F.Cu")
		(net "PWR_BTN_B_CONN")
	)
	(segment
		(start 47.883572 -82.00009)
		(end 48.90008 -82.00009)
		(width 0.508)
		(layer "F.Cu")
		(net "PWR_BTN_B_CONN")
	)
	(segment
		(start 48.90008 -76.999846)
		(end 49.916588 -76.999846)
		(width 0.508)
		(layer "F.Cu")
		(net "PWR_BTN_B_CONN")
	)
	(segment
		(start 48.90008 -82.00009)
		(end 48.90008 -83.016598)
		(width 0.508)
		(layer "F.Cu")
		(net "PWR_BTN_B_CONN")
	)
	(segment
		(start 48.90008 -80.983582)
		(end 48.90008 -82.00009)
		(width 0.508)
		(layer "F.Cu")
		(net "PWR_BTN_B_CONN")
	)
	(segment
		(start 48.90008 -82.00009)
		(end 49.916588 -82.00009)
		(width 0.508)
		(layer "F.Cu")
		(net "PWR_BTN_B_CONN")
	)
	(segment
		(start 8.199882 -75.983338)
		(end 8.199882 -76.999846)
		(width 0.508)
		(layer "F.Cu")
		(net "PWR_BTN_A_CONN")
	)
	(segment
		(start 8.199882 -80.983582)
		(end 8.199882 -82.00009)
		(width 0.508)
		(layer "F.Cu")
		(net "PWR_BTN_A_CONN")
	)
	(segment
		(start 8.199882 -82.00009)
		(end 9.21639 -82.00009)
		(width 0.508)
		(layer "F.Cu")
		(net "PWR_BTN_A_CONN")
	)
	(segment
		(start 8.199882 -82.00009)
		(end 8.199882 -83.016598)
		(width 0.508)
		(layer "F.Cu")
		(net "PWR_BTN_A_CONN")
	)
	(segment
		(start 7.183374 -76.999846)
		(end 8.199882 -76.999846)
		(width 0.508)
		(layer "F.Cu")
		(net "PWR_BTN_A_CONN")
	)
	(segment
		(start 8.199882 -76.999846)
		(end 9.21639 -76.999846)
		(width 0.508)
		(layer "F.Cu")
		(net "PWR_BTN_A_CONN")
	)
	(segment
		(start 8.199882 -76.999846)
		(end 8.199882 -78.016354)
		(width 0.508)
		(layer "F.Cu")
		(net "PWR_BTN_A_CONN")
	)
	(segment
		(start 7.183374 -82.00009)
		(end 8.199882 -82.00009)
		(width 0.508)
		(layer "F.Cu")
		(net "PWR_BTN_A_CONN")
	)
	(segment
		(start 21.777706 -18.22196)
		(end 21.777706 -22.843236)
		(width 0.17145)
		(layer "F.Cu")
		(net "I2C_DPB_A_SDA")
	)
	(segment
		(start 2.2987 -48.7045)
		(end 2.245106 -48.650906)
		(width 0.17145)
		(layer "F.Cu")
		(net "I2C_DPB_A_SDA")
	)
	(segment
		(start 22.87016 -1.599946)
		(end 22.87016 -3.48488)
		(width 0.17145)
		(layer "F.Cu")
		(net "I2C_DPB_A_SDA")
	)
	(segment
		(start 21.777452 -16.532098)
		(end 21.777452 -18.221706)
		(width 0.17145)
		(layer "F.Cu")
		(net "I2C_DPB_A_SDA")
	)
	(segment
		(start 21.853398 -13.349986)
		(end 21.853144 -13.35024)
		(width 0.17145)
		(layer "F.Cu")
		(net "I2C_DPB_A_SDA")
	)
	(segment
		(start 2.740152 -24.871426)
		(end 8.261604 -24.871426)
		(width 0.17145)
		(layer "F.Cu")
		(net "I2C_DPB_A_SDA")
	)
	(segment
		(start 21.777706 -22.843236)
		(end 18.712942 -25.908)
		(width 0.17145)
		(layer "F.Cu")
		(net "I2C_DPB_A_SDA")
	)
	(segment
		(start 2.245106 -46.72203)
		(end 1.628902 -46.105826)
		(width 0.17145)
		(layer "F.Cu")
		(net "I2C_DPB_A_SDA")
	)
	(segment
		(start 8.261604 -24.871426)
		(end 9.531858 -26.14168)
		(width 0.17145)
		(layer "F.Cu")
		(net "I2C_DPB_A_SDA")
	)
	(segment
		(start 22.225 -16.08455)
		(end 21.777452 -16.532098)
		(width 0.17145)
		(layer "F.Cu")
		(net "I2C_DPB_A_SDA")
	)
	(segment
		(start 22.225 -14.28496)
		(end 22.225 -16.08455)
		(width 0.17145)
		(layer "F.Cu")
		(net "I2C_DPB_A_SDA")
	)
	(segment
		(start 18.712942 -25.908)
		(end 14.478 -25.908)
		(width 0.17145)
		(layer "F.Cu")
		(net "I2C_DPB_A_SDA")
	)
	(segment
		(start 1.628902 -25.982676)
		(end 2.740152 -24.871426)
		(width 0.17145)
		(layer "F.Cu")
		(net "I2C_DPB_A_SDA")
	)
	(segment
		(start 21.853398 -4.501642)
		(end 21.853398 -13.349986)
		(width 0.17145)
		(layer "F.Cu")
		(net "I2C_DPB_A_SDA")
	)
	(segment
		(start 2.245106 -48.650906)
		(end 2.245106 -46.72203)
		(width 0.17145)
		(layer "F.Cu")
		(net "I2C_DPB_A_SDA")
	)
	(segment
		(start 22.87016 -3.48488)
		(end 21.853398 -4.501642)
		(width 0.17145)
		(layer "F.Cu")
		(net "I2C_DPB_A_SDA")
	)
	(segment
		(start 14.478 -25.908)
		(end 14.24305 -26.14295)
		(width 0.17145)
		(layer "F.Cu")
		(net "I2C_DPB_A_SDA")
	)
	(segment
		(start 14.24305 -26.14295)
		(end 11.511026 -26.14295)
		(width 0.17145)
		(layer "F.Cu")
		(net "I2C_DPB_A_SDA")
	)
	(segment
		(start 9.531858 -26.14168)
		(end 11.509756 -26.14168)
		(width 0.17145)
		(layer "F.Cu")
		(net "I2C_DPB_A_SDA")
	)
	(segment
		(start 11.511026 -26.14295)
		(end 11.509756 -26.14168)
		(width 0.17145)
		(layer "F.Cu")
		(net "I2C_DPB_A_SDA")
	)
	(segment
		(start 21.777452 -18.221706)
		(end 21.777706 -18.22196)
		(width 0.17145)
		(layer "F.Cu")
		(net "I2C_DPB_A_SDA")
	)
	(segment
		(start 1.628902 -46.105826)
		(end 1.628902 -25.982676)
		(width 0.17145)
		(layer "F.Cu")
		(net "I2C_DPB_A_SDA")
	)
	(segment
		(start 21.853144 -13.35024)
		(end 21.853144 -13.913104)
		(width 0.17145)
		(layer "F.Cu")
		(net "I2C_DPB_A_SDA")
	)
	(segment
		(start 21.853144 -13.913104)
		(end 22.225 -14.28496)
		(width 0.17145)
		(layer "F.Cu")
		(net "I2C_DPB_A_SDA")
	)
	(via
		(at 11.509756 -26.14168)
		(size 0.6604)
		(drill 0.3302)
		(layers "F.Cu" "B.Cu")
		(net "I2C_DPB_A_SDA")
	)
	(segment
		(start 9.44753 -25.096216)
		(end 18.56359 -25.096216)
		(width 0.17145)
		(layer "F.Cu")
		(net "I2C_DPB_A_SCL")
	)
	(segment
		(start 21.173694 -13.068554)
		(end 21.173948 -13.0683)
		(width 0.17145)
		(layer "F.Cu")
		(net "I2C_DPB_A_SCL")
	)
	(segment
		(start 21.5265 -14.69517)
		(end 21.173948 -14.342618)
		(width 0.17145)
		(layer "F.Cu")
		(net "I2C_DPB_A_SCL")
	)
	(segment
		(start 6.868668 -24.171148)
		(end 8.522462 -24.171148)
		(width 0.17145)
		(layer "F.Cu")
		(net "I2C_DPB_A_SCL")
	)
	(segment
		(start 21.173694 -14.19479)
		(end 21.173694 -13.068554)
		(width 0.17145)
		(layer "F.Cu")
		(net "I2C_DPB_A_SCL")
	)
	(segment
		(start 21.098256 -18.503646)
		(end 21.098002 -18.503392)
		(width 0.17145)
		(layer "F.Cu")
		(net "I2C_DPB_A_SCL")
	)
	(segment
		(start 22.07006 -3.323844)
		(end 22.07006 -1.599946)
		(width 0.17145)
		(layer "F.Cu")
		(net "I2C_DPB_A_SCL")
	)
	(segment
		(start 1.1176 -46.8884)
		(end 0.949452 -46.720252)
		(width 0.17145)
		(layer "F.Cu")
		(net "I2C_DPB_A_SCL")
	)
	(segment
		(start 21.098256 -22.56155)
		(end 21.098256 -18.503646)
		(width 0.17145)
		(layer "F.Cu")
		(net "I2C_DPB_A_SCL")
	)
	(segment
		(start 8.522462 -24.171148)
		(end 9.44753 -25.096216)
		(width 0.17145)
		(layer "F.Cu")
		(net "I2C_DPB_A_SCL")
	)
	(segment
		(start 21.173948 -13.0683)
		(end 21.173948 -4.219956)
		(width 0.17145)
		(layer "F.Cu")
		(net "I2C_DPB_A_SCL")
	)
	(segment
		(start 21.173948 -14.195044)
		(end 21.173694 -14.19479)
		(width 0.17145)
		(layer "F.Cu")
		(net "I2C_DPB_A_SCL")
	)
	(segment
		(start 21.173948 -4.219956)
		(end 22.07006 -3.323844)
		(width 0.17145)
		(layer "F.Cu")
		(net "I2C_DPB_A_SCL")
	)
	(segment
		(start 21.098002 -18.503392)
		(end 21.098002 -16.18488)
		(width 0.17145)
		(layer "F.Cu")
		(net "I2C_DPB_A_SCL")
	)
	(segment
		(start 2.479294 -24.171148)
		(end 6.868668 -24.171148)
		(width 0.17145)
		(layer "F.Cu")
		(net "I2C_DPB_A_SCL")
	)
	(segment
		(start 18.56359 -25.096216)
		(end 21.098256 -22.56155)
		(width 0.17145)
		(layer "F.Cu")
		(net "I2C_DPB_A_SCL")
	)
	(segment
		(start 0.949452 -25.70099)
		(end 2.479294 -24.171148)
		(width 0.17145)
		(layer "F.Cu")
		(net "I2C_DPB_A_SCL")
	)
	(segment
		(start 21.098002 -16.18488)
		(end 21.5265 -15.756382)
		(width 0.17145)
		(layer "F.Cu")
		(net "I2C_DPB_A_SCL")
	)
	(segment
		(start 21.5265 -15.756382)
		(end 21.5265 -14.69517)
		(width 0.17145)
		(layer "F.Cu")
		(net "I2C_DPB_A_SCL")
	)
	(segment
		(start 21.173948 -14.342618)
		(end 21.173948 -14.195044)
		(width 0.17145)
		(layer "F.Cu")
		(net "I2C_DPB_A_SCL")
	)
	(segment
		(start 1.1176 -49.8983)
		(end 1.1176 -46.8884)
		(width 0.17145)
		(layer "F.Cu")
		(net "I2C_DPB_A_SCL")
	)
	(segment
		(start 0.949452 -46.720252)
		(end 0.949452 -25.70099)
		(width 0.17145)
		(layer "F.Cu")
		(net "I2C_DPB_A_SCL")
	)
	(segment
		(start 1.8288 -50.6095)
		(end 1.1176 -49.8983)
		(width 0.17145)
		(layer "F.Cu")
		(net "I2C_DPB_A_SCL")
	)
	(via
		(at 6.868668 -24.171148)
		(size 0.6604)
		(drill 0.3302)
		(layers "F.Cu" "B.Cu")
		(net "I2C_DPB_A_SCL")
	)
	(segment
		(start 51.400456 -15.934944)
		(end 51.400456 -14.697456)
		(width 0.17145)
		(layer "F.Cu")
		(net "I2C_DEBUG_B_SDA_R")
	)
	(segment
		(start 51.181 -13.2715)
		(end 51.181 -14.478)
		(width 0.17145)
		(layer "F.Cu")
		(net "I2C_DEBUG_B_SDA_R")
	)
	(segment
		(start 51.400456 -14.697456)
		(end 51.2064 -14.5034)
		(width 0.17145)
		(layer "F.Cu")
		(net "I2C_DEBUG_B_SDA_R")
	)
	(segment
		(start 50.3936 -16.25092)
		(end 51.08448 -16.25092)
		(width 0.17145)
		(layer "F.Cu")
		(net "I2C_DEBUG_B_SDA_R")
	)
	(segment
		(start 51.181 -14.478)
		(end 51.2064 -14.5034)
		(width 0.17145)
		(layer "F.Cu")
		(net "I2C_DEBUG_B_SDA_R")
	)
	(segment
		(start 51.08448 -16.25092)
		(end 51.400456 -15.934944)
		(width 0.17145)
		(layer "F.Cu")
		(net "I2C_DEBUG_B_SDA_R")
	)
	(via
		(at 51.2064 -14.5034)
		(size 0.6604)
		(drill 0.3302)
		(layers "F.Cu" "B.Cu")
		(net "I2C_DEBUG_B_SDA_R")
	)
	(segment
		(start 42.647616 -17.814544)
		(end 41.30294 -19.15922)
		(width 0.17145)
		(layer "F.Cu")
		(net "I2C_DEBUG_B_SDA")
	)
	(segment
		(start 40.865552 -19.596608)
		(end 41.30294 -19.15922)
		(width 0.17145)
		(layer "F.Cu")
		(net "I2C_DEBUG_B_SDA")
	)
	(segment
		(start 39.850314 -20.162012)
		(end 40.415718 -19.596608)
		(width 0.17145)
		(layer "F.Cu")
		(net "I2C_DEBUG_B_SDA")
	)
	(segment
		(start 44.3484 -19.21764)
		(end 44.3484 -18.9484)
		(width 0.17145)
		(layer "F.Cu")
		(net "I2C_DEBUG_B_SDA")
	)
	(segment
		(start 53.893974 -56.900064)
		(end 54.318408 -56.47563)
		(width 0.17145)
		(layer "F.Cu")
		(net "I2C_DEBUG_B_SDA")
	)
	(segment
		(start 40.415718 -19.596608)
		(end 40.865552 -19.596608)
		(width 0.17145)
		(layer "F.Cu")
		(net "I2C_DEBUG_B_SDA")
	)
	(segment
		(start 43.574462 -18.662396)
		(end 43.036998 -18.124932)
		(width 0.17145)
		(layer "F.Cu")
		(net "I2C_DEBUG_B_SDA")
	)
	(segment
		(start 43.036998 -18.124932)
		(end 43.036998 -17.814544)
		(width 0.17145)
		(layer "F.Cu")
		(net "I2C_DEBUG_B_SDA")
	)
	(segment
		(start 44.3484 -18.9484)
		(end 44.062396 -18.662396)
		(width 0.17145)
		(layer "F.Cu")
		(net "I2C_DEBUG_B_SDA")
	)
	(segment
		(start 43.036998 -17.814544)
		(end 42.647616 -17.814544)
		(width 0.17145)
		(layer "F.Cu")
		(net "I2C_DEBUG_B_SDA")
	)
	(segment
		(start 44.062396 -18.662396)
		(end 43.574462 -18.662396)
		(width 0.17145)
		(layer "F.Cu")
		(net "I2C_DEBUG_B_SDA")
	)
	(segment
		(start 52.7685 -56.900064)
		(end 53.893974 -56.900064)
		(width 0.17145)
		(layer "F.Cu")
		(net "I2C_DEBUG_B_SDA")
	)
	(segment
		(start 54.318408 -56.47563)
		(end 54.318408 -56.19242)
		(width 0.17145)
		(layer "F.Cu")
		(net "I2C_DEBUG_B_SDA")
	)
	(via
		(at 41.30294 -19.15922)
		(size 0.6604)
		(drill 0.3302)
		(layers "F.Cu" "B.Cu")
		(net "I2C_DEBUG_B_SDA")
	)
	(via
		(at 52.7685 -56.900064)
		(size 0.508)
		(drill 0.254)
		(layers "F.Cu" "B.Cu")
		(net "I2C_DEBUG_B_SDA")
	)
	(via
		(at 39.850314 -20.162012)
		(size 0.508)
		(drill 0.254)
		(layers "F.Cu" "B.Cu")
		(net "I2C_DEBUG_B_SDA")
	)
	(segment
		(start 39.35349 -20.658836)
		(end 39.35349 -26.44902)
		(width 0.17145)
		(layer "B.Cu")
		(net "I2C_DEBUG_B_SDA")
	)
	(segment
		(start 43.617388 -48.176942)
		(end 45.547534 -50.107088)
		(width 0.17145)
		(layer "B.Cu")
		(net "I2C_DEBUG_B_SDA")
	)
	(segment
		(start 52.535074 -56.666638)
		(end 52.7685 -56.900064)
		(width 0.17145)
		(layer "B.Cu")
		(net "I2C_DEBUG_B_SDA")
	)
	(segment
		(start 39.35349 -26.44902)
		(end 43.617388 -30.712918)
		(width 0.17145)
		(layer "B.Cu")
		(net "I2C_DEBUG_B_SDA")
	)
	(segment
		(start 43.617388 -30.712918)
		(end 43.617388 -48.176942)
		(width 0.17145)
		(layer "B.Cu")
		(net "I2C_DEBUG_B_SDA")
	)
	(segment
		(start 45.547534 -50.107088)
		(end 49.985422 -50.107088)
		(width 0.17145)
		(layer "B.Cu")
		(net "I2C_DEBUG_B_SDA")
	)
	(segment
		(start 49.985422 -50.107088)
		(end 52.535074 -52.65674)
		(width 0.17145)
		(layer "B.Cu")
		(net "I2C_DEBUG_B_SDA")
	)
	(segment
		(start 50.400204 -57.999884)
		(end 51.66868 -57.999884)
		(width 0.17145)
		(layer "B.Cu")
		(net "I2C_DEBUG_B_SDA")
	)
	(segment
		(start 52.535074 -52.65674)
		(end 52.535074 -56.666638)
		(width 0.17145)
		(layer "B.Cu")
		(net "I2C_DEBUG_B_SDA")
	)
	(segment
		(start 39.850314 -20.162012)
		(end 39.35349 -20.658836)
		(width 0.17145)
		(layer "B.Cu")
		(net "I2C_DEBUG_B_SDA")
	)
	(segment
		(start 51.66868 -57.999884)
		(end 52.7685 -56.900064)
		(width 0.17145)
		(layer "B.Cu")
		(net "I2C_DEBUG_B_SDA")
	)
	(segment
		(start 52.3494 -16.256)
		(end 52.3494 -14.3002)
		(width 0.17145)
		(layer "F.Cu")
		(net "I2C_DEBUG_B_SCL_R")
	)
	(segment
		(start 52.3494 -14.3002)
		(end 52.2478 -14.1986)
		(width 0.17145)
		(layer "F.Cu")
		(net "I2C_DEBUG_B_SCL_R")
	)
	(segment
		(start 52.197 -14.1478)
		(end 52.2478 -14.1986)
		(width 0.17145)
		(layer "F.Cu")
		(net "I2C_DEBUG_B_SCL_R")
	)
	(segment
		(start 51.70424 -16.90116)
		(end 52.3494 -16.256)
		(width 0.17145)
		(layer "F.Cu")
		(net "I2C_DEBUG_B_SCL_R")
	)
	(segment
		(start 52.197 -13.2715)
		(end 52.197 -14.1478)
		(width 0.17145)
		(layer "F.Cu")
		(net "I2C_DEBUG_B_SCL_R")
	)
	(segment
		(start 50.3936 -16.90116)
		(end 51.70424 -16.90116)
		(width 0.17145)
		(layer "F.Cu")
		(net "I2C_DEBUG_B_SCL_R")
	)
	(via
		(at 52.2478 -14.1986)
		(size 0.6604)
		(drill 0.3302)
		(layers "F.Cu" "B.Cu")
		(net "I2C_DEBUG_B_SCL_R")
	)
	(segment
		(start 41.780714 -20.851114)
		(end 41.8338 -20.9042)
		(width 0.17145)
		(layer "F.Cu")
		(net "I2C_DEBUG_B_SCL")
	)
	(segment
		(start 40.566594 -20.851114)
		(end 41.780714 -20.851114)
		(width 0.17145)
		(layer "F.Cu")
		(net "I2C_DEBUG_B_SCL")
	)
	(segment
		(start 42.128694 -19.294602)
		(end 41.8338 -19.589496)
		(width 0.17145)
		(layer "F.Cu")
		(net "I2C_DEBUG_B_SCL")
	)
	(segment
		(start 43.173142 -19.558)
		(end 42.909744 -19.294602)
		(width 0.17145)
		(layer "F.Cu")
		(net "I2C_DEBUG_B_SCL")
	)
	(segment
		(start 44.3484 -19.86788)
		(end 43.75785 -19.86788)
		(width 0.17145)
		(layer "F.Cu")
		(net "I2C_DEBUG_B_SCL")
	)
	(segment
		(start 53.214524 -58.41746)
		(end 53.85562 -58.41746)
		(width 0.17145)
		(layer "F.Cu")
		(net "I2C_DEBUG_B_SCL")
	)
	(segment
		(start 43.75785 -19.86788)
		(end 43.44797 -19.558)
		(width 0.17145)
		(layer "F.Cu")
		(net "I2C_DEBUG_B_SCL")
	)
	(segment
		(start 42.909744 -19.294602)
		(end 42.128694 -19.294602)
		(width 0.17145)
		(layer "F.Cu")
		(net "I2C_DEBUG_B_SCL")
	)
	(segment
		(start 53.85562 -58.41746)
		(end 54.318408 -57.954672)
		(width 0.17145)
		(layer "F.Cu")
		(net "I2C_DEBUG_B_SCL")
	)
	(segment
		(start 41.8338 -19.589496)
		(end 41.8338 -20.9042)
		(width 0.17145)
		(layer "F.Cu")
		(net "I2C_DEBUG_B_SCL")
	)
	(segment
		(start 43.44797 -19.558)
		(end 43.173142 -19.558)
		(width 0.17145)
		(layer "F.Cu")
		(net "I2C_DEBUG_B_SCL")
	)
	(segment
		(start 54.318408 -57.954672)
		(end 54.318408 -57.64022)
		(width 0.17145)
		(layer "F.Cu")
		(net "I2C_DEBUG_B_SCL")
	)
	(via
		(at 53.214524 -58.41746)
		(size 0.508)
		(drill 0.254)
		(layers "F.Cu" "B.Cu")
		(net "I2C_DEBUG_B_SCL")
	)
	(via
		(at 41.8338 -20.9042)
		(size 0.6604)
		(drill 0.3302)
		(layers "F.Cu" "B.Cu")
		(net "I2C_DEBUG_B_SCL")
	)
	(via
		(at 40.566594 -20.851114)
		(size 0.508)
		(drill 0.254)
		(layers "F.Cu" "B.Cu")
		(net "I2C_DEBUG_B_SCL")
	)
	(segment
		(start 40.566594 -20.851114)
		(end 40.06977 -21.347938)
		(width 0.17145)
		(layer "B.Cu")
		(net "I2C_DEBUG_B_SCL")
	)
	(segment
		(start 44.296838 -30.431232)
		(end 44.296838 -47.72152)
		(width 0.17145)
		(layer "B.Cu")
		(net "I2C_DEBUG_B_SCL")
	)
	(segment
		(start 49.09312 -58.052208)
		(end 50.018442 -58.97753)
		(width 0.17145)
		(layer "B.Cu")
		(net "I2C_DEBUG_B_SCL")
	)
	(segment
		(start 53.349652 -56.52008)
		(end 53.349652 -58.282332)
		(width 0.17145)
		(layer "B.Cu")
		(net "I2C_DEBUG_B_SCL")
	)
	(segment
		(start 52.654454 -58.97753)
		(end 53.214524 -58.41746)
		(width 0.17145)
		(layer "B.Cu")
		(net "I2C_DEBUG_B_SCL")
	)
	(segment
		(start 53.214524 -52.375054)
		(end 53.214524 -56.384952)
		(width 0.17145)
		(layer "B.Cu")
		(net "I2C_DEBUG_B_SCL")
	)
	(segment
		(start 44.296838 -47.72152)
		(end 45.968158 -49.39284)
		(width 0.17145)
		(layer "B.Cu")
		(net "I2C_DEBUG_B_SCL")
	)
	(segment
		(start 50.23231 -49.39284)
		(end 53.214524 -52.375054)
		(width 0.17145)
		(layer "B.Cu")
		(net "I2C_DEBUG_B_SCL")
	)
	(segment
		(start 50.018442 -58.97753)
		(end 52.654454 -58.97753)
		(width 0.17145)
		(layer "B.Cu")
		(net "I2C_DEBUG_B_SCL")
	)
	(segment
		(start 40.06977 -21.347938)
		(end 40.06977 -26.204164)
		(width 0.17145)
		(layer "B.Cu")
		(net "I2C_DEBUG_B_SCL")
	)
	(segment
		(start 49.09312 -57.306972)
		(end 49.09312 -58.052208)
		(width 0.17145)
		(layer "B.Cu")
		(net "I2C_DEBUG_B_SCL")
	)
	(segment
		(start 50.400204 -55.999888)
		(end 49.09312 -57.306972)
		(width 0.17145)
		(layer "B.Cu")
		(net "I2C_DEBUG_B_SCL")
	)
	(segment
		(start 53.349652 -58.282332)
		(end 53.214524 -58.41746)
		(width 0.17145)
		(layer "B.Cu")
		(net "I2C_DEBUG_B_SCL")
	)
	(segment
		(start 40.06977 -26.204164)
		(end 44.296838 -30.431232)
		(width 0.17145)
		(layer "B.Cu")
		(net "I2C_DEBUG_B_SCL")
	)
	(segment
		(start 53.214524 -56.384952)
		(end 53.349652 -56.52008)
		(width 0.17145)
		(layer "B.Cu")
		(net "I2C_DEBUG_B_SCL")
	)
	(segment
		(start 45.968158 -49.39284)
		(end 50.23231 -49.39284)
		(width 0.17145)
		(layer "B.Cu")
		(net "I2C_DEBUG_B_SCL")
	)
	(segment
		(start 12.0142 -17.26692)
		(end 11.32332 -17.26692)
		(width 0.17145)
		(layer "F.Cu")
		(net "I2C_DEBUG_A_SDA_R")
	)
	(segment
		(start 11.32332 -17.26692)
		(end 11.039348 -16.982948)
		(width 0.17145)
		(layer "F.Cu")
		(net "I2C_DEBUG_A_SDA_R")
	)
	(segment
		(start 9.3853 -15.9004)
		(end 10.4902 -15.9004)
		(width 0.17145)
		(layer "F.Cu")
		(net "I2C_DEBUG_A_SDA_R")
	)
	(segment
		(start 11.039348 -16.449548)
		(end 10.4902 -15.9004)
		(width 0.17145)
		(layer "F.Cu")
		(net "I2C_DEBUG_A_SDA_R")
	)
	(segment
		(start 11.039348 -16.982948)
		(end 11.039348 -16.449548)
		(width 0.17145)
		(layer "F.Cu")
		(net "I2C_DEBUG_A_SDA_R")
	)
	(via
		(at 10.4902 -15.9004)
		(size 0.6604)
		(drill 0.3302)
		(layers "F.Cu" "B.Cu")
		(net "I2C_DEBUG_A_SDA_R")
	)
	(segment
		(start 5.4864 -19.068034)
		(end 5.11937 -18.701004)
		(width 0.17145)
		(layer "F.Cu")
		(net "I2C_DEBUG_A_SDA")
	)
	(segment
		(start 5.11937 -18.701004)
		(end 4.108196 -18.701004)
		(width 0.17145)
		(layer "F.Cu")
		(net "I2C_DEBUG_A_SDA")
	)
	(segment
		(start 5.4864 -19.47164)
		(end 5.4864 -19.068034)
		(width 0.17145)
		(layer "F.Cu")
		(net "I2C_DEBUG_A_SDA")
	)
	(segment
		(start 3.0734 -19.6215)
		(end 2.286 -19.6215)
		(width 0.17145)
		(layer "F.Cu")
		(net "I2C_DEBUG_A_SDA")
	)
	(segment
		(start 3.993896 -18.701004)
		(end 3.0734 -19.6215)
		(width 0.17145)
		(layer "F.Cu")
		(net "I2C_DEBUG_A_SDA")
	)
	(segment
		(start 4.200652 -42.204132)
		(end 4.90601 -41.498774)
		(width 0.17145)
		(layer "F.Cu")
		(net "I2C_DEBUG_A_SDA")
	)
	(segment
		(start 4.90601 -41.498774)
		(end 5.216906 -41.498774)
		(width 0.17145)
		(layer "F.Cu")
		(net "I2C_DEBUG_A_SDA")
	)
	(segment
		(start 4.200652 -42.539158)
		(end 4.200652 -42.204132)
		(width 0.17145)
		(layer "F.Cu")
		(net "I2C_DEBUG_A_SDA")
	)
	(segment
		(start 4.108196 -18.701004)
		(end 3.993896 -18.701004)
		(width 0.17145)
		(layer "F.Cu")
		(net "I2C_DEBUG_A_SDA")
	)
	(via
		(at 2.286 -19.6215)
		(size 0.508)
		(drill 0.254)
		(layers "F.Cu" "B.Cu")
		(net "I2C_DEBUG_A_SDA")
	)
	(via
		(at 4.108196 -18.701004)
		(size 0.6604)
		(drill 0.3302)
		(layers "F.Cu" "B.Cu")
		(net "I2C_DEBUG_A_SDA")
	)
	(via
		(at 5.216906 -41.498774)
		(size 0.508)
		(drill 0.254)
		(layers "F.Cu" "B.Cu")
		(net "I2C_DEBUG_A_SDA")
	)
	(segment
		(start 3.347974 -47.899066)
		(end 5.299964 -45.947076)
		(width 0.17145)
		(layer "B.Cu")
		(net "I2C_DEBUG_A_SDA")
	)
	(segment
		(start 3.347974 -54.613556)
		(end 3.347974 -47.899066)
		(width 0.17145)
		(layer "B.Cu")
		(net "I2C_DEBUG_A_SDA")
	)
	(segment
		(start 3.791458 -21.126958)
		(end 2.286 -19.6215)
		(width 0.17145)
		(layer "B.Cu")
		(net "I2C_DEBUG_A_SDA")
	)
	(segment
		(start 5.216906 -41.498774)
		(end 5.216906 -39.48684)
		(width 0.17145)
		(layer "B.Cu")
		(net "I2C_DEBUG_A_SDA")
	)
	(segment
		(start 8.419592 -56.71947)
		(end 8.419592 -56.039004)
		(width 0.17145)
		(layer "B.Cu")
		(net "I2C_DEBUG_A_SDA")
	)
	(segment
		(start 3.791458 -38.061392)
		(end 3.791458 -21.126958)
		(width 0.17145)
		(layer "B.Cu")
		(net "I2C_DEBUG_A_SDA")
	)
	(segment
		(start 7.858506 -55.477918)
		(end 4.212336 -55.477918)
		(width 0.17145)
		(layer "B.Cu")
		(net "I2C_DEBUG_A_SDA")
	)
	(segment
		(start 5.216906 -39.48684)
		(end 3.791458 -38.061392)
		(width 0.17145)
		(layer "B.Cu")
		(net "I2C_DEBUG_A_SDA")
	)
	(segment
		(start 9.700006 -57.999884)
		(end 8.419592 -56.71947)
		(width 0.17145)
		(layer "B.Cu")
		(net "I2C_DEBUG_A_SDA")
	)
	(segment
		(start 5.299964 -45.947076)
		(end 5.299964 -41.581832)
		(width 0.17145)
		(layer "B.Cu")
		(net "I2C_DEBUG_A_SDA")
	)
	(segment
		(start 5.299964 -41.581832)
		(end 5.216906 -41.498774)
		(width 0.17145)
		(layer "B.Cu")
		(net "I2C_DEBUG_A_SDA")
	)
	(segment
		(start 4.212336 -55.477918)
		(end 3.347974 -54.613556)
		(width 0.17145)
		(layer "B.Cu")
		(net "I2C_DEBUG_A_SDA")
	)
	(segment
		(start 8.419592 -56.039004)
		(end 7.858506 -55.477918)
		(width 0.17145)
		(layer "B.Cu")
		(net "I2C_DEBUG_A_SDA")
	)
	(segment
		(start 12.0142 -17.91716)
		(end 13.22324 -17.91716)
		(width 0.17145)
		(layer "F.Cu")
		(net "I2C_DEBUG_A_SCL_R")
	)
	(segment
		(start 14.351 -16.7894)
		(end 14.351 -15.494)
		(width 0.17145)
		(layer "F.Cu")
		(net "I2C_DEBUG_A_SCL_R")
	)
	(segment
		(start 13.1445 -15.1638)
		(end 14.0208 -15.1638)
		(width 0.17145)
		(layer "F.Cu")
		(net "I2C_DEBUG_A_SCL_R")
	)
	(segment
		(start 14.0208 -15.1638)
		(end 14.224 -15.367)
		(width 0.17145)
		(layer "F.Cu")
		(net "I2C_DEBUG_A_SCL_R")
	)
	(segment
		(start 13.22324 -17.91716)
		(end 14.351 -16.7894)
		(width 0.17145)
		(layer "F.Cu")
		(net "I2C_DEBUG_A_SCL_R")
	)
	(segment
		(start 14.351 -15.494)
		(end 14.224 -15.367)
		(width 0.17145)
		(layer "F.Cu")
		(net "I2C_DEBUG_A_SCL_R")
	)
	(via
		(at 14.224 -15.367)
		(size 0.6604)
		(drill 0.3302)
		(layers "F.Cu" "B.Cu")
		(net "I2C_DEBUG_A_SCL_R")
	)
	(segment
		(start 3.7973 -19.9136)
		(end 3.0734 -20.6375)
		(width 0.17145)
		(layer "F.Cu")
		(net "I2C_DEBUG_A_SCL")
	)
	(segment
		(start 5.4864 -20.12188)
		(end 4.93268 -20.12188)
		(width 0.17145)
		(layer "F.Cu")
		(net "I2C_DEBUG_A_SCL")
	)
	(segment
		(start 4.7244 -19.9136)
		(end 4.0132 -19.9136)
		(width 0.17145)
		(layer "F.Cu")
		(net "I2C_DEBUG_A_SCL")
	)
	(segment
		(start 4.200652 -45.72889)
		(end 4.200652 -43.986958)
		(width 0.17145)
		(layer "F.Cu")
		(net "I2C_DEBUG_A_SCL")
	)
	(segment
		(start 3.0734 -20.6375)
		(end 2.286 -20.6375)
		(width 0.17145)
		(layer "F.Cu")
		(net "I2C_DEBUG_A_SCL")
	)
	(segment
		(start 4.93268 -20.12188)
		(end 4.7244 -19.9136)
		(width 0.17145)
		(layer "F.Cu")
		(net "I2C_DEBUG_A_SCL")
	)
	(segment
		(start 4.0132 -19.9136)
		(end 3.7973 -19.9136)
		(width 0.17145)
		(layer "F.Cu")
		(net "I2C_DEBUG_A_SCL")
	)
	(segment
		(start 4.128262 -45.80128)
		(end 4.200652 -45.72889)
		(width 0.17145)
		(layer "F.Cu")
		(net "I2C_DEBUG_A_SCL")
	)
	(via
		(at 4.128262 -45.80128)
		(size 0.508)
		(drill 0.254)
		(layers "F.Cu" "B.Cu")
		(net "I2C_DEBUG_A_SCL")
	)
	(via
		(at 4.0132 -19.9136)
		(size 0.6604)
		(drill 0.3302)
		(layers "F.Cu" "B.Cu")
		(net "I2C_DEBUG_A_SCL")
	)
	(via
		(at 2.286 -20.6375)
		(size 0.508)
		(drill 0.254)
		(layers "F.Cu" "B.Cu")
		(net "I2C_DEBUG_A_SCL")
	)
	(segment
		(start 5.467096 -57.693814)
		(end 2.668524 -54.895242)
		(width 0.17145)
		(layer "B.Cu")
		(net "I2C_DEBUG_A_SCL")
	)
	(segment
		(start 4.620514 -45.309028)
		(end 4.620514 -42.13225)
		(width 0.17145)
		(layer "B.Cu")
		(net "I2C_DEBUG_A_SCL")
	)
	(segment
		(start 4.534154 -39.944802)
		(end 2.985008 -38.395656)
		(width 0.17145)
		(layer "B.Cu")
		(net "I2C_DEBUG_A_SCL")
	)
	(segment
		(start 9.700006 -55.999888)
		(end 10.635488 -56.93537)
		(width 0.17145)
		(layer "B.Cu")
		(net "I2C_DEBUG_A_SCL")
	)
	(segment
		(start 10.635488 -56.93537)
		(end 10.635488 -58.545222)
		(width 0.17145)
		(layer "B.Cu")
		(net "I2C_DEBUG_A_SCL")
	)
	(segment
		(start 2.668524 -47.61738)
		(end 4.128262 -46.157642)
		(width 0.17145)
		(layer "B.Cu")
		(net "I2C_DEBUG_A_SCL")
	)
	(segment
		(start 2.985008 -38.395656)
		(end 2.985008 -21.336508)
		(width 0.17145)
		(layer "B.Cu")
		(net "I2C_DEBUG_A_SCL")
	)
	(segment
		(start 2.668524 -54.895242)
		(end 2.668524 -47.61738)
		(width 0.17145)
		(layer "B.Cu")
		(net "I2C_DEBUG_A_SCL")
	)
	(segment
		(start 8.919464 -58.86958)
		(end 7.743698 -57.693814)
		(width 0.17145)
		(layer "B.Cu")
		(net "I2C_DEBUG_A_SCL")
	)
	(segment
		(start 10.31113 -58.86958)
		(end 8.919464 -58.86958)
		(width 0.17145)
		(layer "B.Cu")
		(net "I2C_DEBUG_A_SCL")
	)
	(segment
		(start 4.128262 -45.80128)
		(end 4.620514 -45.309028)
		(width 0.17145)
		(layer "B.Cu")
		(net "I2C_DEBUG_A_SCL")
	)
	(segment
		(start 4.534154 -42.04589)
		(end 4.534154 -39.944802)
		(width 0.17145)
		(layer "B.Cu")
		(net "I2C_DEBUG_A_SCL")
	)
	(segment
		(start 4.128262 -46.157642)
		(end 4.128262 -45.80128)
		(width 0.17145)
		(layer "B.Cu")
		(net "I2C_DEBUG_A_SCL")
	)
	(segment
		(start 10.635488 -58.545222)
		(end 10.31113 -58.86958)
		(width 0.17145)
		(layer "B.Cu")
		(net "I2C_DEBUG_A_SCL")
	)
	(segment
		(start 7.743698 -57.693814)
		(end 5.467096 -57.693814)
		(width 0.17145)
		(layer "B.Cu")
		(net "I2C_DEBUG_A_SCL")
	)
	(segment
		(start 2.985008 -21.336508)
		(end 2.286 -20.6375)
		(width 0.17145)
		(layer "B.Cu")
		(net "I2C_DEBUG_A_SCL")
	)
	(segment
		(start 4.620514 -42.13225)
		(end 4.534154 -42.04589)
		(width 0.17145)
		(layer "B.Cu")
		(net "I2C_DEBUG_A_SCL")
	)
	(segment
		(start 45.439838 -7.8232)
		(end 43.771312 -6.154674)
		(width 0.17145)
		(layer "F.Cu")
		(net "UART_IOC_B_TX")
	)
	(segment
		(start 49.5808 -8.9916)
		(end 49.5808 -8.494522)
		(width 0.17145)
		(layer "F.Cu")
		(net "UART_IOC_B_TX")
	)
	(segment
		(start 48.4759 -9.27862)
		(end 49.29378 -9.27862)
		(width 0.17145)
		(layer "F.Cu")
		(net "UART_IOC_B_TX")
	)
	(segment
		(start 40.345106 -1.599946)
		(end 40.345106 -3.0226)
		(width 0.17145)
		(layer "F.Cu")
		(net "UART_IOC_B_TX")
	)
	(segment
		(start 42.446194 -4.829556)
		(end 43.771312 -6.154674)
		(width 0.17145)
		(layer "F.Cu")
		(net "UART_IOC_B_TX")
	)
	(segment
		(start 49.29378 -9.27862)
		(end 49.5808 -8.9916)
		(width 0.17145)
		(layer "F.Cu")
		(net "UART_IOC_B_TX")
	)
	(segment
		(start 40.345106 -3.0226)
		(end 42.152062 -4.829556)
		(width 0.17145)
		(layer "F.Cu")
		(net "UART_IOC_B_TX")
	)
	(segment
		(start 42.152062 -4.829556)
		(end 42.446194 -4.829556)
		(width 0.17145)
		(layer "F.Cu")
		(net "UART_IOC_B_TX")
	)
	(segment
		(start 48.909478 -7.8232)
		(end 45.439838 -7.8232)
		(width 0.17145)
		(layer "F.Cu")
		(net "UART_IOC_B_TX")
	)
	(segment
		(start 49.5808 -8.494522)
		(end 48.909478 -7.8232)
		(width 0.17145)
		(layer "F.Cu")
		(net "UART_IOC_B_TX")
	)
	(via
		(at 43.771312 -6.154674)
		(size 0.6604)
		(drill 0.3302)
		(layers "F.Cu" "B.Cu")
		(net "UART_IOC_B_TX")
	)
	(segment
		(start 43.012106 -4.023106)
		(end 43.787568 -4.798568)
		(width 0.17145)
		(layer "F.Cu")
		(net "UART_IOC_B_RX")
	)
	(segment
		(start 50.51679 -8.289798)
		(end 49.211992 -6.985)
		(width 0.17145)
		(layer "F.Cu")
		(net "UART_IOC_B_RX")
	)
	(segment
		(start 50.51679 -9.624314)
		(end 50.51679 -8.289798)
		(width 0.17145)
		(layer "F.Cu")
		(net "UART_IOC_B_RX")
	)
	(segment
		(start 42.486326 -4.023106)
		(end 43.012106 -4.023106)
		(width 0.17145)
		(layer "F.Cu")
		(net "UART_IOC_B_RX")
	)
	(segment
		(start 41.615106 -1.599946)
		(end 41.615106 -3.151886)
		(width 0.17145)
		(layer "F.Cu")
		(net "UART_IOC_B_RX")
	)
	(segment
		(start 45.974 -6.985)
		(end 43.787568 -4.798568)
		(width 0.17145)
		(layer "F.Cu")
		(net "UART_IOC_B_RX")
	)
	(segment
		(start 49.861724 -10.27938)
		(end 50.51679 -9.624314)
		(width 0.17145)
		(layer "F.Cu")
		(net "UART_IOC_B_RX")
	)
	(segment
		(start 48.4759 -10.27938)
		(end 49.861724 -10.27938)
		(width 0.17145)
		(layer "F.Cu")
		(net "UART_IOC_B_RX")
	)
	(segment
		(start 49.211992 -6.985)
		(end 45.974 -6.985)
		(width 0.17145)
		(layer "F.Cu")
		(net "UART_IOC_B_RX")
	)
	(segment
		(start 41.615106 -3.151886)
		(end 42.486326 -4.023106)
		(width 0.17145)
		(layer "F.Cu")
		(net "UART_IOC_B_RX")
	)
	(via
		(at 43.787568 -4.798568)
		(size 0.6604)
		(drill 0.3302)
		(layers "F.Cu" "B.Cu")
		(net "UART_IOC_B_RX")
	)
	(segment
		(start 12.2301 -12.07262)
		(end 11.508232 -12.07262)
		(width 0.17145)
		(layer "F.Cu")
		(net "UART_IOC_A_TX")
	)
	(segment
		(start 10.581894 -11.369294)
		(end 10.4902 -11.2776)
		(width 0.17145)
		(layer "F.Cu")
		(net "UART_IOC_A_TX")
	)
	(segment
		(start 10.804906 -11.369294)
		(end 10.581894 -11.369294)
		(width 0.17145)
		(layer "F.Cu")
		(net "UART_IOC_A_TX")
	)
	(segment
		(start 10.0076 -10.795)
		(end 10.4902 -11.2776)
		(width 0.17145)
		(layer "F.Cu")
		(net "UART_IOC_A_TX")
	)
	(segment
		(start 17.480026 -3.119374)
		(end 17.480026 -1.599946)
		(width 0.17145)
		(layer "F.Cu")
		(net "UART_IOC_A_TX")
	)
	(segment
		(start 11.508232 -12.07262)
		(end 10.804906 -11.369294)
		(width 0.17145)
		(layer "F.Cu")
		(net "UART_IOC_A_TX")
	)
	(segment
		(start 17.484852 -3.1242)
		(end 17.480026 -3.119374)
		(width 0.17145)
		(layer "F.Cu")
		(net "UART_IOC_A_TX")
	)
	(segment
		(start 10.0076 -10.414)
		(end 10.0076 -10.795)
		(width 0.17145)
		(layer "F.Cu")
		(net "UART_IOC_A_TX")
	)
	(via
		(at 10.4902 -11.2776)
		(size 0.6604)
		(drill 0.3302)
		(layers "F.Cu" "B.Cu")
		(net "UART_IOC_A_TX")
	)
	(via
		(at 17.484852 -3.1242)
		(size 0.508)
		(drill 0.254)
		(layers "F.Cu" "B.Cu")
		(net "UART_IOC_A_TX")
	)
	(via
		(at 10.0076 -10.414)
		(size 0.508)
		(drill 0.254)
		(layers "F.Cu" "B.Cu")
		(net "UART_IOC_A_TX")
	)
	(segment
		(start 11.1506 -9.552686)
		(end 10.289286 -10.414)
		(width 0.17145)
		(layer "B.Cu")
		(net "UART_IOC_A_TX")
	)
	(segment
		(start 17.484852 -3.1242)
		(end 16.9291 -3.679952)
		(width 0.17145)
		(layer "B.Cu")
		(net "UART_IOC_A_TX")
	)
	(segment
		(start 12.065 -3.683)
		(end 11.1506 -4.5974)
		(width 0.17145)
		(layer "B.Cu")
		(net "UART_IOC_A_TX")
	)
	(segment
		(start 16.9291 -3.679952)
		(end 12.146534 -3.679952)
		(width 0.17145)
		(layer "B.Cu")
		(net "UART_IOC_A_TX")
	)
	(segment
		(start 11.1506 -4.5974)
		(end 11.1506 -9.552686)
		(width 0.17145)
		(layer "B.Cu")
		(net "UART_IOC_A_TX")
	)
	(segment
		(start 10.289286 -10.414)
		(end 10.0076 -10.414)
		(width 0.17145)
		(layer "B.Cu")
		(net "UART_IOC_A_TX")
	)
	(segment
		(start 12.146534 -3.679952)
		(end 12.143486 -3.683)
		(width 0.17145)
		(layer "B.Cu")
		(net "UART_IOC_A_TX")
	)
	(segment
		(start 12.143486 -3.683)
		(end 12.065 -3.683)
		(width 0.17145)
		(layer "B.Cu")
		(net "UART_IOC_A_TX")
	)
	(segment
		(start 13.1572 -9.1948)
		(end 13.1572 -9.652)
		(width 0.17145)
		(layer "F.Cu")
		(net "UART_IOC_A_RX")
	)
	(segment
		(start 18.754852 -3.0734)
		(end 18.750026 -3.068574)
		(width 0.17145)
		(layer "F.Cu")
		(net "UART_IOC_A_RX")
	)
	(segment
		(start 13.198348 -11.199114)
		(end 13.198348 -11.166348)
		(width 0.17145)
		(layer "F.Cu")
		(net "UART_IOC_A_RX")
	)
	(segment
		(start 12.2301 -13.07338)
		(end 12.94511 -13.07338)
		(width 0.17145)
		(layer "F.Cu")
		(net "UART_IOC_A_RX")
	)
	(segment
		(start 13.36675 -11.367516)
		(end 13.198348 -11.199114)
		(width 0.17145)
		(layer "F.Cu")
		(net "UART_IOC_A_RX")
	)
	(segment
		(start 13.198348 -11.166348)
		(end 13.1572 -11.1252)
		(width 0.17145)
		(layer "F.Cu")
		(net "UART_IOC_A_RX")
	)
	(segment
		(start 18.750026 -3.068574)
		(end 18.750026 -1.599946)
		(width 0.17145)
		(layer "F.Cu")
		(net "UART_IOC_A_RX")
	)
	(segment
		(start 13.36675 -12.65174)
		(end 13.36675 -11.367516)
		(width 0.17145)
		(layer "F.Cu")
		(net "UART_IOC_A_RX")
	)
	(segment
		(start 12.7254 -8.763)
		(end 13.1572 -9.1948)
		(width 0.17145)
		(layer "F.Cu")
		(net "UART_IOC_A_RX")
	)
	(segment
		(start 13.1572 -11.1252)
		(end 13.1572 -9.652)
		(width 0.17145)
		(layer "F.Cu")
		(net "UART_IOC_A_RX")
	)
	(segment
		(start 12.94511 -13.07338)
		(end 13.36675 -12.65174)
		(width 0.17145)
		(layer "F.Cu")
		(net "UART_IOC_A_RX")
	)
	(via
		(at 12.7254 -8.763)
		(size 0.508)
		(drill 0.254)
		(layers "F.Cu" "B.Cu")
		(net "UART_IOC_A_RX")
	)
	(via
		(at 18.754852 -3.0734)
		(size 0.508)
		(drill 0.254)
		(layers "F.Cu" "B.Cu")
		(net "UART_IOC_A_RX")
	)
	(via
		(at 13.1572 -9.652)
		(size 0.6604)
		(drill 0.3302)
		(layers "F.Cu" "B.Cu")
		(net "UART_IOC_A_RX")
	)
	(segment
		(start 11.95705 -5.01015)
		(end 11.95705 -7.99465)
		(width 0.17145)
		(layer "B.Cu")
		(net "UART_IOC_A_RX")
	)
	(segment
		(start 18.679922 -3.0734)
		(end 17.26692 -4.486402)
		(width 0.17145)
		(layer "B.Cu")
		(net "UART_IOC_A_RX")
	)
	(segment
		(start 17.26692 -4.486402)
		(end 12.480798 -4.486402)
		(width 0.17145)
		(layer "B.Cu")
		(net "UART_IOC_A_RX")
	)
	(segment
		(start 11.95705 -7.99465)
		(end 12.7254 -8.763)
		(width 0.17145)
		(layer "B.Cu")
		(net "UART_IOC_A_RX")
	)
	(segment
		(start 12.480798 -4.486402)
		(end 11.95705 -5.01015)
		(width 0.17145)
		(layer "B.Cu")
		(net "UART_IOC_A_RX")
	)
	(segment
		(start 18.754852 -3.0734)
		(end 18.679922 -3.0734)
		(width 0.17145)
		(layer "B.Cu")
		(net "UART_IOC_A_RX")
	)
	(segment
		(start 52.6161 -9.27862)
		(end 53.45938 -9.27862)
		(width 0.17145)
		(layer "F.Cu")
		(net "UART_EXP_B_TX")
	)
	(segment
		(start 53.666898 -8.614918)
		(end 53.182774 -8.130794)
		(width 0.17145)
		(layer "F.Cu")
		(net "UART_EXP_B_TX")
	)
	(segment
		(start 46.508162 -6.1468)
		(end 46.016418 -5.655056)
		(width 0.17145)
		(layer "F.Cu")
		(net "UART_EXP_B_TX")
	)
	(segment
		(start 53.182774 -8.130794)
		(end 52.37226 -8.130794)
		(width 0.17145)
		(layer "F.Cu")
		(net "UART_EXP_B_TX")
	)
	(segment
		(start 53.45938 -9.27862)
		(end 53.666898 -9.071102)
		(width 0.17145)
		(layer "F.Cu")
		(net "UART_EXP_B_TX")
	)
	(segment
		(start 44.155106 -1.599946)
		(end 44.155106 -3.793744)
		(width 0.17145)
		(layer "F.Cu")
		(net "UART_EXP_B_TX")
	)
	(segment
		(start 53.666898 -9.071102)
		(end 53.666898 -8.614918)
		(width 0.17145)
		(layer "F.Cu")
		(net "UART_EXP_B_TX")
	)
	(segment
		(start 49.514506 -6.1468)
		(end 46.508162 -6.1468)
		(width 0.17145)
		(layer "F.Cu")
		(net "UART_EXP_B_TX")
	)
	(segment
		(start 51.340766 -7.97306)
		(end 49.514506 -6.1468)
		(width 0.17145)
		(layer "F.Cu")
		(net "UART_EXP_B_TX")
	)
	(segment
		(start 52.214526 -7.97306)
		(end 51.340766 -7.97306)
		(width 0.17145)
		(layer "F.Cu")
		(net "UART_EXP_B_TX")
	)
	(segment
		(start 52.37226 -8.130794)
		(end 52.214526 -7.97306)
		(width 0.17145)
		(layer "F.Cu")
		(net "UART_EXP_B_TX")
	)
	(segment
		(start 44.155106 -3.793744)
		(end 46.016418 -5.655056)
		(width 0.17145)
		(layer "F.Cu")
		(net "UART_EXP_B_TX")
	)
	(via
		(at 46.016418 -5.655056)
		(size 0.6604)
		(drill 0.3302)
		(layers "F.Cu" "B.Cu")
		(net "UART_EXP_B_TX")
	)
	(segment
		(start 45.425106 -1.599946)
		(end 45.425106 -3.642106)
		(width 0.17145)
		(layer "F.Cu")
		(net "UART_EXP_B_RX")
	)
	(segment
		(start 53.706522 -10.542778)
		(end 54.135274 -10.542778)
		(width 0.17145)
		(layer "F.Cu")
		(net "UART_EXP_B_RX")
	)
	(segment
		(start 54.135274 -10.542778)
		(end 54.473348 -10.204704)
		(width 0.17145)
		(layer "F.Cu")
		(net "UART_EXP_B_RX")
	)
	(segment
		(start 53.443124 -10.27938)
		(end 53.706522 -10.542778)
		(width 0.17145)
		(layer "F.Cu")
		(net "UART_EXP_B_RX")
	)
	(segment
		(start 46.865286 -5.082286)
		(end 49.20234 -5.082286)
		(width 0.17145)
		(layer "F.Cu")
		(net "UART_EXP_B_RX")
	)
	(segment
		(start 54.473348 -10.204704)
		(end 54.473348 -8.280654)
		(width 0.17145)
		(layer "F.Cu")
		(net "UART_EXP_B_RX")
	)
	(segment
		(start 52.492656 -7.0612)
		(end 51.661314 -7.0612)
		(width 0.17145)
		(layer "F.Cu")
		(net "UART_EXP_B_RX")
	)
	(segment
		(start 51.661314 -7.0612)
		(end 49.6824 -5.082286)
		(width 0.17145)
		(layer "F.Cu")
		(net "UART_EXP_B_RX")
	)
	(segment
		(start 45.425106 -3.642106)
		(end 46.865286 -5.082286)
		(width 0.17145)
		(layer "F.Cu")
		(net "UART_EXP_B_RX")
	)
	(segment
		(start 54.473348 -8.280654)
		(end 53.517038 -7.324344)
		(width 0.17145)
		(layer "F.Cu")
		(net "UART_EXP_B_RX")
	)
	(segment
		(start 52.7558 -7.324344)
		(end 52.492656 -7.0612)
		(width 0.17145)
		(layer "F.Cu")
		(net "UART_EXP_B_RX")
	)
	(segment
		(start 53.517038 -7.324344)
		(end 52.7558 -7.324344)
		(width 0.17145)
		(layer "F.Cu")
		(net "UART_EXP_B_RX")
	)
	(segment
		(start 52.6161 -10.27938)
		(end 53.443124 -10.27938)
		(width 0.17145)
		(layer "F.Cu")
		(net "UART_EXP_B_RX")
	)
	(segment
		(start 49.6824 -5.082286)
		(end 49.20234 -5.082286)
		(width 0.17145)
		(layer "F.Cu")
		(net "UART_EXP_B_RX")
	)
	(via
		(at 49.20234 -5.082286)
		(size 0.6604)
		(drill 0.3302)
		(layers "F.Cu" "B.Cu")
		(net "UART_EXP_B_RX")
	)
	(segment
		(start 18.6436 -7.263892)
		(end 18.6436 -8.128)
		(width 0.17145)
		(layer "F.Cu")
		(net "UART_EXP_A_TX")
	)
	(segment
		(start 15.004796 -4.37769)
		(end 15.004796 -4.377944)
		(width 0.17145)
		(layer "F.Cu")
		(net "UART_EXP_A_TX")
	)
	(segment
		(start 17.3736 -11.791696)
		(end 17.3736 -10.767314)
		(width 0.17145)
		(layer "F.Cu")
		(net "UART_EXP_A_TX")
	)
	(segment
		(start 18.795492 -7.112)
		(end 18.6436 -7.263892)
		(width 0.17145)
		(layer "F.Cu")
		(net "UART_EXP_A_TX")
	)
	(segment
		(start 13.670026 -1.599946)
		(end 13.670026 -3.04292)
		(width 0.17145)
		(layer "F.Cu")
		(net "UART_EXP_A_TX")
	)
	(segment
		(start 15.004796 -4.377944)
		(end 15.476728 -4.849876)
		(width 0.17145)
		(layer "F.Cu")
		(net "UART_EXP_A_TX")
	)
	(segment
		(start 18.235676 -4.849876)
		(end 18.795492 -5.409692)
		(width 0.17145)
		(layer "F.Cu")
		(net "UART_EXP_A_TX")
	)
	(segment
		(start 17.092676 -12.07262)
		(end 17.3736 -11.791696)
		(width 0.17145)
		(layer "F.Cu")
		(net "UART_EXP_A_TX")
	)
	(segment
		(start 16.3703 -12.07262)
		(end 17.092676 -12.07262)
		(width 0.17145)
		(layer "F.Cu")
		(net "UART_EXP_A_TX")
	)
	(segment
		(start 17.3736 -10.767314)
		(end 18.6436 -9.497314)
		(width 0.17145)
		(layer "F.Cu")
		(net "UART_EXP_A_TX")
	)
	(segment
		(start 18.795492 -5.409692)
		(end 18.795492 -7.112)
		(width 0.17145)
		(layer "F.Cu")
		(net "UART_EXP_A_TX")
	)
	(segment
		(start 18.6436 -9.497314)
		(end 18.6436 -8.128)
		(width 0.17145)
		(layer "F.Cu")
		(net "UART_EXP_A_TX")
	)
	(segment
		(start 13.670026 -3.04292)
		(end 15.004796 -4.37769)
		(width 0.17145)
		(layer "F.Cu")
		(net "UART_EXP_A_TX")
	)
	(segment
		(start 15.476728 -4.849876)
		(end 18.235676 -4.849876)
		(width 0.17145)
		(layer "F.Cu")
		(net "UART_EXP_A_TX")
	)
	(via
		(at 18.6436 -8.128)
		(size 0.6604)
		(drill 0.3302)
		(layers "F.Cu" "B.Cu")
		(net "UART_EXP_A_TX")
	)
	(segment
		(start 14.940026 -3.172206)
		(end 15.811246 -4.043426)
		(width 0.17145)
		(layer "F.Cu")
		(net "UART_EXP_A_RX")
	)
	(segment
		(start 18.2372 -12.387326)
		(end 18.2372 -11.044428)
		(width 0.17145)
		(layer "F.Cu")
		(net "UART_EXP_A_RX")
	)
	(segment
		(start 18.62074 -4.043426)
		(end 19.601942 -5.024628)
		(width 0.17145)
		(layer "F.Cu")
		(net "UART_EXP_A_RX")
	)
	(segment
		(start 17.559274 -13.065252)
		(end 18.2372 -12.387326)
		(width 0.17145)
		(layer "F.Cu")
		(net "UART_EXP_A_RX")
	)
	(segment
		(start 15.811246 -4.043426)
		(end 18.62074 -4.043426)
		(width 0.17145)
		(layer "F.Cu")
		(net "UART_EXP_A_RX")
	)
	(segment
		(start 19.601942 -5.024628)
		(end 19.601942 -6.001258)
		(width 0.17145)
		(layer "F.Cu")
		(net "UART_EXP_A_RX")
	)
	(segment
		(start 17.169638 -13.07338)
		(end 17.177766 -13.065252)
		(width 0.17145)
		(layer "F.Cu")
		(net "UART_EXP_A_RX")
	)
	(segment
		(start 17.177766 -13.065252)
		(end 17.559274 -13.065252)
		(width 0.17145)
		(layer "F.Cu")
		(net "UART_EXP_A_RX")
	)
	(segment
		(start 19.601942 -9.679686)
		(end 19.601942 -6.001258)
		(width 0.17145)
		(layer "F.Cu")
		(net "UART_EXP_A_RX")
	)
	(segment
		(start 14.940026 -1.599946)
		(end 14.940026 -3.172206)
		(width 0.17145)
		(layer "F.Cu")
		(net "UART_EXP_A_RX")
	)
	(segment
		(start 18.2372 -11.044428)
		(end 19.601942 -9.679686)
		(width 0.17145)
		(layer "F.Cu")
		(net "UART_EXP_A_RX")
	)
	(segment
		(start 16.3703 -13.07338)
		(end 17.169638 -13.07338)
		(width 0.17145)
		(layer "F.Cu")
		(net "UART_EXP_A_RX")
	)
	(via
		(at 19.601942 -6.001258)
		(size 0.6604)
		(drill 0.3302)
		(layers "F.Cu" "B.Cu")
		(net "UART_EXP_A_RX")
	)
	(segment
		(start 52.034694 -29.31922)
		(end 51.651408 -29.702506)
		(width 0.17145)
		(layer "F.Cu")
		(net "SYS_RESET_BTN_B")
	)
	(segment
		(start 49.4538 -29.3878)
		(end 48.7426 -29.3878)
		(width 0.17145)
		(layer "F.Cu")
		(net "SYS_RESET_BTN_B")
	)
	(segment
		(start 54.7624 -37.23132)
		(end 54.7624 -38.4048)
		(width 0.17145)
		(layer "F.Cu")
		(net "SYS_RESET_BTN_B")
	)
	(segment
		(start 50.41138 -29.271976)
		(end 50.41138 -28.8544)
		(width 0.17145)
		(layer "F.Cu")
		(net "SYS_RESET_BTN_B")
	)
	(segment
		(start 48.4886 -28.4988)
		(end 48.4886 -29.1338)
		(width 0.17145)
		(layer "F.Cu")
		(net "SYS_RESET_BTN_B")
	)
	(segment
		(start 44.92498 -37.249862)
		(end 52.87518 -37.249862)
		(width 0.17145)
		(layer "F.Cu")
		(net "SYS_RESET_BTN_B")
	)
	(segment
		(start 52.87518 -37.249862)
		(end 54.030118 -38.4048)
		(width 0.17145)
		(layer "F.Cu")
		(net "SYS_RESET_BTN_B")
	)
	(segment
		(start 55.3974 -35.0774)
		(end 55.3974 -36.55568)
		(width 0.17145)
		(layer "F.Cu")
		(net "SYS_RESET_BTN_B")
	)
	(segment
		(start 54.030118 -38.4048)
		(end 54.7624 -38.4048)
		(width 0.17145)
		(layer "F.Cu")
		(net "SYS_RESET_BTN_B")
	)
	(segment
		(start 55.3974 -36.55568)
		(end 54.74208 -37.211)
		(width 0.17145)
		(layer "F.Cu")
		(net "SYS_RESET_BTN_B")
	)
	(segment
		(start 48.4886 -29.1338)
		(end 48.7426 -29.3878)
		(width 0.17145)
		(layer "F.Cu")
		(net "SYS_RESET_BTN_B")
	)
	(segment
		(start 49.9872 -28.8544)
		(end 49.4538 -29.3878)
		(width 0.17145)
		(layer "F.Cu")
		(net "SYS_RESET_BTN_B")
	)
	(segment
		(start 49.149 -34.50209)
		(end 54.741064 -34.50209)
		(width 0.17145)
		(layer "F.Cu")
		(net "SYS_RESET_BTN_B")
	)
	(segment
		(start 50.84191 -29.702506)
		(end 50.41138 -29.271976)
		(width 0.17145)
		(layer "F.Cu")
		(net "SYS_RESET_BTN_B")
	)
	(segment
		(start 52.713636 -29.31922)
		(end 52.034694 -29.31922)
		(width 0.17145)
		(layer "F.Cu")
		(net "SYS_RESET_BTN_B")
	)
	(segment
		(start 51.651408 -29.702506)
		(end 50.84191 -29.702506)
		(width 0.17145)
		(layer "F.Cu")
		(net "SYS_RESET_BTN_B")
	)
	(segment
		(start 54.74208 -37.211)
		(end 54.7624 -37.23132)
		(width 0.17145)
		(layer "F.Cu")
		(net "SYS_RESET_BTN_B")
	)
	(segment
		(start 54.741064 -34.50209)
		(end 54.82209 -34.50209)
		(width 0.17145)
		(layer "F.Cu")
		(net "SYS_RESET_BTN_B")
	)
	(segment
		(start 54.82209 -34.50209)
		(end 55.3974 -35.0774)
		(width 0.17145)
		(layer "F.Cu")
		(net "SYS_RESET_BTN_B")
	)
	(segment
		(start 50.41138 -28.8544)
		(end 49.9872 -28.8544)
		(width 0.17145)
		(layer "F.Cu")
		(net "SYS_RESET_BTN_B")
	)
	(via
		(at 54.7624 -38.4048)
		(size 0.6604)
		(drill 0.3302)
		(layers "F.Cu" "B.Cu")
		(net "SYS_RESET_BTN_B")
	)
	(via
		(at 49.149 -34.50209)
		(size 0.508)
		(drill 0.254)
		(layers "F.Cu" "B.Cu")
		(net "SYS_RESET_BTN_B")
	)
	(via
		(at 48.4886 -28.4988)
		(size 0.508)
		(drill 0.254)
		(layers "F.Cu" "B.Cu")
		(net "SYS_RESET_BTN_B")
	)
	(segment
		(start 49.149 -29.1592)
		(end 48.4886 -28.4988)
		(width 0.17145)
		(layer "B.Cu")
		(net "SYS_RESET_BTN_B")
	)
	(segment
		(start 49.149 -34.50209)
		(end 49.149 -29.1592)
		(width 0.17145)
		(layer "B.Cu")
		(net "SYS_RESET_BTN_B")
	)
	(segment
		(start 4.4958 -26.9875)
		(end 4.5847 -26.9875)
		(width 0.17145)
		(layer "F.Cu")
		(net "SYS_RESET_BTN_A")
	)
	(segment
		(start 6.557772 -27.503628)
		(end 7.380732 -27.503628)
		(width 0.17145)
		(layer "F.Cu")
		(net "SYS_RESET_BTN_A")
	)
	(segment
		(start 5.3467 -27.7495)
		(end 5.9182 -27.7495)
		(width 0.17145)
		(layer "F.Cu")
		(net "SYS_RESET_BTN_A")
	)
	(segment
		(start 3.051556 -27.530044)
		(end 3.051556 -38.890956)
		(width 0.17145)
		(layer "F.Cu")
		(net "SYS_RESET_BTN_A")
	)
	(segment
		(start 6.3119 -27.7495)
		(end 6.557772 -27.503628)
		(width 0.17145)
		(layer "F.Cu")
		(net "SYS_RESET_BTN_A")
	)
	(segment
		(start 3.471418 -39.310818)
		(end 4.215892 -39.310818)
		(width 0.17145)
		(layer "F.Cu")
		(net "SYS_RESET_BTN_A")
	)
	(segment
		(start 4.215892 -39.310818)
		(end 4.215892 -37.258752)
		(width 0.17145)
		(layer "F.Cu")
		(net "SYS_RESET_BTN_A")
	)
	(segment
		(start 3.051556 -38.890956)
		(end 3.471418 -39.310818)
		(width 0.17145)
		(layer "F.Cu")
		(net "SYS_RESET_BTN_A")
	)
	(segment
		(start 3.2766 -27.305)
		(end 3.051556 -27.530044)
		(width 0.17145)
		(layer "F.Cu")
		(net "SYS_RESET_BTN_A")
	)
	(segment
		(start 4.5847 -26.9875)
		(end 5.3467 -27.7495)
		(width 0.17145)
		(layer "F.Cu")
		(net "SYS_RESET_BTN_A")
	)
	(segment
		(start 3.2766 -27.305)
		(end 3.5941 -26.9875)
		(width 0.17145)
		(layer "F.Cu")
		(net "SYS_RESET_BTN_A")
	)
	(segment
		(start 5.9182 -27.7495)
		(end 6.3119 -27.7495)
		(width 0.17145)
		(layer "F.Cu")
		(net "SYS_RESET_BTN_A")
	)
	(segment
		(start 12.931648 -39.158418)
		(end 12.931648 -38.788848)
		(width 0.17145)
		(layer "F.Cu")
		(net "SYS_RESET_BTN_A")
	)
	(segment
		(start 4.224782 -37.249862)
		(end 12.174982 -37.249862)
		(width 0.17145)
		(layer "F.Cu")
		(net "SYS_RESET_BTN_A")
	)
	(segment
		(start 4.215892 -37.258752)
		(end 4.224782 -37.249862)
		(width 0.17145)
		(layer "F.Cu")
		(net "SYS_RESET_BTN_A")
	)
	(segment
		(start 12.931648 -38.788848)
		(end 12.174982 -38.032182)
		(width 0.17145)
		(layer "F.Cu")
		(net "SYS_RESET_BTN_A")
	)
	(segment
		(start 3.5941 -26.9875)
		(end 4.4958 -26.9875)
		(width 0.17145)
		(layer "F.Cu")
		(net "SYS_RESET_BTN_A")
	)
	(segment
		(start 12.174982 -38.032182)
		(end 12.174982 -37.249862)
		(width 0.17145)
		(layer "F.Cu")
		(net "SYS_RESET_BTN_A")
	)
	(via
		(at 3.2766 -27.305)
		(size 0.6604)
		(drill 0.3302)
		(layers "F.Cu" "B.Cu")
		(net "SYS_RESET_BTN_A")
	)
	(segment
		(start 46.9138 -39.751)
		(end 46.1772 -40.4876)
		(width 0.17145)
		(layer "F.Cu")
		(net "SYS_FAULT_B_R")
	)
	(segment
		(start 46.630082 -43.999912)
		(end 45.72 -43.08983)
		(width 0.17145)
		(layer "F.Cu")
		(net "SYS_FAULT_B_R")
	)
	(segment
		(start 45.72 -40.9448)
		(end 46.1772 -40.4876)
		(width 0.17145)
		(layer "F.Cu")
		(net "SYS_FAULT_B_R")
	)
	(segment
		(start 47.900082 -39.751)
		(end 46.9138 -39.751)
		(width 0.17145)
		(layer "F.Cu")
		(net "SYS_FAULT_B_R")
	)
	(segment
		(start 45.72 -43.08983)
		(end 45.72 -40.9448)
		(width 0.17145)
		(layer "F.Cu")
		(net "SYS_FAULT_B_R")
	)
	(via
		(at 46.1772 -40.4876)
		(size 0.6604)
		(drill 0.3302)
		(layers "F.Cu" "B.Cu")
		(net "SYS_FAULT_B_R")
	)
	(segment
		(start 7.17296 -43.756834)
		(end 6.929882 -43.999912)
		(width 0.17145)
		(layer "F.Cu")
		(net "SYS_FAULT_A_R")
	)
	(segment
		(start 7.460234 -40.573452)
		(end 7.424928 -40.608758)
		(width 0.17145)
		(layer "F.Cu")
		(net "SYS_FAULT_A_R")
	)
	(segment
		(start 7.17296 -40.860726)
		(end 7.17296 -43.756834)
		(width 0.17145)
		(layer "F.Cu")
		(net "SYS_FAULT_A_R")
	)
	(segment
		(start 7.424928 -40.608758)
		(end 7.17296 -40.860726)
		(width 0.17145)
		(layer "F.Cu")
		(net "SYS_FAULT_A_R")
	)
	(segment
		(start 8.536686 -40.573452)
		(end 7.460234 -40.573452)
		(width 0.17145)
		(layer "F.Cu")
		(net "SYS_FAULT_A_R")
	)
	(via
		(at 7.424928 -40.608758)
		(size 0.6604)
		(drill 0.3302)
		(layers "F.Cu" "B.Cu")
		(net "SYS_FAULT_A_R")
	)
	(segment
		(start 56.106314 -76.37526)
		(end 56.106314 -75.321414)
		(width 0.17145)
		(layer "F.Cu")
		(net "PWR_BTN_LED_B_R")
	)
	(segment
		(start 53.90007 -79.499968)
		(end 53.90007 -78.581504)
		(width 0.17145)
		(layer "F.Cu")
		(net "PWR_BTN_LED_B_R")
	)
	(segment
		(start 56.063642 -75.278742)
		(end 56.106314 -75.321414)
		(width 0.17145)
		(layer "F.Cu")
		(net "PWR_BTN_LED_B_R")
	)
	(segment
		(start 53.90007 -78.581504)
		(end 56.106314 -76.37526)
		(width 0.17145)
		(layer "F.Cu")
		(net "PWR_BTN_LED_B_R")
	)
	(segment
		(start 56.063642 -74.01433)
		(end 56.063642 -75.278742)
		(width 0.17145)
		(layer "F.Cu")
		(net "PWR_BTN_LED_B_R")
	)
	(via
		(at 56.106314 -75.321414)
		(size 0.6604)
		(drill 0.3302)
		(layers "F.Cu" "B.Cu")
		(net "PWR_BTN_LED_B_R")
	)
	(segment
		(start 14.1732 -73.6346)
		(end 14.1732 -74.3966)
		(width 0.17145)
		(layer "F.Cu")
		(net "PWR_BTN_LED_A_R")
	)
	(segment
		(start 13.823188 -73.284588)
		(end 14.1732 -73.6346)
		(width 0.17145)
		(layer "F.Cu")
		(net "PWR_BTN_LED_A_R")
	)
	(segment
		(start 14.1732 -78.52664)
		(end 14.1732 -74.3966)
		(width 0.17145)
		(layer "F.Cu")
		(net "PWR_BTN_LED_A_R")
	)
	(segment
		(start 13.199872 -79.499968)
		(end 14.1732 -78.52664)
		(width 0.17145)
		(layer "F.Cu")
		(net "PWR_BTN_LED_A_R")
	)
	(segment
		(start 12.769088 -73.284588)
		(end 13.823188 -73.284588)
		(width 0.17145)
		(layer "F.Cu")
		(net "PWR_BTN_LED_A_R")
	)
	(via
		(at 14.1732 -74.3966)
		(size 0.6604)
		(drill 0.3302)
		(layers "F.Cu" "B.Cu")
		(net "PWR_BTN_LED_A_R")
	)
	(segment
		(start 39.075106 -3.215894)
		(end 38.439344 -3.851656)
		(width 0.17145)
		(layer "F.Cu")
		(net "PWR_BTN_B")
	)
	(segment
		(start 45.837856 -24.2824)
		(end 48.548036 -24.2824)
		(width 0.17145)
		(layer "F.Cu")
		(net "PWR_BTN_B")
	)
	(segment
		(start 39.075106 -1.599946)
		(end 39.075106 -3.215894)
		(width 0.17145)
		(layer "F.Cu")
		(net "PWR_BTN_B")
	)
	(segment
		(start 56.515 -24.003)
		(end 58.1533 -25.6413)
		(width 0.17145)
		(layer "F.Cu")
		(net "PWR_BTN_B")
	)
	(segment
		(start 55.465726 -80.322674)
		(end 56.436006 -80.322674)
		(width 0.17145)
		(layer "F.Cu")
		(net "PWR_BTN_B")
	)
	(segment
		(start 57.1754 -80.322674)
		(end 56.436006 -80.322674)
		(width 0.17145)
		(layer "F.Cu")
		(net "PWR_BTN_B")
	)
	(segment
		(start 54.7116 -24.003)
		(end 56.515 -24.003)
		(width 0.17145)
		(layer "F.Cu")
		(net "PWR_BTN_B")
	)
	(segment
		(start 38.439344 -15.8242)
		(end 38.439344 -15.824454)
		(width 0.17145)
		(layer "F.Cu")
		(net "PWR_BTN_B")
	)
	(segment
		(start 58.1533 -25.6413)
		(end 58.1533 -79.344774)
		(width 0.17145)
		(layer "F.Cu")
		(net "PWR_BTN_B")
	)
	(segment
		(start 38.439344 -10.522712)
		(end 38.439344 -15.8242)
		(width 0.17145)
		(layer "F.Cu")
		(net "PWR_BTN_B")
	)
	(segment
		(start 51.400202 -82.00009)
		(end 53.78831 -82.00009)
		(width 0.17145)
		(layer "F.Cu")
		(net "PWR_BTN_B")
	)
	(segment
		(start 48.548036 -24.2824)
		(end 49.397666 -23.43277)
		(width 0.17145)
		(layer "F.Cu")
		(net "PWR_BTN_B")
	)
	(segment
		(start 38.417246 -19.51736)
		(end 38.439344 -19.539458)
		(width 0.17145)
		(layer "F.Cu")
		(net "PWR_BTN_B")
	)
	(segment
		(start 49.397666 -23.43277)
		(end 54.14137 -23.43277)
		(width 0.17145)
		(layer "F.Cu")
		(net "PWR_BTN_B")
	)
	(segment
		(start 38.439344 -19.539458)
		(end 38.439344 -20.854416)
		(width 0.17145)
		(layer "F.Cu")
		(net "PWR_BTN_B")
	)
	(segment
		(start 38.417246 -8.06704)
		(end 38.417246 -10.500614)
		(width 0.17145)
		(layer "F.Cu")
		(net "PWR_BTN_B")
	)
	(segment
		(start 45.666406 -24.45385)
		(end 45.837856 -24.2824)
		(width 0.17145)
		(layer "F.Cu")
		(net "PWR_BTN_B")
	)
	(segment
		(start 38.439344 -3.851656)
		(end 38.439344 -8.044942)
		(width 0.17145)
		(layer "F.Cu")
		(net "PWR_BTN_B")
	)
	(segment
		(start 38.417246 -15.846552)
		(end 38.417246 -19.51736)
		(width 0.17145)
		(layer "F.Cu")
		(net "PWR_BTN_B")
	)
	(segment
		(start 53.78831 -82.00009)
		(end 55.465726 -80.322674)
		(width 0.17145)
		(layer "F.Cu")
		(net "PWR_BTN_B")
	)
	(segment
		(start 42.038778 -24.45385)
		(end 45.666406 -24.45385)
		(width 0.17145)
		(layer "F.Cu")
		(net "PWR_BTN_B")
	)
	(segment
		(start 58.1533 -79.344774)
		(end 57.1754 -80.322674)
		(width 0.17145)
		(layer "F.Cu")
		(net "PWR_BTN_B")
	)
	(segment
		(start 38.417246 -10.500614)
		(end 38.439344 -10.522712)
		(width 0.17145)
		(layer "F.Cu")
		(net "PWR_BTN_B")
	)
	(segment
		(start 38.439344 -8.044942)
		(end 38.417246 -8.06704)
		(width 0.17145)
		(layer "F.Cu")
		(net "PWR_BTN_B")
	)
	(segment
		(start 54.14137 -23.43277)
		(end 54.7116 -24.003)
		(width 0.17145)
		(layer "F.Cu")
		(net "PWR_BTN_B")
	)
	(segment
		(start 38.439344 -15.824454)
		(end 38.417246 -15.846552)
		(width 0.17145)
		(layer "F.Cu")
		(net "PWR_BTN_B")
	)
	(segment
		(start 38.439344 -20.854416)
		(end 42.038778 -24.45385)
		(width 0.17145)
		(layer "F.Cu")
		(net "PWR_BTN_B")
	)
	(via
		(at 38.439344 -15.8242)
		(size 0.6604)
		(drill 0.3302)
		(layers "F.Cu" "B.Cu")
		(net "PWR_BTN_B")
	)
	(segment
		(start 4.9276 -84.0486)
		(end 8.8646 -84.0486)
		(width 0.17145)
		(layer "F.Cu")
		(net "PWR_BTN_A")
	)
	(segment
		(start 20.32 -3.937)
		(end 21.290026 -2.966974)
		(width 0.17145)
		(layer "F.Cu")
		(net "PWR_BTN_A")
	)
	(segment
		(start 2.985262 -25.587452)
		(end 5.669788 -25.587452)
		(width 0.17145)
		(layer "F.Cu")
		(net "PWR_BTN_A")
	)
	(segment
		(start 3.8862 -73.3171)
		(end 3.8862 -75.5396)
		(width 0.17145)
		(layer "F.Cu")
		(net "PWR_BTN_A")
	)
	(segment
		(start 5.245862 -40.594026)
		(end 4.400042 -40.594026)
		(width 0.17145)
		(layer "F.Cu")
		(net "PWR_BTN_A")
	)
	(segment
		(start 9.345422 -51.504596)
		(end 8.478266 -51.504596)
		(width 0.17145)
		(layer "F.Cu")
		(net "PWR_BTN_A")
	)
	(segment
		(start 8.8646 -84.0486)
		(end 10.700004 -82.213196)
		(width 0.17145)
		(layer "F.Cu")
		(net "PWR_BTN_A")
	)
	(segment
		(start 5.341366 -42.955464)
		(end 5.81406 -42.48277)
		(width 0.17145)
		(layer "F.Cu")
		(net "PWR_BTN_A")
	)
	(segment
		(start 3.79349 -40.594026)
		(end 2.308352 -39.108888)
		(width 0.17145)
		(layer "F.Cu")
		(net "PWR_BTN_A")
	)
	(segment
		(start 19.5326 -3.937)
		(end 20.32 -3.937)
		(width 0.17145)
		(layer "F.Cu")
		(net "PWR_BTN_A")
	)
	(segment
		(start 14.239494 -54.906418)
		(end 11.33729 -52.004214)
		(width 0.17145)
		(layer "F.Cu")
		(net "PWR_BTN_A")
	)
	(segment
		(start 10.700004 -82.213196)
		(end 10.700004 -82.00009)
		(width 0.17145)
		(layer "F.Cu")
		(net "PWR_BTN_A")
	)
	(segment
		(start 5.341366 -45.17898)
		(end 5.341366 -42.955464)
		(width 0.17145)
		(layer "F.Cu")
		(net "PWR_BTN_A")
	)
	(segment
		(start 9.719564 -73.3171)
		(end 14.239494 -68.79717)
		(width 0.17145)
		(layer "F.Cu")
		(net "PWR_BTN_A")
	)
	(segment
		(start 3.8862 -75.5396)
		(end 2.346452 -77.079348)
		(width 0.17145)
		(layer "F.Cu")
		(net "PWR_BTN_A")
	)
	(segment
		(start 7.49681 -47.334424)
		(end 5.341366 -45.17898)
		(width 0.17145)
		(layer "F.Cu")
		(net "PWR_BTN_A")
	)
	(segment
		(start 7.49681 -50.52314)
		(end 7.49681 -47.334424)
		(width 0.17145)
		(layer "F.Cu")
		(net "PWR_BTN_A")
	)
	(segment
		(start 2.308352 -39.108888)
		(end 2.308352 -26.264362)
		(width 0.17145)
		(layer "F.Cu")
		(net "PWR_BTN_A")
	)
	(segment
		(start 14.239494 -68.79717)
		(end 14.239494 -54.906418)
		(width 0.17145)
		(layer "F.Cu")
		(net "PWR_BTN_A")
	)
	(segment
		(start 8.478266 -51.504596)
		(end 7.49681 -50.52314)
		(width 0.17145)
		(layer "F.Cu")
		(net "PWR_BTN_A")
	)
	(segment
		(start 9.84504 -52.004214)
		(end 9.345422 -51.504596)
		(width 0.17145)
		(layer "F.Cu")
		(net "PWR_BTN_A")
	)
	(segment
		(start 5.669788 -25.587452)
		(end 5.865622 -25.391618)
		(width 0.17145)
		(layer "F.Cu")
		(net "PWR_BTN_A")
	)
	(segment
		(start 3.8862 -73.3171)
		(end 9.719564 -73.3171)
		(width 0.17145)
		(layer "F.Cu")
		(net "PWR_BTN_A")
	)
	(segment
		(start 4.400042 -40.594026)
		(end 3.79349 -40.594026)
		(width 0.17145)
		(layer "F.Cu")
		(net "PWR_BTN_A")
	)
	(segment
		(start 5.81406 -41.162224)
		(end 5.245862 -40.594026)
		(width 0.17145)
		(layer "F.Cu")
		(net "PWR_BTN_A")
	)
	(segment
		(start 2.346452 -77.079348)
		(end 2.346452 -81.467452)
		(width 0.17145)
		(layer "F.Cu")
		(net "PWR_BTN_A")
	)
	(segment
		(start 5.81406 -42.48277)
		(end 5.81406 -41.162224)
		(width 0.17145)
		(layer "F.Cu")
		(net "PWR_BTN_A")
	)
	(segment
		(start 21.290026 -2.966974)
		(end 21.290026 -1.599946)
		(width 0.17145)
		(layer "F.Cu")
		(net "PWR_BTN_A")
	)
	(segment
		(start 2.346452 -81.467452)
		(end 4.9276 -84.0486)
		(width 0.17145)
		(layer "F.Cu")
		(net "PWR_BTN_A")
	)
	(segment
		(start 2.308352 -26.264362)
		(end 2.985262 -25.587452)
		(width 0.17145)
		(layer "F.Cu")
		(net "PWR_BTN_A")
	)
	(segment
		(start 11.33729 -52.004214)
		(end 9.84504 -52.004214)
		(width 0.17145)
		(layer "F.Cu")
		(net "PWR_BTN_A")
	)
	(via
		(at 5.865622 -25.391618)
		(size 0.508)
		(drill 0.254)
		(layers "F.Cu" "B.Cu")
		(net "PWR_BTN_A")
	)
	(via
		(at 19.5326 -3.937)
		(size 0.508)
		(drill 0.254)
		(layers "F.Cu" "B.Cu")
		(net "PWR_BTN_A")
	)
	(via
		(at 4.400042 -40.594026)
		(size 0.6604)
		(drill 0.3302)
		(layers "F.Cu" "B.Cu")
		(net "PWR_BTN_A")
	)
	(segment
		(start 10.902188 -11.902948)
		(end 10.917936 -11.8872)
		(width 0.17145)
		(layer "B.Cu")
		(net "PWR_BTN_A")
	)
	(segment
		(start 10.47115 -11.90625)
		(end 10.7061 -11.90625)
		(width 0.17145)
		(layer "B.Cu")
		(net "PWR_BTN_A")
	)
	(segment
		(start 18.176748 -5.292852)
		(end 19.5326 -3.937)
		(width 0.17145)
		(layer "B.Cu")
		(net "PWR_BTN_A")
	)
	(segment
		(start 10.7061 -11.90625)
		(end 10.709402 -11.902948)
		(width 0.17145)
		(layer "B.Cu")
		(net "PWR_BTN_A")
	)
	(segment
		(start 5.8674 -25.38984)
		(end 5.8674 -19.431)
		(width 0.17145)
		(layer "B.Cu")
		(net "PWR_BTN_A")
	)
	(segment
		(start 10.709402 -11.902948)
		(end 10.902188 -11.902948)
		(width 0.17145)
		(layer "B.Cu")
		(net "PWR_BTN_A")
	)
	(segment
		(start 13.532104 -5.832348)
		(end 14.0716 -5.292852)
		(width 0.17145)
		(layer "B.Cu")
		(net "PWR_BTN_A")
	)
	(segment
		(start 9.1694 -14.3764)
		(end 9.652 -13.8938)
		(width 0.17145)
		(layer "B.Cu")
		(net "PWR_BTN_A")
	)
	(segment
		(start 5.865622 -25.391618)
		(end 5.8674 -25.38984)
		(width 0.17145)
		(layer "B.Cu")
		(net "PWR_BTN_A")
	)
	(segment
		(start 10.917936 -11.8872)
		(end 11.2268 -11.8872)
		(width 0.17145)
		(layer "B.Cu")
		(net "PWR_BTN_A")
	)
	(segment
		(start 9.652 -13.8938)
		(end 9.652 -12.7254)
		(width 0.17145)
		(layer "B.Cu")
		(net "PWR_BTN_A")
	)
	(segment
		(start 9.652 -12.7254)
		(end 10.47115 -11.90625)
		(width 0.17145)
		(layer "B.Cu")
		(net "PWR_BTN_A")
	)
	(segment
		(start 9.1694 -16.129)
		(end 9.1694 -14.3764)
		(width 0.17145)
		(layer "B.Cu")
		(net "PWR_BTN_A")
	)
	(segment
		(start 11.2268 -11.8872)
		(end 13.532104 -9.581896)
		(width 0.17145)
		(layer "B.Cu")
		(net "PWR_BTN_A")
	)
	(segment
		(start 13.532104 -9.581896)
		(end 13.532104 -5.832348)
		(width 0.17145)
		(layer "B.Cu")
		(net "PWR_BTN_A")
	)
	(segment
		(start 14.0716 -5.292852)
		(end 18.176748 -5.292852)
		(width 0.17145)
		(layer "B.Cu")
		(net "PWR_BTN_A")
	)
	(segment
		(start 5.8674 -19.431)
		(end 9.1694 -16.129)
		(width 0.17145)
		(layer "B.Cu")
		(net "PWR_BTN_A")
	)
	(segment
		(start 47.010574 -63.5)
		(end 47.900082 -63.5)
		(width 0.508)
		(layer "F.Cu")
		(net "P5V_VBUS_B")
	)
	(segment
		(start 47.900082 -62.610492)
		(end 47.900082 -63.5)
		(width 0.508)
		(layer "F.Cu")
		(net "P5V_VBUS_B")
	)
	(segment
		(start 47.900082 -63.5)
		(end 47.900082 -64.389508)
		(width 0.508)
		(layer "F.Cu")
		(net "P5V_VBUS_B")
	)
	(segment
		(start 47.900082 -63.5)
		(end 48.78959 -63.5)
		(width 0.508)
		(layer "F.Cu")
		(net "P5V_VBUS_B")
	)
	(via
		(at 43.336718 -69.037962)
		(size 0.6604)
		(drill 0.3302)
		(layers "F.Cu" "B.Cu")
		(net "P5V_VBUS_B")
	)
	(segment
		(start 7.199884 -62.610492)
		(end 7.199884 -63.5)
		(width 0.508)
		(layer "F.Cu")
		(net "P5V_VBUS_A")
	)
	(segment
		(start 7.199884 -63.5)
		(end 8.089392 -63.5)
		(width 0.508)
		(layer "F.Cu")
		(net "P5V_VBUS_A")
	)
	(segment
		(start 7.199884 -63.5)
		(end 7.199884 -64.389508)
		(width 0.508)
		(layer "F.Cu")
		(net "P5V_VBUS_A")
	)
	(segment
		(start 6.310376 -63.5)
		(end 7.199884 -63.5)
		(width 0.508)
		(layer "F.Cu")
		(net "P5V_VBUS_A")
	)
	(via
		(at 2.955544 -57.66689)
		(size 0.6604)
		(drill 0.3302)
		(layers "F.Cu" "B.Cu")
		(net "P5V_VBUS_A")
	)
	(segment
		(start 56.052212 -73.1139)
		(end 56.052212 -72.240648)
		(width 0.508)
		(layer "F.Cu")
		(net "P5V_USB_B")
	)
	(segment
		(start 56.063642 -73.12533)
		(end 56.052212 -73.1139)
		(width 0.508)
		(layer "F.Cu")
		(net "P5V_USB_B")
	)
	(segment
		(start 49.424082 -39.751)
		(end 50.6984 -39.751)
		(width 0.762)
		(layer "F.Cu")
		(net "P5V_USB_B")
	)
	(via
		(at 50.6984 -39.751)
		(size 0.5588)
		(drill 0.3048)
		(layers "F.Cu" "B.Cu")
		(net "P5V_USB_B")
	)
	(via
		(at 49.768506 -70.855586)
		(size 0.7112)
		(drill 0.4064)
		(layers "F.Cu" "B.Cu")
		(net "P5V_USB_B")
	)
	(via
		(at 56.052212 -72.240648)
		(size 0.5588)
		(drill 0.3048)
		(layers "F.Cu" "B.Cu")
		(net "P5V_USB_B")
	)
	(via
		(at 29.57322 -4.208526)
		(size 0.7112)
		(drill 0.4064)
		(layers "F.Cu" "B.Cu")
		(net "P5V_USB_B")
	)
	(via
		(at 48.613314 -70.842124)
		(size 0.7112)
		(drill 0.4064)
		(layers "F.Cu" "B.Cu")
		(net "P5V_USB_B")
	)
	(segment
		(start 10.060686 -40.573452)
		(end 10.533634 -41.0464)
		(width 0.508)
		(layer "F.Cu")
		(net "P5V_USB_A")
	)
	(segment
		(start 13.5636 -41.0972)
		(end 11.684 -41.0972)
		(width 0.508)
		(layer "F.Cu")
		(net "P5V_USB_A")
	)
	(segment
		(start 14.3256 -40.3352)
		(end 13.5636 -41.0972)
		(width 0.508)
		(layer "F.Cu")
		(net "P5V_USB_A")
	)
	(segment
		(start 12.769088 -72.395588)
		(end 14.0208 -72.395588)
		(width 0.508)
		(layer "F.Cu")
		(net "P5V_USB_A")
	)
	(segment
		(start 11.6332 -41.0464)
		(end 11.684 -41.0972)
		(width 0.508)
		(layer "F.Cu")
		(net "P5V_USB_A")
	)
	(segment
		(start 10.533634 -41.0464)
		(end 11.6332 -41.0464)
		(width 0.508)
		(layer "F.Cu")
		(net "P5V_USB_A")
	)
	(via
		(at 4.313936 -63.181992)
		(size 0.7112)
		(drill 0.4064)
		(layers "F.Cu" "B.Cu")
		(net "P5V_USB_A")
	)
	(via
		(at 4.312158 -62.050676)
		(size 0.7112)
		(drill 0.4064)
		(layers "F.Cu" "B.Cu")
		(net "P5V_USB_A")
	)
	(via
		(at 14.3256 -40.3352)
		(size 0.5588)
		(drill 0.3048)
		(layers "F.Cu" "B.Cu")
		(net "P5V_USB_A")
	)
	(via
		(at 27.306524 -4.246626)
		(size 0.7112)
		(drill 0.4064)
		(layers "F.Cu" "B.Cu")
		(net "P5V_USB_A")
	)
	(via
		(at 14.0208 -72.395588)
		(size 0.5588)
		(drill 0.3048)
		(layers "F.Cu" "B.Cu")
		(net "P5V_USB_A")
	)
	(via
		(at 11.684 -41.0972)
		(size 0.6604)
		(drill 0.3302)
		(layers "F.Cu" "B.Cu")
		(net "P5V_USB_A")
	)
	(segment
		(start 54.5719 -29.2608)
		(end 54.51348 -29.31922)
		(width 0.3048)
		(layer "F.Cu")
		(net "P3V3_STBY_B")
	)
	(segment
		(start 54.9529 -53.349652)
		(end 56.757316 -53.349652)
		(width 0.508)
		(layer "F.Cu")
		(net "P3V3_STBY_B")
	)
	(segment
		(start 43.603164 -20.51812)
		(end 44.3484 -20.51812)
		(width 0.3556)
		(layer "F.Cu")
		(net "P3V3_STBY_B")
	)
	(segment
		(start 47.8155 -15.886684)
		(end 47.8155 -16.764)
		(width 0.508)
		(layer "F.Cu")
		(net "P3V3_STBY_B")
	)
	(segment
		(start 46.9265 -9.779)
		(end 46.609 -10.0965)
		(width 0.3048)
		(layer "F.Cu")
		(net "P3V3_STBY_B")
	)
	(segment
		(start 55.6641 -47.0662)
		(end 56.6928 -47.0662)
		(width 0.508)
		(layer "F.Cu")
		(net "P3V3_STBY_B")
	)
	(segment
		(start 56.6928 -47.0662)
		(end 56.6928 -46.3296)
		(width 0.508)
		(layer "F.Cu")
		(net "P3V3_STBY_B")
	)
	(segment
		(start 43.925998 -17.814544)
		(end 45.005244 -17.814544)
		(width 0.508)
		(layer "F.Cu")
		(net "P3V3_STBY_B")
	)
	(segment
		(start 44.7802 -10.2743)
		(end 44.731432 -10.323068)
		(width 0.4064)
		(layer "F.Cu")
		(net "P3V3_STBY_B")
	)
	(segment
		(start 51.749452 -31.429452)
		(end 50.408586 -31.429452)
		(width 0.508)
		(layer "F.Cu")
		(net "P3V3_STBY_B")
	)
	(segment
		(start 53.721 -31.6992)
		(end 52.019454 -31.6992)
		(width 0.508)
		(layer "F.Cu")
		(net "P3V3_STBY_B")
	)
	(segment
		(start 44.914312 -10.2743)
		(end 44.7802 -10.2743)
		(width 0.508)
		(layer "F.Cu")
		(net "P3V3_STBY_B")
	)
	(segment
		(start 44.731432 -10.323068)
		(end 43.167808 -10.323068)
		(width 0.4064)
		(layer "F.Cu")
		(net "P3V3_STBY_B")
	)
	(segment
		(start 48.943514 -21.395436)
		(end 48.951896 -21.387054)
		(width 0.508)
		(layer "F.Cu")
		(net "P3V3_STBY_B")
	)
	(segment
		(start 30.7213 -5.7404)
		(end 31.5722 -5.7404)
		(width 0.508)
		(layer "F.Cu")
		(net "P3V3_STBY_B")
	)
	(segment
		(start 45.426122 -16.549878)
		(end 45.426122 -15.9258)
		(width 0.508)
		(layer "F.Cu")
		(net "P3V3_STBY_B")
	)
	(segment
		(start 54.2798 -32.258254)
		(end 54.03088 -32.009334)
		(width 0.508)
		(layer "F.Cu")
		(net "P3V3_STBY_B")
	)
	(segment
		(start 42.917364 -21.20392)
		(end 43.603164 -20.51812)
		(width 0.3556)
		(layer "F.Cu")
		(net "P3V3_STBY_B")
	)
	(segment
		(start 51.70678 -28.448)
		(end 54.483 -28.448)
		(width 0.508)
		(layer "F.Cu")
		(net "P3V3_STBY_B")
	)
	(segment
		(start 54.51348 -29.31922)
		(end 53.333904 -29.31922)
		(width 0.3048)
		(layer "F.Cu")
		(net "P3V3_STBY_B")
	)
	(segment
		(start 47.5996 -20.51812)
		(end 44.3484 -20.51812)
		(width 0.3556)
		(layer "F.Cu")
		(net "P3V3_STBY_B")
	)
	(segment
		(start 54.5592 -32.590486)
		(end 54.2798 -32.311086)
		(width 0.508)
		(layer "F.Cu")
		(net "P3V3_STBY_B")
	)
	(segment
		(start 33.6804 -8.6741)
		(end 33.619186 -8.735314)
		(width 0.3048)
		(layer "F.Cu")
		(net "P3V3_STBY_B")
	)
	(segment
		(start 50.3936 -15.60068)
		(end 50.3936 -14.583918)
		(width 0.3556)
		(layer "F.Cu")
		(net "P3V3_STBY_B")
	)
	(segment
		(start 41.8719 -11.5951)
		(end 41.402 -11.1252)
		(width 0.508)
		(layer "F.Cu")
		(net "P3V3_STBY_B")
	)
	(segment
		(start 53.872892 -6.349492)
		(end 53.8226 -6.2992)
		(width 0.508)
		(layer "F.Cu")
		(net "P3V3_STBY_B")
	)
	(segment
		(start 45.005244 -17.814544)
		(end 45.0215 -17.8308)
		(width 0.508)
		(layer "F.Cu")
		(net "P3V3_STBY_B")
	)
	(segment
		(start 53.743098 -31.721298)
		(end 53.721 -31.6992)
		(width 0.508)
		(layer "F.Cu")
		(net "P3V3_STBY_B")
	)
	(segment
		(start 51.30038 -28.8544)
		(end 51.70678 -28.448)
		(width 0.508)
		(layer "F.Cu")
		(net "P3V3_STBY_B")
	)
	(segment
		(start 53.218588 -12.385548)
		(end 53.218588 -12.12977)
		(width 0.508)
		(layer "F.Cu")
		(net "P3V3_STBY_B")
	)
	(segment
		(start 50.3936 -14.583918)
		(end 50.23104 -14.421358)
		(width 0.3556)
		(layer "F.Cu")
		(net "P3V3_STBY_B")
	)
	(segment
		(start 54.497478 -6.56717)
		(end 54.2798 -6.349492)
		(width 0.508)
		(layer "F.Cu")
		(net "P3V3_STBY_B")
	)
	(segment
		(start 54.5719 -28.5369)
		(end 54.5719 -29.2608)
		(width 0.508)
		(layer "F.Cu")
		(net "P3V3_STBY_B")
	)
	(segment
		(start 54.741064 -33.61309)
		(end 55.5498 -33.61309)
		(width 0.508)
		(layer "F.Cu")
		(net "P3V3_STBY_B")
	)
	(segment
		(start 54.03088 -32.009334)
		(end 54.03088 -31.94431)
		(width 0.508)
		(layer "F.Cu")
		(net "P3V3_STBY_B")
	)
	(segment
		(start 50.408586 -31.429452)
		(end 49.840134 -30.861)
		(width 0.508)
		(layer "F.Cu")
		(net "P3V3_STBY_B")
	)
	(segment
		(start 46.609 -10.0965)
		(end 46.349412 -10.0965)
		(width 0.508)
		(layer "F.Cu")
		(net "P3V3_STBY_B")
	)
	(segment
		(start 53.218588 -12.12977)
		(end 52.652422 -11.563604)
		(width 0.508)
		(layer "F.Cu")
		(net "P3V3_STBY_B")
	)
	(segment
		(start 54.4703 -51.2826)
		(end 54.4703 -52.4764)
		(width 0.508)
		(layer "F.Cu")
		(net "P3V3_STBY_B")
	)
	(segment
		(start 41.7195 -13.82776)
		(end 41.7195 -13.3223)
		(width 0.4064)
		(layer "F.Cu")
		(net "P3V3_STBY_B")
	)
	(segment
		(start 48.4759 -9.779)
		(end 46.9265 -9.779)
		(width 0.3048)
		(layer "F.Cu")
		(net "P3V3_STBY_B")
	)
	(segment
		(start 42.909744 -20.183602)
		(end 42.909744 -21.1963)
		(width 0.508)
		(layer "F.Cu")
		(net "P3V3_STBY_B")
	)
	(segment
		(start 54.6862 -27.44724)
		(end 54.8132 -27.32024)
		(width 0.4064)
		(layer "F.Cu")
		(net "P3V3_STBY_B")
	)
	(segment
		(start 33.8963 -6.096)
		(end 33.8963 -7.3025)
		(width 0.508)
		(layer "F.Cu")
		(net "P3V3_STBY_B")
	)
	(segment
		(start 33.6804 -7.5184)
		(end 33.6804 -8.6741)
		(width 0.508)
		(layer "F.Cu")
		(net "P3V3_STBY_B")
	)
	(segment
		(start 48.951896 -20.51812)
		(end 47.5996 -20.51812)
		(width 0.3556)
		(layer "F.Cu")
		(net "P3V3_STBY_B")
	)
	(segment
		(start 47.9425 -22.39645)
		(end 48.943514 -21.395436)
		(width 0.508)
		(layer "F.Cu")
		(net "P3V3_STBY_B")
	)
	(segment
		(start 45.0215 -17.8308)
		(end 45.0215 -16.9545)
		(width 0.508)
		(layer "F.Cu")
		(net "P3V3_STBY_B")
	)
	(segment
		(start 54.8132 -27.32024)
		(end 55.626 -27.32024)
		(width 0.508)
		(layer "F.Cu")
		(net "P3V3_STBY_B")
	)
	(segment
		(start 56.6928 -46.3296)
		(end 56.5912 -46.228)
		(width 0.508)
		(layer "F.Cu")
		(net "P3V3_STBY_B")
	)
	(segment
		(start 54.2798 -6.349492)
		(end 53.872892 -6.349492)
		(width 0.508)
		(layer "F.Cu")
		(net "P3V3_STBY_B")
	)
	(segment
		(start 45.489622 -9.69899)
		(end 44.914312 -10.2743)
		(width 0.508)
		(layer "F.Cu")
		(net "P3V3_STBY_B")
	)
	(segment
		(start 47.9425 -22.86)
		(end 47.9425 -22.39645)
		(width 0.508)
		(layer "F.Cu")
		(net "P3V3_STBY_B")
	)
	(segment
		(start 53.2257 -27.44724)
		(end 54.6862 -27.44724)
		(width 0.4064)
		(layer "F.Cu")
		(net "P3V3_STBY_B")
	)
	(segment
		(start 47.8155 -16.764)
		(end 47.8155 -17.8308)
		(width 0.508)
		(layer "F.Cu")
		(net "P3V3_STBY_B")
	)
	(segment
		(start 48.951896 -21.387054)
		(end 48.951896 -20.51812)
		(width 0.508)
		(layer "F.Cu")
		(net "P3V3_STBY_B")
	)
	(segment
		(start 54.4703 -52.4764)
		(end 54.4449 -52.5018)
		(width 0.508)
		(layer "F.Cu")
		(net "P3V3_STBY_B")
	)
	(segment
		(start 55.4482 -9.0805)
		(end 55.4482 -8.3058)
		(width 0.508)
		(layer "F.Cu")
		(net "P3V3_STBY_B")
	)
	(segment
		(start 54.4703 -51.0159)
		(end 54.4703 -51.2826)
		(width 0.3556)
		(layer "F.Cu")
		(net "P3V3_STBY_B")
	)
	(segment
		(start 52.72786 -49.76876)
		(end 53.22316 -49.76876)
		(width 0.3556)
		(layer "F.Cu")
		(net "P3V3_STBY_B")
	)
	(segment
		(start 45.72 -10.7315)
		(end 45.593 -10.8585)
		(width 0.508)
		(layer "F.Cu")
		(net "P3V3_STBY_B")
	)
	(segment
		(start 54.03088 -31.94431)
		(end 53.807868 -31.721298)
		(width 0.508)
		(layer "F.Cu")
		(net "P3V3_STBY_B")
	)
	(segment
		(start 41.8719 -13.1699)
		(end 41.8719 -12.2428)
		(width 0.4064)
		(layer "F.Cu")
		(net "P3V3_STBY_B")
	)
	(segment
		(start 42.909744 -21.1963)
		(end 42.917364 -21.20392)
		(width 0.508)
		(layer "F.Cu")
		(net "P3V3_STBY_B")
	)
	(segment
		(start 54.706012 -6.56717)
		(end 54.497478 -6.56717)
		(width 0.508)
		(layer "F.Cu")
		(net "P3V3_STBY_B")
	)
	(segment
		(start 30.4927 -5.969)
		(end 30.7213 -5.7404)
		(width 0.508)
		(layer "F.Cu")
		(net "P3V3_STBY_B")
	)
	(segment
		(start 50.23104 -14.421358)
		(end 49.41824 -14.421358)
		(width 0.508)
		(layer "F.Cu")
		(net "P3V3_STBY_B")
	)
	(segment
		(start 41.8719 -12.2428)
		(end 41.8719 -11.5951)
		(width 0.508)
		(layer "F.Cu")
		(net "P3V3_STBY_B")
	)
	(segment
		(start 45.426122 -15.9258)
		(end 45.426122 -14.986)
		(width 0.508)
		(layer "F.Cu")
		(net "P3V3_STBY_B")
	)
	(segment
		(start 33.619186 -8.735314)
		(end 32.45358 -8.735314)
		(width 0.3048)
		(layer "F.Cu")
		(net "P3V3_STBY_B")
	)
	(segment
		(start 33.8963 -7.3025)
		(end 33.6804 -7.5184)
		(width 0.508)
		(layer "F.Cu")
		(net "P3V3_STBY_B")
	)
	(segment
		(start 45.72 -10.725912)
		(end 45.72 -10.7315)
		(width 0.508)
		(layer "F.Cu")
		(net "P3V3_STBY_B")
	)
	(segment
		(start 54.483 -28.448)
		(end 54.5719 -28.5369)
		(width 0.508)
		(layer "F.Cu")
		(net "P3V3_STBY_B")
	)
	(segment
		(start 54.4449 -52.841652)
		(end 54.9529 -53.349652)
		(width 0.508)
		(layer "F.Cu")
		(net "P3V3_STBY_B")
	)
	(segment
		(start 56.757316 -53.349652)
		(end 56.896 -53.488336)
		(width 0.508)
		(layer "F.Cu")
		(net "P3V3_STBY_B")
	)
	(segment
		(start 55.583328 -32.590486)
		(end 54.5592 -32.590486)
		(width 0.508)
		(layer "F.Cu")
		(net "P3V3_STBY_B")
	)
	(segment
		(start 51.941984 -31.621984)
		(end 51.749452 -31.429452)
		(width 0.508)
		(layer "F.Cu")
		(net "P3V3_STBY_B")
	)
	(segment
		(start 52.019454 -31.6992)
		(end 51.942238 -31.621984)
		(width 0.508)
		(layer "F.Cu")
		(net "P3V3_STBY_B")
	)
	(segment
		(start 51.942238 -31.621984)
		(end 51.941984 -31.621984)
		(width 0.508)
		(layer "F.Cu")
		(net "P3V3_STBY_B")
	)
	(segment
		(start 55.753 -13.5001)
		(end 56.542686 -13.5001)
		(width 0.508)
		(layer "F.Cu")
		(net "P3V3_STBY_B")
	)
	(segment
		(start 54.4449 -52.5018)
		(end 54.4449 -52.841652)
		(width 0.508)
		(layer "F.Cu")
		(net "P3V3_STBY_B")
	)
	(segment
		(start 41.7195 -13.3223)
		(end 41.8719 -13.1699)
		(width 0.4064)
		(layer "F.Cu")
		(net "P3V3_STBY_B")
	)
	(segment
		(start 53.22316 -49.76876)
		(end 54.4703 -51.0159)
		(width 0.3556)
		(layer "F.Cu")
		(net "P3V3_STBY_B")
	)
	(segment
		(start 46.349412 -10.0965)
		(end 45.72 -10.725912)
		(width 0.508)
		(layer "F.Cu")
		(net "P3V3_STBY_B")
	)
	(segment
		(start 45.0215 -16.9545)
		(end 45.426122 -16.549878)
		(width 0.508)
		(layer "F.Cu")
		(net "P3V3_STBY_B")
	)
	(segment
		(start 53.807868 -31.721298)
		(end 53.743098 -31.721298)
		(width 0.508)
		(layer "F.Cu")
		(net "P3V3_STBY_B")
	)
	(segment
		(start 54.2798 -32.311086)
		(end 54.2798 -32.258254)
		(width 0.508)
		(layer "F.Cu")
		(net "P3V3_STBY_B")
	)
	(via
		(at 56.542686 -13.5001)
		(size 0.508)
		(drill 0.254)
		(layers "F.Cu" "B.Cu")
		(net "P3V3_STBY_B")
	)
	(via
		(at 54.5592 -32.590486)
		(size 0.508)
		(drill 0.254)
		(layers "F.Cu" "B.Cu")
		(net "P3V3_STBY_B")
	)
	(via
		(at 33.8328 -4.508754)
		(size 0.7112)
		(drill 0.4064)
		(layers "F.Cu" "B.Cu")
		(net "P3V3_STBY_B")
	)
	(via
		(at 49.41824 -14.421358)
		(size 0.508)
		(drill 0.254)
		(layers "F.Cu" "B.Cu")
		(net "P3V3_STBY_B")
	)
	(via
		(at 47.8155 -16.764)
		(size 0.508)
		(drill 0.254)
		(layers "F.Cu" "B.Cu")
		(net "P3V3_STBY_B")
	)
	(via
		(at 45.489622 -9.69899)
		(size 0.508)
		(drill 0.254)
		(layers "F.Cu" "B.Cu")
		(net "P3V3_STBY_B")
	)
	(via
		(at 56.896 -53.488336)
		(size 0.508)
		(drill 0.254)
		(layers "F.Cu" "B.Cu")
		(net "P3V3_STBY_B")
	)
	(via
		(at 55.4482 -8.3058)
		(size 0.508)
		(drill 0.254)
		(layers "F.Cu" "B.Cu")
		(net "P3V3_STBY_B")
	)
	(via
		(at 56.5912 -46.228)
		(size 0.5588)
		(drill 0.3048)
		(layers "F.Cu" "B.Cu")
		(net "P3V3_STBY_B")
	)
	(via
		(at 45.593 -10.8585)
		(size 0.508)
		(drill 0.254)
		(layers "F.Cu" "B.Cu")
		(net "P3V3_STBY_B")
	)
	(via
		(at 52.652422 -11.563604)
		(size 0.508)
		(drill 0.254)
		(layers "F.Cu" "B.Cu")
		(net "P3V3_STBY_B")
	)
	(via
		(at 54.483 -28.448)
		(size 0.508)
		(drill 0.254)
		(layers "F.Cu" "B.Cu")
		(net "P3V3_STBY_B")
	)
	(via
		(at 48.943514 -21.395436)
		(size 0.508)
		(drill 0.254)
		(layers "F.Cu" "B.Cu")
		(net "P3V3_STBY_B")
	)
	(via
		(at 33.6804 -7.5184)
		(size 0.508)
		(drill 0.254)
		(layers "F.Cu" "B.Cu")
		(net "P3V3_STBY_B")
	)
	(via
		(at 31.5722 -5.7404)
		(size 0.508)
		(drill 0.254)
		(layers "F.Cu" "B.Cu")
		(net "P3V3_STBY_B")
	)
	(via
		(at 41.402 -11.1252)
		(size 0.508)
		(drill 0.254)
		(layers "F.Cu" "B.Cu")
		(net "P3V3_STBY_B")
	)
	(via
		(at 45.426122 -14.986)
		(size 0.508)
		(drill 0.254)
		(layers "F.Cu" "B.Cu")
		(net "P3V3_STBY_B")
	)
	(via
		(at 55.5498 -33.61309)
		(size 0.508)
		(drill 0.254)
		(layers "F.Cu" "B.Cu")
		(net "P3V3_STBY_B")
	)
	(via
		(at 55.626 -27.32024)
		(size 0.508)
		(drill 0.254)
		(layers "F.Cu" "B.Cu")
		(net "P3V3_STBY_B")
	)
	(via
		(at 53.8226 -6.2992)
		(size 0.508)
		(drill 0.254)
		(layers "F.Cu" "B.Cu")
		(net "P3V3_STBY_B")
	)
	(via
		(at 45.426122 -15.9258)
		(size 0.6604)
		(drill 0.3302)
		(layers "F.Cu" "B.Cu")
		(net "P3V3_STBY_B")
	)
	(segment
		(start 57.453022 -52.931314)
		(end 57.453022 -47.902622)
		(width 0.762)
		(layer "B.Cu")
		(net "P3V3_STBY_B")
	)
	(segment
		(start 56.5912 -47.0408)
		(end 56.5912 -46.228)
		(width 0.762)
		(layer "B.Cu")
		(net "P3V3_STBY_B")
	)
	(segment
		(start 56.896 -53.488336)
		(end 57.453022 -52.931314)
		(width 0.762)
		(layer "B.Cu")
		(net "P3V3_STBY_B")
	)
	(segment
		(start 57.453022 -47.902622)
		(end 56.5912 -47.0408)
		(width 0.762)
		(layer "B.Cu")
		(net "P3V3_STBY_B")
	)
	(segment
		(start 25.5651 -10.3251)
		(end 25.359106 -10.119106)
		(width 0.508)
		(layer "F.Cu")
		(net "P3V3_STBY_A")
	)
	(segment
		(start 9.50468 -20.77212)
		(end 8.7376 -20.77212)
		(width 0.3556)
		(layer "F.Cu")
		(net "P3V3_STBY_A")
	)
	(segment
		(start 24.819102 -9.584436)
		(end 24.819102 -9.579102)
		(width 0.508)
		(layer "F.Cu")
		(net "P3V3_STBY_A")
	)
	(segment
		(start 26.61031 -10.804652)
		(end 26.183082 -10.804652)
		(width 0.3048)
		(layer "F.Cu")
		(net "P3V3_STBY_A")
	)
	(segment
		(start 6.9088 -26.4414)
		(end 7.050532 -26.299668)
		(width 0.508)
		(layer "F.Cu")
		(net "P3V3_STBY_A")
	)
	(segment
		(start 3.3401 -21.5265)
		(end 3.0734 -21.5265)
		(width 0.3556)
		(layer "F.Cu")
		(net "P3V3_STBY_A")
	)
	(segment
		(start 26.936192 -11.40079)
		(end 26.936192 -11.130534)
		(width 0.3048)
		(layer "F.Cu")
		(net "P3V3_STBY_A")
	)
	(segment
		(start 6.2103 -30.8229)
		(end 6.096 -30.7086)
		(width 0.508)
		(layer "F.Cu")
		(net "P3V3_STBY_A")
	)
	(segment
		(start 13.894054 -6.7056)
		(end 13.728954 -6.8707)
		(width 0.508)
		(layer "F.Cu")
		(net "P3V3_STBY_A")
	)
	(segment
		(start 26.936192 -12.027408)
		(end 26.936192 -11.40079)
		(width 0.3048)
		(layer "F.Cu")
		(net "P3V3_STBY_A")
	)
	(segment
		(start 12.463272 -50.964846)
		(end 12.463272 -50.643536)
		(width 0.508)
		(layer "F.Cu")
		(net "P3V3_STBY_A")
	)
	(segment
		(start 6.3373 -26.4414)
		(end 6.9088 -26.4414)
		(width 0.508)
		(layer "F.Cu")
		(net "P3V3_STBY_A")
	)
	(segment
		(start 5.9182 -26.8605)
		(end 6.3373 -26.4414)
		(width 0.508)
		(layer "F.Cu")
		(net "P3V3_STBY_A")
	)
	(segment
		(start 13.3096 -43.7007)
		(end 13.3096 -43.0022)
		(width 0.508)
		(layer "F.Cu")
		(net "P3V3_STBY_A")
	)
	(segment
		(start 12.042648 -39.158418)
		(end 11.2014 -39.158418)
		(width 0.508)
		(layer "F.Cu")
		(net "P3V3_STBY_A")
	)
	(segment
		(start 8.001 -27.399742)
		(end 8.001 -27.503628)
		(width 0.3048)
		(layer "F.Cu")
		(net "P3V3_STBY_A")
	)
	(segment
		(start 3.613404 -17.646396)
		(end 4.270502 -17.646396)
		(width 0.508)
		(layer "F.Cu")
		(net "P3V3_STBY_A")
	)
	(segment
		(start 12.372848 -50.553112)
		(end 12.463272 -50.643536)
		(width 0.3556)
		(layer "F.Cu")
		(net "P3V3_STBY_A")
	)
	(segment
		(start 13.728954 -6.8707)
		(end 13.3604 -6.8707)
		(width 0.508)
		(layer "F.Cu")
		(net "P3V3_STBY_A")
	)
	(segment
		(start 1.975612 -21.5265)
		(end 1.438148 -20.989036)
		(width 0.508)
		(layer "F.Cu")
		(net "P3V3_STBY_A")
	)
	(segment
		(start 5.4864 -20.77212)
		(end 8.7376 -20.77212)
		(width 0.3556)
		(layer "F.Cu")
		(net "P3V3_STBY_A")
	)
	(segment
		(start 14.56436 -28.71724)
		(end 13.6525 -29.6291)
		(width 0.381)
		(layer "F.Cu")
		(net "P3V3_STBY_A")
	)
	(segment
		(start 20.1168 -19.3167)
		(end 20.2565 -19.4564)
		(width 0.508)
		(layer "F.Cu")
		(net "P3V3_STBY_A")
	)
	(segment
		(start 19.1897 -13.8811)
		(end 18.542 -14.5288)
		(width 0.508)
		(layer "F.Cu")
		(net "P3V3_STBY_A")
	)
	(segment
		(start 8.4201 -17.02689)
		(end 8.4201 -17.9832)
		(width 0.508)
		(layer "F.Cu")
		(net "P3V3_STBY_A")
	)
	(segment
		(start 25.359106 -10.119106)
		(end 25.353772 -10.119106)
		(width 0.508)
		(layer "F.Cu")
		(net "P3V3_STBY_A")
	)
	(segment
		(start 26.72715 -12.23645)
		(end 26.936192 -12.027408)
		(width 0.3048)
		(layer "F.Cu")
		(net "P3V3_STBY_A")
	)
	(segment
		(start 3.0734 -18.1864)
		(end 3.613404 -17.646396)
		(width 0.508)
		(layer "F.Cu")
		(net "P3V3_STBY_A")
	)
	(segment
		(start 11.1506 -15.1384)
		(end 11.1506 -15.2654)
		(width 0.3048)
		(layer "F.Cu")
		(net "P3V3_STBY_A")
	)
	(segment
		(start 13.6525 -29.6291)
		(end 13.6525 -30.0482)
		(width 0.381)
		(layer "F.Cu")
		(net "P3V3_STBY_A")
	)
	(segment
		(start 14.002766 -48.124364)
		(end 14.002766 -47.246794)
		(width 0.508)
		(layer "F.Cu")
		(net "P3V3_STBY_A")
	)
	(segment
		(start 20.1168 -18.6817)
		(end 20.1168 -19.3167)
		(width 0.508)
		(layer "F.Cu")
		(net "P3V3_STBY_A")
	)
	(segment
		(start 18.640806 -15.015972)
		(end 18.640806 -15.326106)
		(width 0.508)
		(layer "F.Cu")
		(net "P3V3_STBY_A")
	)
	(segment
		(start 9.44626 -49.99736)
		(end 9.89076 -49.99736)
		(width 0.3556)
		(layer "F.Cu")
		(net "P3V3_STBY_A")
	)
	(segment
		(start 10.4013 -12.8397)
		(end 10.7442 -13.1826)
		(width 0.508)
		(layer "F.Cu")
		(net "P3V3_STBY_A")
	)
	(segment
		(start 11.1506 -15.2654)
		(end 12.0142 -16.129)
		(width 0.3048)
		(layer "F.Cu")
		(net "P3V3_STBY_A")
	)
	(segment
		(start 20.219416 -21.290026)
		(end 20.219416 -22.064726)
		(width 0.381)
		(layer "F.Cu")
		(net "P3V3_STBY_A")
	)
	(segment
		(start 25.70353 -10.3251)
		(end 25.6286 -10.3251)
		(width 0.3048)
		(layer "F.Cu")
		(net "P3V3_STBY_A")
	)
	(segment
		(start 1.438148 -20.989036)
		(end 1.438148 -19.269964)
		(width 0.508)
		(layer "F.Cu")
		(net "P3V3_STBY_A")
	)
	(segment
		(start 15.748 -9.8044)
		(end 16.0782 -9.4742)
		(width 0.4064)
		(layer "F.Cu")
		(net "P3V3_STBY_A")
	)
	(segment
		(start 7.821168 -26.299668)
		(end 7.821168 -26.8351)
		(width 0.3048)
		(layer "F.Cu")
		(net "P3V3_STBY_A")
	)
	(segment
		(start 10.446512 -50.553112)
		(end 12.372848 -50.553112)
		(width 0.3556)
		(layer "F.Cu")
		(net "P3V3_STBY_A")
	)
	(segment
		(start 9.89076 -49.99736)
		(end 10.446512 -50.553112)
		(width 0.3556)
		(layer "F.Cu")
		(net "P3V3_STBY_A")
	)
	(segment
		(start 15.2019 -9.7536)
		(end 15.1511 -9.8044)
		(width 0.4064)
		(layer "F.Cu")
		(net "P3V3_STBY_A")
	)
	(segment
		(start 25.353772 -10.119106)
		(end 24.819102 -9.584436)
		(width 0.508)
		(layer "F.Cu")
		(net "P3V3_STBY_A")
	)
	(segment
		(start 7.050532 -26.299668)
		(end 7.821168 -26.299668)
		(width 0.508)
		(layer "F.Cu")
		(net "P3V3_STBY_A")
	)
	(segment
		(start 5.6261 -17.9832)
		(end 5.289296 -17.646396)
		(width 0.508)
		(layer "F.Cu")
		(net "P3V3_STBY_A")
	)
	(segment
		(start 13.6525 -30.0482)
		(end 12.8016 -30.0482)
		(width 0.508)
		(layer "F.Cu")
		(net "P3V3_STBY_A")
	)
	(segment
		(start 7.1628 -30.8229)
		(end 6.2103 -30.8229)
		(width 0.508)
		(layer "F.Cu")
		(net "P3V3_STBY_A")
	)
	(segment
		(start 12.973304 -51.474878)
		(end 12.463272 -50.964846)
		(width 0.508)
		(layer "F.Cu")
		(net "P3V3_STBY_A")
	)
	(segment
		(start 3.0734 -18.7325)
		(end 3.0734 -18.1864)
		(width 0.508)
		(layer "F.Cu")
		(net "P3V3_STBY_A")
	)
	(segment
		(start 10.538968 -27.776932)
		(end 10.538968 -26.989532)
		(width 0.508)
		(layer "F.Cu")
		(net "P3V3_STBY_A")
	)
	(segment
		(start 3.0734 -21.5265)
		(end 1.975612 -21.5265)
		(width 0.508)
		(layer "F.Cu")
		(net "P3V3_STBY_A")
	)
	(segment
		(start 26.936192 -11.130534)
		(end 26.61031 -10.804652)
		(width 0.3048)
		(layer "F.Cu")
		(net "P3V3_STBY_A")
	)
	(segment
		(start 7.986268 -27.0002)
		(end 7.986268 -27.38501)
		(width 0.3048)
		(layer "F.Cu")
		(net "P3V3_STBY_A")
	)
	(segment
		(start 24.765 -9.525)
		(end 24.765 -9.2964)
		(width 0.508)
		(layer "F.Cu")
		(net "P3V3_STBY_A")
	)
	(segment
		(start 9.8171 -20.4597)
		(end 9.50468 -20.77212)
		(width 0.3556)
		(layer "F.Cu")
		(net "P3V3_STBY_A")
	)
	(segment
		(start 1.438148 -19.269964)
		(end 1.975612 -18.7325)
		(width 0.508)
		(layer "F.Cu")
		(net "P3V3_STBY_A")
	)
	(segment
		(start 12.2301 -12.573)
		(end 12.221972 -12.564872)
		(width 0.3048)
		(layer "F.Cu")
		(net "P3V3_STBY_A")
	)
	(segment
		(start 13.081 -48.641)
		(end 13.48613 -48.641)
		(width 0.508)
		(layer "F.Cu")
		(net "P3V3_STBY_A")
	)
	(segment
		(start 8.504174 -16.942816)
		(end 8.4201 -17.02689)
		(width 0.508)
		(layer "F.Cu")
		(net "P3V3_STBY_A")
	)
	(segment
		(start 24.819102 -9.579102)
		(end 24.765 -9.525)
		(width 0.508)
		(layer "F.Cu")
		(net "P3V3_STBY_A")
	)
	(segment
		(start 15.2019 -9.0043)
		(end 15.2019 -9.7536)
		(width 0.4064)
		(layer "F.Cu")
		(net "P3V3_STBY_A")
	)
	(segment
		(start 10.1981 -14.9352)
		(end 10.9474 -14.9352)
		(width 0.508)
		(layer "F.Cu")
		(net "P3V3_STBY_A")
	)
	(segment
		(start 5.289296 -17.646396)
		(end 4.270502 -17.646396)
		(width 0.508)
		(layer "F.Cu")
		(net "P3V3_STBY_A")
	)
	(segment
		(start 8.4201 -18.7579)
		(end 8.4074 -18.7706)
		(width 0.508)
		(layer "F.Cu")
		(net "P3V3_STBY_A")
	)
	(segment
		(start 25.6286 -10.3251)
		(end 25.5651 -10.3251)
		(width 0.508)
		(layer "F.Cu")
		(net "P3V3_STBY_A")
	)
	(segment
		(start 15.85976 -8.34644)
		(end 15.2019 -9.0043)
		(width 0.4064)
		(layer "F.Cu")
		(net "P3V3_STBY_A")
	)
	(segment
		(start 1.975612 -18.7325)
		(end 3.0734 -18.7325)
		(width 0.508)
		(layer "F.Cu")
		(net "P3V3_STBY_A")
	)
	(segment
		(start 11.30427 -12.564872)
		(end 11.083798 -12.3444)
		(width 0.3048)
		(layer "F.Cu")
		(net "P3V3_STBY_A")
	)
	(segment
		(start 13.3604 -6.8707)
		(end 12.7635 -6.8707)
		(width 0.4064)
		(layer "F.Cu")
		(net "P3V3_STBY_A")
	)
	(segment
		(start 10.4013 -12.3444)
		(end 10.4013 -12.8397)
		(width 0.508)
		(layer "F.Cu")
		(net "P3V3_STBY_A")
	)
	(segment
		(start 3.8227 -21.0439)
		(end 3.3401 -21.5265)
		(width 0.3556)
		(layer "F.Cu")
		(net "P3V3_STBY_A")
	)
	(segment
		(start 12.0142 -16.129)
		(end 12.0142 -16.61668)
		(width 0.3048)
		(layer "F.Cu")
		(net "P3V3_STBY_A")
	)
	(segment
		(start 12.4841 -6.5913)
		(end 11.95324 -6.5913)
		(width 0.4064)
		(layer "F.Cu")
		(net "P3V3_STBY_A")
	)
	(segment
		(start 12.2555 -48.66894)
		(end 13.05306 -48.66894)
		(width 0.508)
		(layer "F.Cu")
		(net "P3V3_STBY_A")
	)
	(segment
		(start 8.4201 -17.9832)
		(end 8.4201 -18.7579)
		(width 0.508)
		(layer "F.Cu")
		(net "P3V3_STBY_A")
	)
	(segment
		(start 10.16 -19.5834)
		(end 10.16 -20.4343)
		(width 0.508)
		(layer "F.Cu")
		(net "P3V3_STBY_A")
	)
	(segment
		(start 10.16 -20.4343)
		(end 10.1346 -20.4597)
		(width 0.508)
		(layer "F.Cu")
		(net "P3V3_STBY_A")
	)
	(segment
		(start 11.083798 -12.3444)
		(end 10.4013 -12.3444)
		(width 0.3048)
		(layer "F.Cu")
		(net "P3V3_STBY_A")
	)
	(segment
		(start 15.85976 -8.1915)
		(end 15.85976 -8.34644)
		(width 0.4064)
		(layer "F.Cu")
		(net "P3V3_STBY_A")
	)
	(segment
		(start 13.05306 -48.66894)
		(end 13.081 -48.641)
		(width 0.508)
		(layer "F.Cu")
		(net "P3V3_STBY_A")
	)
	(segment
		(start 24.7396 -8.226044)
		(end 24.7396 -7.4422)
		(width 0.508)
		(layer "F.Cu")
		(net "P3V3_STBY_A")
	)
	(segment
		(start 14.7955 -28.71724)
		(end 14.56436 -28.71724)
		(width 0.381)
		(layer "F.Cu")
		(net "P3V3_STBY_A")
	)
	(segment
		(start 14.5796 -6.7056)
		(end 13.894054 -6.7056)
		(width 0.508)
		(layer "F.Cu")
		(net "P3V3_STBY_A")
	)
	(segment
		(start 13.48613 -48.641)
		(end 14.002766 -48.124364)
		(width 0.508)
		(layer "F.Cu")
		(net "P3V3_STBY_A")
	)
	(segment
		(start 18.542 -14.5288)
		(end 18.542 -14.917166)
		(width 0.508)
		(layer "F.Cu")
		(net "P3V3_STBY_A")
	)
	(segment
		(start 18.640806 -15.326106)
		(end 18.6817 -15.367)
		(width 0.508)
		(layer "F.Cu")
		(net "P3V3_STBY_A")
	)
	(segment
		(start 13.3096 -43.0022)
		(end 13.0556 -42.7482)
		(width 0.508)
		(layer "F.Cu")
		(net "P3V3_STBY_A")
	)
	(segment
		(start 7.821168 -26.8351)
		(end 7.986268 -27.0002)
		(width 0.3048)
		(layer "F.Cu")
		(net "P3V3_STBY_A")
	)
	(segment
		(start 18.542 -14.917166)
		(end 18.640806 -15.015972)
		(width 0.508)
		(layer "F.Cu")
		(net "P3V3_STBY_A")
	)
	(segment
		(start 9.0805 -23.2156)
		(end 8.1788 -23.2156)
		(width 0.508)
		(layer "F.Cu")
		(net "P3V3_STBY_A")
	)
	(segment
		(start 19.431 -13.8811)
		(end 19.1897 -13.8811)
		(width 0.508)
		(layer "F.Cu")
		(net "P3V3_STBY_A")
	)
	(segment
		(start 12.221972 -12.564872)
		(end 11.30427 -12.564872)
		(width 0.3048)
		(layer "F.Cu")
		(net "P3V3_STBY_A")
	)
	(segment
		(start 10.9474 -14.9352)
		(end 11.1506 -15.1384)
		(width 0.508)
		(layer "F.Cu")
		(net "P3V3_STBY_A")
	)
	(segment
		(start 5.4864 -20.77212)
		(end 4.31038 -20.77212)
		(width 0.3556)
		(layer "F.Cu")
		(net "P3V3_STBY_A")
	)
	(segment
		(start 10.1346 -20.4597)
		(end 9.8171 -20.4597)
		(width 0.3556)
		(layer "F.Cu")
		(net "P3V3_STBY_A")
	)
	(segment
		(start 15.1511 -9.8044)
		(end 15.748 -9.8044)
		(width 0.4064)
		(layer "F.Cu")
		(net "P3V3_STBY_A")
	)
	(segment
		(start 24.777954 -8.264398)
		(end 24.7396 -8.226044)
		(width 0.508)
		(layer "F.Cu")
		(net "P3V3_STBY_A")
	)
	(segment
		(start 14.002766 -47.246794)
		(end 13.840968 -47.084996)
		(width 0.508)
		(layer "F.Cu")
		(net "P3V3_STBY_A")
	)
	(segment
		(start 4.0386 -21.0439)
		(end 3.8227 -21.0439)
		(width 0.3556)
		(layer "F.Cu")
		(net "P3V3_STBY_A")
	)
	(segment
		(start 4.31038 -20.77212)
		(end 4.0386 -21.0439)
		(width 0.3556)
		(layer "F.Cu")
		(net "P3V3_STBY_A")
	)
	(segment
		(start 7.986268 -27.38501)
		(end 8.001 -27.399742)
		(width 0.3048)
		(layer "F.Cu")
		(net "P3V3_STBY_A")
	)
	(segment
		(start 12.7635 -6.8707)
		(end 12.4841 -6.5913)
		(width 0.4064)
		(layer "F.Cu")
		(net "P3V3_STBY_A")
	)
	(segment
		(start 26.183082 -10.804652)
		(end 25.70353 -10.3251)
		(width 0.3048)
		(layer "F.Cu")
		(net "P3V3_STBY_A")
	)
	(segment
		(start 24.910034 -12.23645)
		(end 26.72715 -12.23645)
		(width 0.3048)
		(layer "F.Cu")
		(net "P3V3_STBY_A")
	)
	(via
		(at 24.7396 -7.4422)
		(size 0.508)
		(drill 0.254)
		(layers "F.Cu" "B.Cu")
		(net "P3V3_STBY_A")
	)
	(via
		(at 10.538968 -26.989532)
		(size 0.508)
		(drill 0.254)
		(layers "F.Cu" "B.Cu")
		(net "P3V3_STBY_A")
	)
	(via
		(at 24.765 -9.2964)
		(size 0.508)
		(drill 0.254)
		(layers "F.Cu" "B.Cu")
		(net "P3V3_STBY_A")
	)
	(via
		(at 13.0556 -42.7482)
		(size 0.508)
		(drill 0.254)
		(layers "F.Cu" "B.Cu")
		(net "P3V3_STBY_A")
	)
	(via
		(at 4.270502 -17.646396)
		(size 0.6604)
		(drill 0.3302)
		(layers "F.Cu" "B.Cu")
		(net "P3V3_STBY_A")
	)
	(via
		(at 6.096 -30.7086)
		(size 0.508)
		(drill 0.254)
		(layers "F.Cu" "B.Cu")
		(net "P3V3_STBY_A")
	)
	(via
		(at 18.542 -14.5288)
		(size 0.508)
		(drill 0.254)
		(layers "F.Cu" "B.Cu")
		(net "P3V3_STBY_A")
	)
	(via
		(at 8.4074 -18.7706)
		(size 0.508)
		(drill 0.254)
		(layers "F.Cu" "B.Cu")
		(net "P3V3_STBY_A")
	)
	(via
		(at 11.1506 -15.1384)
		(size 0.508)
		(drill 0.254)
		(layers "F.Cu" "B.Cu")
		(net "P3V3_STBY_A")
	)
	(via
		(at 20.219416 -22.064726)
		(size 0.508)
		(drill 0.254)
		(layers "F.Cu" "B.Cu")
		(net "P3V3_STBY_A")
	)
	(via
		(at 14.5796 -6.7056)
		(size 0.508)
		(drill 0.254)
		(layers "F.Cu" "B.Cu")
		(net "P3V3_STBY_A")
	)
	(via
		(at 10.16 -19.5834)
		(size 0.508)
		(drill 0.254)
		(layers "F.Cu" "B.Cu")
		(net "P3V3_STBY_A")
	)
	(via
		(at 24.4348 -4.1656)
		(size 0.7112)
		(drill 0.4064)
		(layers "F.Cu" "B.Cu")
		(net "P3V3_STBY_A")
	)
	(via
		(at 12.8016 -30.0482)
		(size 0.508)
		(drill 0.254)
		(layers "F.Cu" "B.Cu")
		(net "P3V3_STBY_A")
	)
	(via
		(at 16.0782 -9.4742)
		(size 0.508)
		(drill 0.254)
		(layers "F.Cu" "B.Cu")
		(net "P3V3_STBY_A")
	)
	(via
		(at 8.1788 -23.2156)
		(size 0.508)
		(drill 0.254)
		(layers "F.Cu" "B.Cu")
		(net "P3V3_STBY_A")
	)
	(via
		(at 13.081 -48.641)
		(size 0.5588)
		(drill 0.3048)
		(layers "F.Cu" "B.Cu")
		(net "P3V3_STBY_A")
	)
	(via
		(at 20.2565 -19.4564)
		(size 0.508)
		(drill 0.254)
		(layers "F.Cu" "B.Cu")
		(net "P3V3_STBY_A")
	)
	(via
		(at 6.9088 -26.4414)
		(size 0.508)
		(drill 0.254)
		(layers "F.Cu" "B.Cu")
		(net "P3V3_STBY_A")
	)
	(via
		(at 12.973304 -51.474878)
		(size 0.5588)
		(drill 0.3048)
		(layers "F.Cu" "B.Cu")
		(net "P3V3_STBY_A")
	)
	(via
		(at 10.7442 -13.1826)
		(size 0.508)
		(drill 0.254)
		(layers "F.Cu" "B.Cu")
		(net "P3V3_STBY_A")
	)
	(via
		(at 11.2014 -39.158418)
		(size 0.5588)
		(drill 0.3048)
		(layers "F.Cu" "B.Cu")
		(net "P3V3_STBY_A")
	)
	(segment
		(start 48.951896 -18.696686)
		(end 48.951896 -19.62912)
		(width 0.508)
		(layer "F.Cu")
		(net "GND")
	)
	(segment
		(start 8.001 -29.0322)
		(end 8.001 -28.504388)
		(width 0.254)
		(layer "F.Cu")
		(net "GND")
	)
	(segment
		(start 30.4927 -7.4041)
		(end 30.2768 -7.62)
		(width 0.508)
		(layer "F.Cu")
		(net "GND")
	)
	(segment
		(start 53.920898 -10.025126)
		(end 53.674772 -9.779)
		(width 0.254)
		(layer "F.Cu")
		(net "GND")
	)
	(segment
		(start 35.5854 -3.556)
		(end 35.5854 -3.0226)
		(width 0.3556)
		(layer "F.Cu")
		(net "GND")
	)
	(segment
		(start 46.9392 -28.6004)
		(end 46.9392 -29.1084)
		(width 0.508)
		(layer "F.Cu")
		(net "GND")
	)
	(segment
		(start 35.5854 -3.0226)
		(end 35.265106 -2.702306)
		(width 0.3556)
		(layer "F.Cu")
		(net "GND")
	)
	(segment
		(start 56.065928 -12.481306)
		(end 56.065928 -11.693906)
		(width 0.508)
		(layer "F.Cu")
		(net "GND")
	)
	(segment
		(start 54.7116 -22.5806)
		(end 54.88432 -22.75332)
		(width 0.254)
		(layer "F.Cu")
		(net "GND")
	)
	(segment
		(start 2.02819 -56.448198)
		(end 2.02819 -56.203596)
		(width 0.254)
		(layer "F.Cu")
		(net "GND")
	)
	(segment
		(start 52.023772 -30.0736)
		(end 52.0446 -30.052772)
		(width 0.254)
		(layer "F.Cu")
		(net "GND")
	)
	(segment
		(start 55.626 -26.43124)
		(end 54.8132 -26.43124)
		(width 0.508)
		(layer "F.Cu")
		(net "GND")
	)
	(segment
		(start 10.1346 -21.3487)
		(end 10.1346 -21.5646)
		(width 0.508)
		(layer "F.Cu")
		(net "GND")
	)
	(segment
		(start 19.1262 -16.2306)
		(end 19.0754 -16.2306)
		(width 0.508)
		(layer "F.Cu")
		(net "GND")
	)
	(segment
		(start 52.0446 -30.052772)
		(end 52.0446 -30.0482)
		(width 0.254)
		(layer "F.Cu")
		(net "GND")
	)
	(segment
		(start 13.1445 -27.41676)
		(end 12.0142 -27.41676)
		(width 0.381)
		(layer "F.Cu")
		(net "GND")
	)
	(segment
		(start 14.5415 -30.4419)
		(end 14.1478 -30.8356)
		(width 0.508)
		(layer "F.Cu")
		(net "GND")
	)
	(segment
		(start 12.2682 -43.1038)
		(end 12.0142 -42.8498)
		(width 0.254)
		(layer "F.Cu")
		(net "GND")
	)
	(segment
		(start 48.895 -17.8435)
		(end 48.895 -18.63979)
		(width 0.508)
		(layer "F.Cu")
		(net "GND")
	)
	(segment
		(start 47.2694 -47.371)
		(end 47.580804 -47.371)
		(width 0.3556)
		(layer "F.Cu")
		(net "GND")
	)
	(segment
		(start 6.7818 -48.04664)
		(end 5.33654 -48.04664)
		(width 0.3556)
		(layer "F.Cu")
		(net "GND")
	)
	(segment
		(start 55.4609 -28.4226)
		(end 55.4609 -29.2608)
		(width 0.508)
		(layer "F.Cu")
		(net "GND")
	)
	(segment
		(start 42.917364 -22.09292)
		(end 44.3484 -22.09292)
		(width 0.508)
		(layer "F.Cu")
		(net "GND")
	)
	(segment
		(start 8.710168 -26.299668)
		(end 8.710168 -26.930604)
		(width 0.381)
		(layer "F.Cu")
		(net "GND")
	)
	(segment
		(start 4.24307 -22.7076)
		(end 3.9878 -22.45233)
		(width 0.254)
		(layer "F.Cu")
		(net "GND")
	)
	(segment
		(start 33.6804 -9.5631)
		(end 33.655 -9.5885)
		(width 0.508)
		(layer "F.Cu")
		(net "GND")
	)
	(segment
		(start 56.515 -8.9154)
		(end 56.515 -9.8425)
		(width 0.508)
		(layer "F.Cu")
		(net "GND")
	)
	(segment
		(start 8.710168 -26.930604)
		(end 8.8646 -27.085036)
		(width 0.381)
		(layer "F.Cu")
		(net "GND")
	)
	(segment
		(start 4.4958 -29.2608)
		(end 4.4958 -28.5115)
		(width 0.254)
		(layer "F.Cu")
		(net "GND")
	)
	(segment
		(start 13.05306 -49.68494)
		(end 13.0556 -49.6824)
		(width 0.508)
		(layer "F.Cu")
		(net "GND")
	)
	(segment
		(start 14.3764 -8.6106)
		(end 14.3764 -8.7757)
		(width 0.254)
		(layer "F.Cu")
		(net "GND")
	)
	(segment
		(start 43.1165 -15.875)
		(end 43.3705 -15.621)
		(width 0.4064)
		(layer "F.Cu")
		(net "GND")
	)
	(segment
		(start 12.2555 -49.68494)
		(end 13.05306 -49.68494)
		(width 0.508)
		(layer "F.Cu")
		(net "GND")
	)
	(segment
		(start 8.8646 -27.085036)
		(end 8.8646 -27.112468)
		(width 0.381)
		(layer "F.Cu")
		(net "GND")
	)
	(segment
		(start 16.210026 -2.911094)
		(end 16.210026 -1.599946)
		(width 0.508)
		(layer "F.Cu")
		(net "GND")
	)
	(segment
		(start 2.02819 -56.203596)
		(end 1.57988 -55.755286)
		(width 0.254)
		(layer "F.Cu")
		(net "GND")
	)
	(segment
		(start 17.324832 -12.573)
		(end 16.3703 -12.573)
		(width 0.254)
		(layer "F.Cu")
		(net "GND")
	)
	(segment
		(start 3.700526 -41.660826)
		(end 3.700526 -42.539158)
		(width 0.254)
		(layer "F.Cu")
		(net "GND")
	)
	(segment
		(start 13.07846 -47.65294)
		(end 13.081 -47.6504)
		(width 0.508)
		(layer "F.Cu")
		(net "GND")
	)
	(segment
		(start 5.7912 -28.6004)
		(end 6.5024 -28.6004)
		(width 0.254)
		(layer "F.Cu")
		(net "GND")
	)
	(segment
		(start 16.240252 -2.94132)
		(end 16.210026 -2.911094)
		(width 0.508)
		(layer "F.Cu")
		(net "GND")
	)
	(segment
		(start 42.889932 -3.048)
		(end 42.885106 -3.043174)
		(width 0.508)
		(layer "F.Cu")
		(net "GND")
	)
	(segment
		(start 52.285392 -50.707798)
		(end 53.006498 -50.707798)
		(width 0.508)
		(layer "F.Cu")
		(net "GND")
	)
	(segment
		(start 20.1168 -15.8877)
		(end 19.4691 -15.8877)
		(width 0.508)
		(layer "F.Cu")
		(net "GND")
	)
	(segment
		(start 13.3604 -5.9817)
		(end 13.3604 -5.8928)
		(width 0.508)
		(layer "F.Cu")
		(net "GND")
	)
	(segment
		(start 44.1452 -11.1633)
		(end 43.8912 -11.4173)
		(width 0.508)
		(layer "F.Cu")
		(net "GND")
	)
	(segment
		(start 5.739892 -39.310818)
		(end 5.739892 -38.20668)
		(width 0.508)
		(layer "F.Cu")
		(net "GND")
	)
	(segment
		(start 53.410104 -30.988)
		(end 53.333904 -30.9118)
		(width 0.254)
		(layer "F.Cu")
		(net "GND")
	)
	(segment
		(start 40.9829 -12.2428)
		(end 40.9829 -13.0683)
		(width 0.254)
		(layer "F.Cu")
		(net "GND")
	)
	(segment
		(start 13.352272 -50.643536)
		(end 14.41577 -50.643536)
		(width 0.508)
		(layer "F.Cu")
		(net "GND")
	)
	(segment
		(start 50.3174 -26.416)
		(end 50.58664 -26.14676)
		(width 0.254)
		(layer "F.Cu")
		(net "GND")
	)
	(segment
		(start 10.65276 -9.13384)
		(end 10.65276 -8.2423)
		(width 0.4064)
		(layer "F.Cu")
		(net "GND")
	)
	(segment
		(start 9.078976 -12.777724)
		(end 9.078976 -13.193776)
		(width 0.254)
		(layer "F.Cu")
		(net "GND")
	)
	(segment
		(start 55.6641 -46.0502)
		(end 55.6641 -45.212)
		(width 0.508)
		(layer "F.Cu")
		(net "GND")
	)
	(segment
		(start 54.818534 -55.464202)
		(end 54.386226 -55.031894)
		(width 0.254)
		(layer "F.Cu")
		(net "GND")
	)
	(segment
		(start 10.6045 -30.099)
		(end 10.6045 -29.4005)
		(width 0.508)
		(layer "F.Cu")
		(net "GND")
	)
	(segment
		(start 27.8257 -13.1572)
		(end 28.6766 -13.1572)
		(width 0.508)
		(layer "F.Cu")
		(net "GND")
	)
	(segment
		(start 44.7802 -11.1633)
		(end 44.1452 -11.1633)
		(width 0.508)
		(layer "F.Cu")
		(net "GND")
	)
	(segment
		(start 44.2849 -12.3952)
		(end 44.2849 -13.1953)
		(width 0.508)
		(layer "F.Cu")
		(net "GND")
	)
	(segment
		(start 54.818534 -56.19242)
		(end 54.818534 -55.464202)
		(width 0.254)
		(layer "F.Cu")
		(net "GND")
	)
	(segment
		(start 19.4691 -15.8877)
		(end 19.1262 -16.2306)
		(width 0.508)
		(layer "F.Cu")
		(net "GND")
	)
	(segment
		(start 17.639284 -12.258548)
		(end 17.324832 -12.573)
		(width 0.254)
		(layer "F.Cu")
		(net "GND")
	)
	(segment
		(start 25.6286 -11.2141)
		(end 24.6888 -11.2141)
		(width 0.508)
		(layer "F.Cu")
		(net "GND")
	)
	(segment
		(start 43.3705 -15.621)
		(end 43.3705 -15.12824)
		(width 0.4064)
		(layer "F.Cu")
		(net "GND")
	)
	(segment
		(start 9.5123 -12.3444)
		(end 9.078976 -12.777724)
		(width 0.254)
		(layer "F.Cu")
		(net "GND")
	)
	(segment
		(start 9.469374 -17.984216)
		(end 9.469374 -18.739866)
		(width 0.508)
		(layer "F.Cu")
		(net "GND")
	)
	(segment
		(start 18.67408 -23.76932)
		(end 17.653 -23.76932)
		(width 0.3556)
		(layer "F.Cu")
		(net "GND")
	)
	(segment
		(start 52.2732 -29.8196)
		(end 52.713636 -29.8196)
		(width 0.254)
		(layer "F.Cu")
		(net "GND")
	)
	(segment
		(start 19.203416 -22.096984)
		(end 19.2024 -22.098)
		(width 0.508)
		(layer "F.Cu")
		(net "GND")
	)
	(segment
		(start 10.6045 -29.4005)
		(end 10.795 -29.21)
		(width 0.508)
		(layer "F.Cu")
		(net "GND")
	)
	(segment
		(start 20.1041 -11.1125)
		(end 20.066 -11.0744)
		(width 0.508)
		(layer "F.Cu")
		(net "GND")
	)
	(segment
		(start 8.509 -14.9352)
		(end 8.4328 -15.0114)
		(width 0.508)
		(layer "F.Cu")
		(net "GND")
	)
	(segment
		(start 50.58664 -26.14676)
		(end 51.5747 -26.14676)
		(width 0.254)
		(layer "F.Cu")
		(net "GND")
	)
	(segment
		(start 9.3091 -14.9352)
		(end 8.509 -14.9352)
		(width 0.508)
		(layer "F.Cu")
		(net "GND")
	)
	(segment
		(start 3.9878 -22.45233)
		(end 3.9878 -21.9837)
		(width 0.254)
		(layer "F.Cu")
		(net "GND")
	)
	(segment
		(start 53.674772 -9.779)
		(end 52.6161 -9.779)
		(width 0.254)
		(layer "F.Cu")
		(net "GND")
	)
	(segment
		(start 30.4927 -6.9596)
		(end 30.4927 -7.4041)
		(width 0.508)
		(layer "F.Cu")
		(net "GND")
	)
	(segment
		(start 3.811778 -41.549574)
		(end 3.700526 -41.660826)
		(width 0.254)
		(layer "F.Cu")
		(net "GND")
	)
	(segment
		(start 42.885106 -3.043174)
		(end 42.885106 -1.599946)
		(width 0.508)
		(layer "F.Cu")
		(net "GND")
	)
	(segment
		(start 48.895 -18.63979)
		(end 48.951896 -18.696686)
		(width 0.508)
		(layer "F.Cu")
		(net "GND")
	)
	(segment
		(start 5.1308 -29.6164)
		(end 4.8514 -29.6164)
		(width 0.254)
		(layer "F.Cu")
		(net "GND")
	)
	(segment
		(start 14.3764 -8.7757)
		(end 14.5923 -8.9916)
		(width 0.254)
		(layer "F.Cu")
		(net "GND")
	)
	(segment
		(start 9.469374 -18.739866)
		(end 9.4234 -18.78584)
		(width 0.508)
		(layer "F.Cu")
		(net "GND")
	)
	(segment
		(start 51.506882 -32.749998)
		(end 52.87518 -32.749998)
		(width 0.508)
		(layer "F.Cu")
		(net "GND")
	)
	(segment
		(start 54.88432 -22.75332)
		(end 56.0324 -22.75332)
		(width 0.254)
		(layer "F.Cu")
		(net "GND")
	)
	(segment
		(start 50.23104 -13.532358)
		(end 49.41824 -13.532358)
		(width 0.508)
		(layer "F.Cu")
		(net "GND")
	)
	(segment
		(start 26.4922 -5.6388)
		(end 26.6446 -5.4864)
		(width 0.508)
		(layer "F.Cu")
		(net "GND")
	)
	(segment
		(start 6.5024 -28.6004)
		(end 7.098792 -28.004008)
		(width 0.254)
		(layer "F.Cu")
		(net "GND")
	)
	(segment
		(start 17.16024 -6.5405)
		(end 17.87144 -6.5405)
		(width 0.254)
		(layer "F.Cu")
		(net "GND")
	)
	(segment
		(start 4.4958 -22.7076)
		(end 4.24307 -22.7076)
		(width 0.254)
		(layer "F.Cu")
		(net "GND")
	)
	(segment
		(start 30.2768 -7.62)
		(end 30.2768 -7.8486)
		(width 0.508)
		(layer "F.Cu")
		(net "GND")
	)
	(segment
		(start 14.5415 -30.0482)
		(end 14.5415 -30.4419)
		(width 0.508)
		(layer "F.Cu")
		(net "GND")
	)
	(segment
		(start 4.4323 -21.9329)
		(end 4.94284 -21.42236)
		(width 0.254)
		(layer "F.Cu")
		(net "GND")
	)
	(segment
		(start 10.1346 -21.5646)
		(end 9.525 -22.1742)
		(width 0.508)
		(layer "F.Cu")
		(net "GND")
	)
	(segment
		(start 29.9974 -11.43)
		(end 30.355286 -11.072114)
		(width 0.3048)
		(layer "F.Cu")
		(net "GND")
	)
	(segment
		(start 35.265106 -2.702306)
		(end 35.265106 -1.599946)
		(width 0.3556)
		(layer "F.Cu")
		(net "GND")
	)
	(segment
		(start 14.2621 -9.8044)
		(end 14.2621 -10.5029)
		(width 0.254)
		(layer "F.Cu")
		(net "GND")
	)
	(segment
		(start 46.609 -10.9855)
		(end 46.609 -11.6332)
		(width 0.508)
		(layer "F.Cu")
		(net "GND")
	)
	(segment
		(start 4.224782 -32.749998)
		(end 5.685282 -32.749998)
		(width 0.508)
		(layer "F.Cu")
		(net "GND")
	)
	(segment
		(start 4.94284 -21.42236)
		(end 5.4864 -21.42236)
		(width 0.254)
		(layer "F.Cu")
		(net "GND")
	)
	(segment
		(start 19.203416 -21.290026)
		(end 19.203416 -22.096984)
		(width 0.508)
		(layer "F.Cu")
		(net "GND")
	)
	(segment
		(start 20.024852 -2.946908)
		(end 20.020026 -2.942082)
		(width 0.508)
		(layer "F.Cu")
		(net "GND")
	)
	(segment
		(start 20.020026 -2.942082)
		(end 20.020026 -1.599946)
		(width 0.508)
		(layer "F.Cu")
		(net "GND")
	)
	(segment
		(start 4.0386 -21.9329)
		(end 4.4323 -21.9329)
		(width 0.254)
		(layer "F.Cu")
		(net "GND")
	)
	(segment
		(start 55.4609 -29.2608)
		(end 55.4609 -30.226)
		(width 0.508)
		(layer "F.Cu")
		(net "GND")
	)
	(segment
		(start 46.9392 -29.1084)
		(end 47.2186 -29.3878)
		(width 0.508)
		(layer "F.Cu")
		(net "GND")
	)
	(segment
		(start 20.1041 -11.938)
		(end 20.1041 -11.1125)
		(width 0.508)
		(layer "F.Cu")
		(net "GND")
	)
	(segment
		(start 47.580804 -47.371)
		(end 48.027844 -47.81804)
		(width 0.3556)
		(layer "F.Cu")
		(net "GND")
	)
	(segment
		(start 3.9878 -21.9837)
		(end 4.0386 -21.9329)
		(width 0.254)
		(layer "F.Cu")
		(net "GND")
	)
	(segment
		(start 33.6804 -12.8397)
		(end 33.6804 -13.6652)
		(width 0.508)
		(layer "F.Cu")
		(net "GND")
	)
	(segment
		(start 53.333904 -30.9118)
		(end 53.333904 -30.31998)
		(width 0.254)
		(layer "F.Cu")
		(net "GND")
	)
	(segment
		(start 14.4145 -8.5725)
		(end 14.3764 -8.6106)
		(width 0.254)
		(layer "F.Cu")
		(net "GND")
	)
	(segment
		(start 28.437332 -9.590532)
		(end 28.437332 -9.06399)
		(width 0.254)
		(layer "F.Cu")
		(net "GND")
	)
	(segment
		(start 19.2024 -23.241)
		(end 18.67408 -23.76932)
		(width 0.3556)
		(layer "F.Cu")
		(net "GND")
	)
	(segment
		(start 29.1846 -10.1346)
		(end 28.9814 -10.1346)
		(width 0.254)
		(layer "F.Cu")
		(net "GND")
	)
	(segment
		(start 46.9138 -28.575)
		(end 46.9392 -28.6004)
		(width 0.508)
		(layer "F.Cu")
		(net "GND")
	)
	(segment
		(start 52.0446 -30.0482)
		(end 52.2732 -29.8196)
		(width 0.254)
		(layer "F.Cu")
		(net "GND")
	)
	(segment
		(start 10.414 -9.3726)
		(end 10.65276 -9.13384)
		(width 0.4064)
		(layer "F.Cu")
		(net "GND")
	)
	(segment
		(start 14.2621 -10.5029)
		(end 14.097 -10.668)
		(width 0.254)
		(layer "F.Cu")
		(net "GND")
	)
	(segment
		(start 26.6446 -5.4864)
		(end 26.6446 -5.4356)
		(width 0.508)
		(layer "F.Cu")
		(net "GND")
	)
	(segment
		(start 8.1534 -29.1846)
		(end 8.001 -29.0322)
		(width 0.254)
		(layer "F.Cu")
		(net "GND")
	)
	(segment
		(start 28.9814 -10.1346)
		(end 28.437332 -9.590532)
		(width 0.254)
		(layer "F.Cu")
		(net "GND")
	)
	(segment
		(start 46.609 -11.6332)
		(end 46.4312 -11.811)
		(width 0.508)
		(layer "F.Cu")
		(net "GND")
	)
	(segment
		(start 48.027844 -47.81804)
		(end 48.61814 -47.81804)
		(width 0.3556)
		(layer "F.Cu")
		(net "GND")
	)
	(segment
		(start 30.355286 -11.072114)
		(end 30.95244 -11.072114)
		(width 0.3048)
		(layer "F.Cu")
		(net "GND")
	)
	(segment
		(start 4.8514 -29.6164)
		(end 4.4958 -29.2608)
		(width 0.254)
		(layer "F.Cu")
		(net "GND")
	)
	(segment
		(start 54.74208 -35.687)
		(end 53.594 -35.687)
		(width 0.508)
		(layer "F.Cu")
		(net "GND")
	)
	(segment
		(start 33.655 -9.5885)
		(end 33.655 -10.4648)
		(width 0.508)
		(layer "F.Cu")
		(net "GND")
	)
	(segment
		(start 26.4922 -6.3373)
		(end 26.4922 -5.6388)
		(width 0.508)
		(layer "F.Cu")
		(net "GND")
	)
	(segment
		(start 53.006498 -50.707798)
		(end 53.5813 -51.2826)
		(width 0.508)
		(layer "F.Cu")
		(net "GND")
	)
	(segment
		(start 13.3604 -5.8928)
		(end 12.7254 -5.2578)
		(width 0.508)
		(layer "F.Cu")
		(net "GND")
	)
	(segment
		(start 14.4145 -8.2042)
		(end 14.4145 -8.5725)
		(width 0.254)
		(layer "F.Cu")
		(net "GND")
	)
	(segment
		(start 44.2849 -13.1953)
		(end 44.2722 -13.208)
		(width 0.508)
		(layer "F.Cu")
		(net "GND")
	)
	(segment
		(start 40.9829 -13.0683)
		(end 40.9702 -13.081)
		(width 0.254)
		(layer "F.Cu")
		(net "GND")
	)
	(segment
		(start 7.098792 -28.004008)
		(end 7.380732 -28.004008)
		(width 0.254)
		(layer "F.Cu")
		(net "GND")
	)
	(segment
		(start 12.2682 -43.7007)
		(end 12.2682 -43.1038)
		(width 0.254)
		(layer "F.Cu")
		(net "GND")
	)
	(segment
		(start 41.516808 -9.022588)
		(end 41.516808 -8.2169)
		(width 0.4064)
		(layer "F.Cu")
		(net "GND")
	)
	(segment
		(start 12.2555 -47.65294)
		(end 13.07846 -47.65294)
		(width 0.508)
		(layer "F.Cu")
		(net "GND")
	)
	(segment
		(start 44.3484 -22.09292)
		(end 44.3484 -21.16836)
		(width 0.254)
		(layer "F.Cu")
		(net "GND")
	)
	(via
		(at 53.920898 -10.025126)
		(size 0.5588)
		(drill 0.3048)
		(layers "F.Cu" "B.Cu")
		(net "GND")
	)
	(via
		(at 53.8226 -85.725)
		(size 0.508)
		(drill 0.254)
		(layers "F.Cu" "B.Cu")
		(net "GND")
	)
	(via
		(at 58.0644 -10.668)
		(size 0.508)
		(drill 0.254)
		(layers "F.Cu" "B.Cu")
		(net "GND")
	)
	(via
		(at 15.3162 -84.2772)
		(size 0.508)
		(drill 0.254)
		(layers "F.Cu" "B.Cu")
		(net "GND")
	)
	(via
		(at 1.0668 -83.566)
		(size 0.508)
		(drill 0.254)
		(layers "F.Cu" "B.Cu")
		(net "GND")
	)
	(via
		(at 20.066 -11.0744)
		(size 0.508)
		(drill 0.254)
		(layers "F.Cu" "B.Cu")
		(net "GND")
	)
	(via
		(at 20.735036 -28.332176)
		(size 0.5588)
		(drill 0.3048)
		(layers "F.Cu" "B.Cu")
		(net "GND")
	)
	(via
		(at 1.0668 -79.2734)
		(size 0.508)
		(drill 0.254)
		(layers "F.Cu" "B.Cu")
		(net "GND")
	)
	(via
		(at 9.4234 -18.78584)
		(size 0.508)
		(drill 0.254)
		(layers "F.Cu" "B.Cu")
		(net "GND")
	)
	(via
		(at 48.895 -18.63979)
		(size 0.508)
		(drill 0.254)
		(layers "F.Cu" "B.Cu")
		(net "GND")
	)
	(via
		(at 23.925022 -25.307798)
		(size 0.5588)
		(drill 0.3048)
		(layers "F.Cu" "B.Cu")
		(net "GND")
	)
	(via
		(at 12.0142 -27.41676)
		(size 0.508)
		(drill 0.254)
		(layers "F.Cu" "B.Cu")
		(net "GND")
	)
	(via
		(at 54.457854 -71.598536)
		(size 0.508)
		(drill 0.254)
		(layers "F.Cu" "B.Cu")
		(net "GND")
	)
	(via
		(at 5.334 -13.589)
		(size 0.5588)
		(drill 0.3048)
		(layers "F.Cu" "B.Cu")
		(net "GND")
	)
	(via
		(at 55.4609 -28.4226)
		(size 0.508)
		(drill 0.254)
		(layers "F.Cu" "B.Cu")
		(net "GND")
	)
	(via
		(at 58.039 -85.6234)
		(size 0.508)
		(drill 0.254)
		(layers "F.Cu" "B.Cu")
		(net "GND")
	)
	(via
		(at 3.811778 -41.549574)
		(size 0.508)
		(drill 0.254)
		(layers "F.Cu" "B.Cu")
		(net "GND")
	)
	(via
		(at 29.1846 -10.1346)
		(size 0.508)
		(drill 0.254)
		(layers "F.Cu" "B.Cu")
		(net "GND")
	)
	(via
		(at 46.9138 -28.575)
		(size 0.508)
		(drill 0.254)
		(layers "F.Cu" "B.Cu")
		(net "GND")
	)
	(via
		(at 54.7116 -22.5806)
		(size 0.5588)
		(drill 0.3048)
		(layers "F.Cu" "B.Cu")
		(net "GND")
	)
	(via
		(at 17.87144 -6.5405)
		(size 0.508)
		(drill 0.254)
		(layers "F.Cu" "B.Cu")
		(net "GND")
	)
	(via
		(at 56.5023 -50.673)
		(size 0.5588)
		(drill 0.3048)
		(layers "F.Cu" "B.Cu")
		(net "GND")
	)
	(via
		(at 14.41577 -50.643536)
		(size 0.5588)
		(drill 0.3048)
		(layers "F.Cu" "B.Cu")
		(net "GND")
	)
	(via
		(at 1.524 4.445)
		(size 0.5588)
		(drill 0.3048)
		(layers "F.Cu" "B.Cu")
		(net "GND")
	)
	(via
		(at 5.1308 -29.6164)
		(size 0.5588)
		(drill 0.3048)
		(layers "F.Cu" "B.Cu")
		(net "GND")
	)
	(via
		(at 28.6766 -13.1572)
		(size 0.5588)
		(drill 0.3048)
		(layers "F.Cu" "B.Cu")
		(net "GND")
	)
	(via
		(at 4.4958 -22.7076)
		(size 0.508)
		(drill 0.254)
		(layers "F.Cu" "B.Cu")
		(net "GND")
	)
	(via
		(at 34.5186 -25.2476)
		(size 0.5588)
		(drill 0.3048)
		(layers "F.Cu" "B.Cu")
		(net "GND")
	)
	(via
		(at 12.0142 -42.8498)
		(size 0.508)
		(drill 0.254)
		(layers "F.Cu" "B.Cu")
		(net "GND")
	)
	(via
		(at 19.2024 -23.241)
		(size 0.508)
		(drill 0.254)
		(layers "F.Cu" "B.Cu")
		(net "GND")
	)
	(via
		(at 17.9324 -31.115)
		(size 0.5588)
		(drill 0.3048)
		(layers "F.Cu" "B.Cu")
		(net "GND")
	)
	(via
		(at 56.515 -8.9154)
		(size 0.508)
		(drill 0.254)
		(layers "F.Cu" "B.Cu")
		(net "GND")
	)
	(via
		(at 55.20436 1.76784)
		(size 0.5588)
		(drill 0.3048)
		(layers "F.Cu" "B.Cu")
		(net "GND")
	)
	(via
		(at 33.6804 -13.6652)
		(size 0.508)
		(drill 0.254)
		(layers "F.Cu" "B.Cu")
		(net "GND")
	)
	(via
		(at 15.3162 -73.66)
		(size 0.508)
		(drill 0.254)
		(layers "F.Cu" "B.Cu")
		(net "GND")
	)
	(via
		(at 51.6382 -3.7592)
		(size 0.508)
		(drill 0.254)
		(layers "F.Cu" "B.Cu")
		(net "GND")
	)
	(via
		(at 14.5923 -8.9916)
		(size 0.508)
		(drill 0.254)
		(layers "F.Cu" "B.Cu")
		(net "GND")
	)
	(via
		(at 5.685282 -32.749998)
		(size 0.5588)
		(drill 0.3048)
		(layers "F.Cu" "B.Cu")
		(net "GND")
	)
	(via
		(at 16.6624 -32.5374)
		(size 0.5588)
		(drill 0.3048)
		(layers "F.Cu" "B.Cu")
		(net "GND")
	)
	(via
		(at 34.4932 -17.9832)
		(size 0.5588)
		(drill 0.3048)
		(layers "F.Cu" "B.Cu")
		(net "GND")
	)
	(via
		(at 11.176 -88.9508)
		(size 0.508)
		(drill 0.254)
		(layers "F.Cu" "B.Cu")
		(net "GND")
	)
	(via
		(at 8.8646 -27.112468)
		(size 0.508)
		(drill 0.254)
		(layers "F.Cu" "B.Cu")
		(net "GND")
	)
	(via
		(at 19.2024 -22.098)
		(size 0.508)
		(drill 0.254)
		(layers "F.Cu" "B.Cu")
		(net "GND")
	)
	(via
		(at 56.065928 -11.693906)
		(size 0.508)
		(drill 0.254)
		(layers "F.Cu" "B.Cu")
		(net "GND")
	)
	(via
		(at 1.1176 -88.9762)
		(size 0.508)
		(drill 0.254)
		(layers "F.Cu" "B.Cu")
		(net "GND")
	)
	(via
		(at 47.752 -88.9762)
		(size 0.508)
		(drill 0.254)
		(layers "F.Cu" "B.Cu")
		(net "GND")
	)
	(via
		(at 52.959 -2.3876)
		(size 0.508)
		(drill 0.254)
		(layers "F.Cu" "B.Cu")
		(net "GND")
	)
	(via
		(at 51.506882 -32.749998)
		(size 0.5588)
		(drill 0.3048)
		(layers "F.Cu" "B.Cu")
		(net "GND")
	)
	(via
		(at 55.20436 -0.97536)
		(size 0.5588)
		(drill 0.3048)
		(layers "F.Cu" "B.Cu")
		(net "GND")
	)
	(via
		(at 55.646828 -5.279644)
		(size 0.6604)
		(drill 0.3302)
		(layers "F.Cu" "B.Cu")
		(net "GND")
	)
	(via
		(at 40.9702 -13.081)
		(size 0.508)
		(drill 0.254)
		(layers "F.Cu" "B.Cu")
		(net "GND")
	)
	(via
		(at 1.331976 -65.814956)
		(size 0.5588)
		(drill 0.3048)
		(layers "F.Cu" "B.Cu")
		(net "GND")
	)
	(via
		(at 41.516808 -8.2169)
		(size 0.508)
		(drill 0.254)
		(layers "F.Cu" "B.Cu")
		(net "GND")
	)
	(via
		(at 53.213 -88.9762)
		(size 0.508)
		(drill 0.254)
		(layers "F.Cu" "B.Cu")
		(net "GND")
	)
	(via
		(at 45.401738 -73.329546)
		(size 0.5588)
		(drill 0.3048)
		(layers "F.Cu" "B.Cu")
		(net "GND")
	)
	(via
		(at 4.08686 -0.97536)
		(size 0.5588)
		(drill 0.3048)
		(layers "F.Cu" "B.Cu")
		(net "GND")
	)
	(via
		(at 52.285392 -50.707798)
		(size 0.5588)
		(drill 0.3048)
		(layers "F.Cu" "B.Cu")
		(net "GND")
	)
	(via
		(at 47.2694 -47.371)
		(size 0.5588)
		(drill 0.3048)
		(layers "F.Cu" "B.Cu")
		(net "GND")
	)
	(via
		(at 43.7642 -88.9508)
		(size 0.508)
		(drill 0.254)
		(layers "F.Cu" "B.Cu")
		(net "GND")
	)
	(via
		(at 42.889932 -3.048)
		(size 0.5588)
		(drill 0.3048)
		(layers "F.Cu" "B.Cu")
		(net "GND")
	)
	(via
		(at 46.316138 -74.206608)
		(size 0.5588)
		(drill 0.3048)
		(layers "F.Cu" "B.Cu")
		(net "GND")
	)
	(via
		(at 10.8712 -85.979)
		(size 0.508)
		(drill 0.254)
		(layers "F.Cu" "B.Cu")
		(net "GND")
	)
	(via
		(at 34.2392 -15.3162)
		(size 0.5588)
		(drill 0.3048)
		(layers "F.Cu" "B.Cu")
		(net "GND")
	)
	(via
		(at 17.639284 -12.258548)
		(size 0.508)
		(drill 0.254)
		(layers "F.Cu" "B.Cu")
		(net "GND")
	)
	(via
		(at 54.4068 -82.5754)
		(size 0.508)
		(drill 0.254)
		(layers "F.Cu" "B.Cu")
		(net "GND")
	)
	(via
		(at 1.0922 -9.8298)
		(size 0.5588)
		(drill 0.3048)
		(layers "F.Cu" "B.Cu")
		(net "GND")
	)
	(via
		(at 6.67258 -71.766938)
		(size 0.508)
		(drill 0.254)
		(layers "F.Cu" "B.Cu")
		(net "GND")
	)
	(via
		(at 58.0136 -88.9508)
		(size 0.508)
		(drill 0.254)
		(layers "F.Cu" "B.Cu")
		(net "GND")
	)
	(via
		(at 14.1478 -30.8356)
		(size 0.508)
		(drill 0.254)
		(layers "F.Cu" "B.Cu")
		(net "GND")
	)
	(via
		(at 44.644564 -30.897322)
		(size 0.6604)
		(drill 0.3302)
		(layers "F.Cu" "B.Cu")
		(net "GND")
	)
	(via
		(at 54.386226 -55.031894)
		(size 0.508)
		(drill 0.254)
		(layers "F.Cu" "B.Cu")
		(net "GND")
	)
	(via
		(at 10.414 -9.3726)
		(size 0.508)
		(drill 0.254)
		(layers "F.Cu" "B.Cu")
		(net "GND")
	)
	(via
		(at 52.023772 -30.0736)
		(size 0.508)
		(drill 0.254)
		(layers "F.Cu" "B.Cu")
		(net "GND")
	)
	(via
		(at 15.367 -80.3656)
		(size 0.508)
		(drill 0.254)
		(layers "F.Cu" "B.Cu")
		(net "GND")
	)
	(via
		(at 24.6888 -11.2141)
		(size 0.508)
		(drill 0.254)
		(layers "F.Cu" "B.Cu")
		(net "GND")
	)
	(via
		(at 58.0136 5.4356)
		(size 0.508)
		(drill 0.254)
		(layers "F.Cu" "B.Cu")
		(net "GND")
	)
	(via
		(at 50.8508 -87.3506)
		(size 0.508)
		(drill 0.254)
		(layers "F.Cu" "B.Cu")
		(net "GND")
	)
	(via
		(at 39.2938 -29.591)
		(size 0.5588)
		(drill 0.3048)
		(layers "F.Cu" "B.Cu")
		(net "GND")
	)
	(via
		(at 8.1534 -29.1846)
		(size 0.508)
		(drill 0.254)
		(layers "F.Cu" "B.Cu")
		(net "GND")
	)
	(via
		(at 12.7254 -5.2578)
		(size 0.508)
		(drill 0.254)
		(layers "F.Cu" "B.Cu")
		(net "GND")
	)
	(via
		(at 55.3212 -3.6322)
		(size 0.508)
		(drill 0.254)
		(layers "F.Cu" "B.Cu")
		(net "GND")
	)
	(via
		(at 43.1165 -15.875)
		(size 0.508)
		(drill 0.254)
		(layers "F.Cu" "B.Cu")
		(net "GND")
	)
	(via
		(at 57.8612 -81.8388)
		(size 0.508)
		(drill 0.254)
		(layers "F.Cu" "B.Cu")
		(net "GND")
	)
	(via
		(at 58.0644 -21.8186)
		(size 0.508)
		(drill 0.254)
		(layers "F.Cu" "B.Cu")
		(net "GND")
	)
	(via
		(at 25.908 -15.8496)
		(size 0.5588)
		(drill 0.3048)
		(layers "F.Cu" "B.Cu")
		(net "GND")
	)
	(via
		(at 8.4328 -15.0114)
		(size 0.508)
		(drill 0.254)
		(layers "F.Cu" "B.Cu")
		(net "GND")
	)
	(via
		(at 26.6446 -5.4356)
		(size 0.508)
		(drill 0.254)
		(layers "F.Cu" "B.Cu")
		(net "GND")
	)
	(via
		(at 5.1054 -88.9762)
		(size 0.508)
		(drill 0.254)
		(layers "F.Cu" "B.Cu")
		(net "GND")
	)
	(via
		(at 4.3434 -70.6882)
		(size 0.508)
		(drill 0.254)
		(layers "F.Cu" "B.Cu")
		(net "GND")
	)
	(via
		(at 56.8706 -51.6128)
		(size 0.6604)
		(drill 0.3302)
		(layers "F.Cu" "B.Cu")
		(net "GND")
	)
	(via
		(at 25.8064 -25.3238)
		(size 0.5588)
		(drill 0.3048)
		(layers "F.Cu" "B.Cu")
		(net "GND")
	)
	(via
		(at 9.078976 -13.193776)
		(size 0.508)
		(drill 0.254)
		(layers "F.Cu" "B.Cu")
		(net "GND")
	)
	(via
		(at 44.3484 -22.09292)
		(size 0.508)
		(drill 0.254)
		(layers "F.Cu" "B.Cu")
		(net "GND")
	)
	(via
		(at 55.7022 3.5306)
		(size 0.508)
		(drill 0.254)
		(layers "F.Cu" "B.Cu")
		(net "GND")
	)
	(via
		(at 49.41824 -13.532358)
		(size 0.508)
		(drill 0.254)
		(layers "F.Cu" "B.Cu")
		(net "GND")
	)
	(via
		(at 43.7642 -85.7504)
		(size 0.508)
		(drill 0.254)
		(layers "F.Cu" "B.Cu")
		(net "GND")
	)
	(via
		(at 55.5498 -49.2506)
		(size 0.5588)
		(drill 0.3048)
		(layers "F.Cu" "B.Cu")
		(net "GND")
	)
	(via
		(at 50.3174 -26.416)
		(size 0.508)
		(drill 0.254)
		(layers "F.Cu" "B.Cu")
		(net "GND")
	)
	(via
		(at 1.0414 -3.1242)
		(size 0.5588)
		(drill 0.3048)
		(layers "F.Cu" "B.Cu")
		(net "GND")
	)
	(via
		(at 6.7818 -48.04664)
		(size 0.5588)
		(drill 0.3048)
		(layers "F.Cu" "B.Cu")
		(net "GND")
	)
	(via
		(at 16.240252 -2.94132)
		(size 0.5588)
		(drill 0.3048)
		(layers "F.Cu" "B.Cu")
		(net "GND")
	)
	(via
		(at 1.57988 -55.755286)
		(size 0.5588)
		(drill 0.3048)
		(layers "F.Cu" "B.Cu")
		(net "GND")
	)
	(via
		(at 13.0556 -49.6824)
		(size 0.5588)
		(drill 0.3048)
		(layers "F.Cu" "B.Cu")
		(net "GND")
	)
	(via
		(at 56.896 -77.724)
		(size 0.508)
		(drill 0.254)
		(layers "F.Cu" "B.Cu")
		(net "GND")
	)
	(via
		(at 58.0644 -17.5768)
		(size 0.508)
		(drill 0.254)
		(layers "F.Cu" "B.Cu")
		(net "GND")
	)
	(via
		(at 15.3416 -88.9762)
		(size 0.508)
		(drill 0.254)
		(layers "F.Cu" "B.Cu")
		(net "GND")
	)
	(via
		(at 14.097 -10.668)
		(size 0.508)
		(drill 0.254)
		(layers "F.Cu" "B.Cu")
		(net "GND")
	)
	(via
		(at 13.081 -47.6504)
		(size 0.5588)
		(drill 0.3048)
		(layers "F.Cu" "B.Cu")
		(net "GND")
	)
	(via
		(at 44.2722 -13.208)
		(size 0.508)
		(drill 0.254)
		(layers "F.Cu" "B.Cu")
		(net "GND")
	)
	(via
		(at 5.7912 -28.6004)
		(size 0.508)
		(drill 0.254)
		(layers "F.Cu" "B.Cu")
		(net "GND")
	)
	(via
		(at 58.0136 -5.7912)
		(size 0.508)
		(drill 0.254)
		(layers "F.Cu" "B.Cu")
		(net "GND")
	)
	(via
		(at 1.100582 -61.470794)
		(size 0.5588)
		(drill 0.3048)
		(layers "F.Cu" "B.Cu")
		(net "GND")
	)
	(via
		(at 4.7244 -86.0552)
		(size 0.508)
		(drill 0.254)
		(layers "F.Cu" "B.Cu")
		(net "GND")
	)
	(via
		(at 35.5854 -3.556)
		(size 0.5588)
		(drill 0.3048)
		(layers "F.Cu" "B.Cu")
		(net "GND")
	)
	(via
		(at 47.8282 -87.2236)
		(size 0.508)
		(drill 0.254)
		(layers "F.Cu" "B.Cu")
		(net "GND")
	)
	(via
		(at 19.3294 -29.9212)
		(size 0.5588)
		(drill 0.3048)
		(layers "F.Cu" "B.Cu")
		(net "GND")
	)
	(via
		(at 57.9882 -1.5494)
		(size 0.508)
		(drill 0.254)
		(layers "F.Cu" "B.Cu")
		(net "GND")
	)
	(via
		(at 55.626 -26.43124)
		(size 0.508)
		(drill 0.254)
		(layers "F.Cu" "B.Cu")
		(net "GND")
	)
	(via
		(at 9.525 -22.1742)
		(size 0.508)
		(drill 0.254)
		(layers "F.Cu" "B.Cu")
		(net "GND")
	)
	(via
		(at 5.79628 -71.779638)
		(size 0.508)
		(drill 0.254)
		(layers "F.Cu" "B.Cu")
		(net "GND")
	)
	(via
		(at 5.739892 -38.20668)
		(size 0.5588)
		(drill 0.3048)
		(layers "F.Cu" "B.Cu")
		(net "GND")
	)
	(via
		(at 53.594 -35.687)
		(size 0.508)
		(drill 0.254)
		(layers "F.Cu" "B.Cu")
		(net "GND")
	)
	(via
		(at 48.4378 -32.3596)
		(size 0.5588)
		(drill 0.3048)
		(layers "F.Cu" "B.Cu")
		(net "GND")
	)
	(via
		(at 55.20436 0.85344)
		(size 0.5588)
		(drill 0.3048)
		(layers "F.Cu" "B.Cu")
		(net "GND")
	)
	(via
		(at 47.2948 -3.7846)
		(size 0.508)
		(drill 0.254)
		(layers "F.Cu" "B.Cu")
		(net "GND")
	)
	(via
		(at 1.0414 -74.9046)
		(size 0.508)
		(drill 0.254)
		(layers "F.Cu" "B.Cu")
		(net "GND")
	)
	(via
		(at 50.678334 -73.25106)
		(size 0.5588)
		(drill 0.3048)
		(layers "F.Cu" "B.Cu")
		(net "GND")
	)
	(via
		(at 29.9974 -11.43)
		(size 0.508)
		(drill 0.254)
		(layers "F.Cu" "B.Cu")
		(net "GND")
	)
	(via
		(at 3.5814 -12.3698)
		(size 0.6604)
		(drill 0.3302)
		(layers "F.Cu" "B.Cu")
		(net "GND")
	)
	(via
		(at 55.6641 -45.212)
		(size 0.5588)
		(drill 0.3048)
		(layers "F.Cu" "B.Cu")
		(net "GND")
	)
	(via
		(at 20.024852 -2.946908)
		(size 0.5588)
		(drill 0.3048)
		(layers "F.Cu" "B.Cu")
		(net "GND")
	)
	(via
		(at 43.8912 -11.4173)
		(size 0.508)
		(drill 0.254)
		(layers "F.Cu" "B.Cu")
		(net "GND")
	)
	(via
		(at 24.7904 -23.4188)
		(size 0.5588)
		(drill 0.3048)
		(layers "F.Cu" "B.Cu")
		(net "GND")
	)
	(via
		(at 37.2618 -27.5336)
		(size 0.5588)
		(drill 0.3048)
		(layers "F.Cu" "B.Cu")
		(net "GND")
	)
	(via
		(at 3.4671 -70.7009)
		(size 0.508)
		(drill 0.254)
		(layers "F.Cu" "B.Cu")
		(net "GND")
	)
	(via
		(at 56.515 -87.503)
		(size 0.508)
		(drill 0.254)
		(layers "F.Cu" "B.Cu")
		(net "GND")
	)
	(via
		(at 55.8546 -83.947)
		(size 0.508)
		(drill 0.254)
		(layers "F.Cu" "B.Cu")
		(net "GND")
	)
	(via
		(at 54.714394 -68.706746)
		(size 0.508)
		(drill 0.254)
		(layers "F.Cu" "B.Cu")
		(net "GND")
	)
	(via
		(at 30.2768 -7.8486)
		(size 0.508)
		(drill 0.254)
		(layers "F.Cu" "B.Cu")
		(net "GND")
	)
	(via
		(at 1.175766 -16.470122)
		(size 0.5588)
		(drill 0.3048)
		(layers "F.Cu" "B.Cu")
		(net "GND")
	)
	(via
		(at 10.8204 -32.766)
		(size 0.5588)
		(drill 0.3048)
		(layers "F.Cu" "B.Cu")
		(net "GND")
	)
	(via
		(at 50.687478 -74.17308)
		(size 0.5588)
		(drill 0.3048)
		(layers "F.Cu" "B.Cu")
		(net "GND")
	)
	(via
		(at 7.366 -86.0044)
		(size 0.508)
		(drill 0.254)
		(layers "F.Cu" "B.Cu")
		(net "GND")
	)
	(via
		(at 52.959 5.588)
		(size 0.508)
		(drill 0.254)
		(layers "F.Cu" "B.Cu")
		(net "GND")
	)
	(via
		(at 53.410104 -30.988)
		(size 0.508)
		(drill 0.254)
		(layers "F.Cu" "B.Cu")
		(net "GND")
	)
	(via
		(at 22.2504 -27.0256)
		(size 0.5588)
		(drill 0.3048)
		(layers "F.Cu" "B.Cu")
		(net "GND")
	)
	(via
		(at 49.0982 -85.8266)
		(size 0.508)
		(drill 0.254)
		(layers "F.Cu" "B.Cu")
		(net "GND")
	)
	(via
		(at 4.08686 1.76784)
		(size 0.5588)
		(drill 0.3048)
		(layers "F.Cu" "B.Cu")
		(net "GND")
	)
	(via
		(at 56.0197 -77.7367)
		(size 0.508)
		(drill 0.254)
		(layers "F.Cu" "B.Cu")
		(net "GND")
	)
	(via
		(at 46.4312 -11.811)
		(size 0.508)
		(drill 0.254)
		(layers "F.Cu" "B.Cu")
		(net "GND")
	)
	(via
		(at 4.08686 0.85344)
		(size 0.5588)
		(drill 0.3048)
		(layers "F.Cu" "B.Cu")
		(net "GND")
	)
	(via
		(at 33.655 -10.4648)
		(size 0.508)
		(drill 0.254)
		(layers "F.Cu" "B.Cu")
		(net "GND")
	)
	(via
		(at 19.0754 -16.2306)
		(size 0.508)
		(drill 0.254)
		(layers "F.Cu" "B.Cu")
		(net "GND")
	)
	(via
		(at 31.5722 -25.273)
		(size 0.5588)
		(drill 0.3048)
		(layers "F.Cu" "B.Cu")
		(net "GND")
	)
	(via
		(at 55.20436 -0.06096)
		(size 0.5588)
		(drill 0.3048)
		(layers "F.Cu" "B.Cu")
		(net "GND")
	)
	(via
		(at 15.3416 -77.6986)
		(size 0.508)
		(drill 0.254)
		(layers "F.Cu" "B.Cu")
		(net "GND")
	)
	(via
		(at 10.795 -29.21)
		(size 0.508)
		(drill 0.254)
		(layers "F.Cu" "B.Cu")
		(net "GND")
	)
	(via
		(at 24.892 -17.3228)
		(size 0.5588)
		(drill 0.3048)
		(layers "F.Cu" "B.Cu")
		(net "GND")
	)
	(via
		(at 4.08686 -0.06096)
		(size 0.5588)
		(drill 0.3048)
		(layers "F.Cu" "B.Cu")
		(net "GND")
	)
	(segment
		(start 10.700004 -76.999846)
		(end 10.700004 -78.016354)
		(width 0.508)
		(layer "B.Cu")
		(net "GND")
	)
	(segment
		(start 51.400202 -76.999846)
		(end 51.400202 -78.016354)
		(width 0.508)
		(layer "B.Cu")
		(net "GND")
	)
	(segment
		(start 10.700004 -75.983338)
		(end 10.700004 -76.999846)
		(width 0.508)
		(layer "B.Cu")
		(net "GND")
	)
	(segment
		(start 50.383694 -76.999846)
		(end 51.400202 -76.999846)
		(width 0.508)
		(layer "B.Cu")
		(net "GND")
	)
	(segment
		(start 10.700004 -76.999846)
		(end 11.716512 -76.999846)
		(width 0.508)
		(layer "B.Cu")
		(net "GND")
	)
	(segment
		(start 51.400202 -76.999846)
		(end 52.41671 -76.999846)
		(width 0.508)
		(layer "B.Cu")
		(net "GND")
	)
	(segment
		(start 51.400202 -75.983338)
		(end 51.400202 -76.999846)
		(width 0.508)
		(layer "B.Cu")
		(net "GND")
	)
	(segment
		(start 9.683496 -76.999846)
		(end 10.700004 -76.999846)
		(width 0.508)
		(layer "B.Cu")
		(net "GND")
	)
	(segment
		(start 43.7896 -43.3832)
		(end 43.7896 -34.0614)
		(width 0.17145)
		(layer "F.Cu")
		(net "FAULT_LED_B")
	)
	(segment
		(start 43.7896 -34.0614)
		(end 42.926 -33.1978)
		(width 0.17145)
		(layer "F.Cu")
		(net "FAULT_LED_B")
	)
	(segment
		(start 45.6438 -45.2374)
		(end 43.7896 -43.3832)
		(width 0.17145)
		(layer "F.Cu")
		(net "FAULT_LED_B")
	)
	(segment
		(start 35.334956 -22.685756)
		(end 40.2844 -27.6352)
		(width 0.17145)
		(layer "F.Cu")
		(net "FAULT_LED_B")
	)
	(segment
		(start 34.247836 -5.248148)
		(end 35.334956 -6.335268)
		(width 0.17145)
		(layer "F.Cu")
		(net "FAULT_LED_B")
	)
	(segment
		(start 49.170082 -43.999912)
		(end 47.932594 -45.2374)
		(width 0.17145)
		(layer "F.Cu")
		(net "FAULT_LED_B")
	)
	(segment
		(start 41.588436 -27.6352)
		(end 41.962324 -28.009088)
		(width 0.17145)
		(layer "F.Cu")
		(net "FAULT_LED_B")
	)
	(segment
		(start 42.926 -33.1978)
		(end 42.926 -28.972764)
		(width 0.17145)
		(layer "F.Cu")
		(net "FAULT_LED_B")
	)
	(segment
		(start 30.718252 -3.687064)
		(end 32.279336 -5.248148)
		(width 0.17145)
		(layer "F.Cu")
		(net "FAULT_LED_B")
	)
	(segment
		(start 30.185106 -1.599946)
		(end 30.185106 -3.013456)
		(width 0.17145)
		(layer "F.Cu")
		(net "FAULT_LED_B")
	)
	(segment
		(start 32.279336 -5.248148)
		(end 34.247836 -5.248148)
		(width 0.17145)
		(layer "F.Cu")
		(net "FAULT_LED_B")
	)
	(segment
		(start 35.334956 -6.335268)
		(end 35.334956 -22.685756)
		(width 0.17145)
		(layer "F.Cu")
		(net "FAULT_LED_B")
	)
	(segment
		(start 30.185106 -3.013456)
		(end 30.718252 -3.546602)
		(width 0.17145)
		(layer "F.Cu")
		(net "FAULT_LED_B")
	)
	(segment
		(start 47.932594 -45.2374)
		(end 45.6438 -45.2374)
		(width 0.17145)
		(layer "F.Cu")
		(net "FAULT_LED_B")
	)
	(segment
		(start 30.718252 -3.546602)
		(end 30.718252 -3.687064)
		(width 0.17145)
		(layer "F.Cu")
		(net "FAULT_LED_B")
	)
	(segment
		(start 42.926 -28.972764)
		(end 41.962324 -28.009088)
		(width 0.17145)
		(layer "F.Cu")
		(net "FAULT_LED_B")
	)
	(segment
		(start 40.2844 -27.6352)
		(end 41.588436 -27.6352)
		(width 0.17145)
		(layer "F.Cu")
		(net "FAULT_LED_B")
	)
	(via
		(at 41.962324 -28.009088)
		(size 0.6604)
		(drill 0.3302)
		(layers "F.Cu" "B.Cu")
		(net "FAULT_LED_B")
	)
	(segment
		(start 15.281148 -32.823658)
		(end 15.281148 -33.156398)
		(width 0.17145)
		(layer "F.Cu")
		(net "FAULT_LED_A")
	)
	(segment
		(start 23.891748 -6.888988)
		(end 23.891748 -13.0683)
		(width 0.17145)
		(layer "F.Cu")
		(net "FAULT_LED_A")
	)
	(segment
		(start 15.287752 -41.379648)
		(end 14.722348 -41.945052)
		(width 0.17145)
		(layer "F.Cu")
		(net "FAULT_LED_A")
	)
	(segment
		(start 23.816056 -23.688294)
		(end 23.815548 -23.688802)
		(width 0.17145)
		(layer "F.Cu")
		(net "FAULT_LED_A")
	)
	(segment
		(start 15.287752 -33.163002)
		(end 15.287752 -41.379648)
		(width 0.17145)
		(layer "F.Cu")
		(net "FAULT_LED_A")
	)
	(segment
		(start 14.722348 -41.945052)
		(end 14.0462 -41.945052)
		(width 0.17145)
		(layer "F.Cu")
		(net "FAULT_LED_A")
	)
	(segment
		(start 23.815548 -23.688802)
		(end 23.815548 -24.289258)
		(width 0.17145)
		(layer "F.Cu")
		(net "FAULT_LED_A")
	)
	(segment
		(start 11.524742 -41.945052)
		(end 14.0462 -41.945052)
		(width 0.17145)
		(layer "F.Cu")
		(net "FAULT_LED_A")
	)
	(segment
		(start 26.070052 -1.599946)
		(end 26.070052 -4.710684)
		(width 0.17145)
		(layer "F.Cu")
		(net "FAULT_LED_A")
	)
	(segment
		(start 9.469882 -43.999912)
		(end 11.524742 -41.945052)
		(width 0.17145)
		(layer "F.Cu")
		(net "FAULT_LED_A")
	)
	(segment
		(start 26.070052 -4.710684)
		(end 23.891748 -6.888988)
		(width 0.17145)
		(layer "F.Cu")
		(net "FAULT_LED_A")
	)
	(segment
		(start 23.816056 -17.376902)
		(end 23.816056 -23.688294)
		(width 0.17145)
		(layer "F.Cu")
		(net "FAULT_LED_A")
	)
	(segment
		(start 24.3332 -16.859758)
		(end 23.816056 -17.376902)
		(width 0.17145)
		(layer "F.Cu")
		(net "FAULT_LED_A")
	)
	(segment
		(start 24.3332 -13.509752)
		(end 24.3332 -16.859758)
		(width 0.17145)
		(layer "F.Cu")
		(net "FAULT_LED_A")
	)
	(segment
		(start 15.281148 -33.156398)
		(end 15.287752 -33.163002)
		(width 0.17145)
		(layer "F.Cu")
		(net "FAULT_LED_A")
	)
	(segment
		(start 23.891748 -13.0683)
		(end 24.3332 -13.509752)
		(width 0.17145)
		(layer "F.Cu")
		(net "FAULT_LED_A")
	)
	(segment
		(start 23.815548 -24.289258)
		(end 15.281148 -32.823658)
		(width 0.17145)
		(layer "F.Cu")
		(net "FAULT_LED_A")
	)
	(via
		(at 14.0462 -41.945052)
		(size 0.6604)
		(drill 0.3302)
		(layers "F.Cu" "B.Cu")
		(net "FAULT_LED_A")
	)
	(segment
		(start 45.797978 -58.999882)
		(end 44.245784 -57.447688)
		(width 0.17145)
		(layer "F.Cu")
		(net "DEBUG_USB_B_DP")
	)
	(segment
		(start 44.245784 -57.447688)
		(end 44.245784 -51.214528)
		(width 0.17145)
		(layer "F.Cu")
		(net "DEBUG_USB_B_DP")
	)
	(segment
		(start 44.245784 -51.214528)
		(end 45.355002 -50.10531)
		(width 0.17145)
		(layer "F.Cu")
		(net "DEBUG_USB_B_DP")
	)
	(segment
		(start 45.355002 -50.10531)
		(end 45.355002 -50.041556)
		(width 0.17145)
		(layer "F.Cu")
		(net "DEBUG_USB_B_DP")
	)
	(segment
		(start 47.900082 -58.999882)
		(end 45.797978 -58.999882)
		(width 0.17145)
		(layer "F.Cu")
		(net "DEBUG_USB_B_DP")
	)
	(segment
		(start 46.836838 -60.999878)
		(end 43.566334 -57.729374)
		(width 0.17145)
		(layer "F.Cu")
		(net "DEBUG_USB_B_DN")
	)
	(segment
		(start 43.566334 -48.971454)
		(end 45.38853 -47.149258)
		(width 0.17145)
		(layer "F.Cu")
		(net "DEBUG_USB_B_DN")
	)
	(segment
		(start 43.566334 -57.729374)
		(end 43.566334 -48.971454)
		(width 0.17145)
		(layer "F.Cu")
		(net "DEBUG_USB_B_DN")
	)
	(segment
		(start 47.900082 -60.999878)
		(end 46.836838 -60.999878)
		(width 0.17145)
		(layer "F.Cu")
		(net "DEBUG_USB_B_DN")
	)
	(segment
		(start 45.38853 -47.149258)
		(end 45.38853 -47.028862)
		(width 0.17145)
		(layer "F.Cu")
		(net "DEBUG_USB_B_DN")
	)
	(segment
		(start 7.199884 -58.999882)
		(end 7.199884 -58.795158)
		(width 0.17145)
		(layer "F.Cu")
		(net "DEBUG_USB_A_DP")
	)
	(segment
		(start 2.131568 -53.726842)
		(end 2.131568 -52.79644)
		(width 0.17145)
		(layer "F.Cu")
		(net "DEBUG_USB_A_DP")
	)
	(segment
		(start 7.199884 -58.795158)
		(end 2.131568 -53.726842)
		(width 0.17145)
		(layer "F.Cu")
		(net "DEBUG_USB_A_DP")
	)
	(segment
		(start 5.83184 -59.631834)
		(end 5.83184 -58.38825)
		(width 0.17145)
		(layer "F.Cu")
		(net "DEBUG_USB_A_DN")
	)
	(segment
		(start 5.83184 -58.38825)
		(end 2.67208 -55.22849)
		(width 0.17145)
		(layer "F.Cu")
		(net "DEBUG_USB_A_DN")
	)
	(segment
		(start 2.67208 -55.22849)
		(end 2.671826 -55.22849)
		(width 0.17145)
		(layer "F.Cu")
		(net "DEBUG_USB_A_DN")
	)
	(segment
		(start 7.199884 -60.999878)
		(end 5.83184 -59.631834)
		(width 0.17145)
		(layer "F.Cu")
		(net "DEBUG_USB_A_DN")
	)
	(segment
		(start 32.7533 -11.9507)
		(end 33.6804 -11.9507)
		(width 0.17145)
		(layer "F.Cu")
		(net "DEBUG_HDR_B_UART_SEL")
	)
	(segment
		(start 34.655506 -8.067294)
		(end 34.655506 -11.801094)
		(width 0.17145)
		(layer "F.Cu")
		(net "DEBUG_HDR_B_UART_SEL")
	)
	(segment
		(start 34.655506 -11.801094)
		(end 34.6456 -11.811)
		(width 0.17145)
		(layer "F.Cu")
		(net "DEBUG_HDR_B_UART_SEL")
	)
	(segment
		(start 51.90236 -18.20164)
		(end 50.3936 -18.20164)
		(width 0.17145)
		(layer "F.Cu")
		(net "DEBUG_HDR_B_UART_SEL")
	)
	(segment
		(start 34.5059 -11.9507)
		(end 34.6456 -11.811)
		(width 0.17145)
		(layer "F.Cu")
		(net "DEBUG_HDR_B_UART_SEL")
	)
	(segment
		(start 32.45358 -11.072114)
		(end 32.45358 -11.65098)
		(width 0.17145)
		(layer "F.Cu")
		(net "DEBUG_HDR_B_UART_SEL")
	)
	(segment
		(start 32.45358 -11.65098)
		(end 32.7533 -11.9507)
		(width 0.17145)
		(layer "F.Cu")
		(net "DEBUG_HDR_B_UART_SEL")
	)
	(segment
		(start 33.6804 -11.9507)
		(end 34.5059 -11.9507)
		(width 0.17145)
		(layer "F.Cu")
		(net "DEBUG_HDR_B_UART_SEL")
	)
	(via
		(at 34.6456 -11.811)
		(size 0.6604)
		(drill 0.3302)
		(layers "F.Cu" "B.Cu")
		(net "DEBUG_HDR_B_UART_SEL")
	)
	(via
		(at 51.90236 -18.20164)
		(size 0.508)
		(drill 0.254)
		(layers "F.Cu" "B.Cu")
		(net "DEBUG_HDR_B_UART_SEL")
	)
	(via
		(at 34.655506 -8.067294)
		(size 0.508)
		(drill 0.254)
		(layers "F.Cu" "B.Cu")
		(net "DEBUG_HDR_B_UART_SEL")
	)
	(segment
		(start 42.3164 -8.9916)
		(end 51.52644 -18.20164)
		(width 0.17145)
		(layer "B.Cu")
		(net "DEBUG_HDR_B_UART_SEL")
	)
	(segment
		(start 51.52644 -18.20164)
		(end 51.90236 -18.20164)
		(width 0.17145)
		(layer "B.Cu")
		(net "DEBUG_HDR_B_UART_SEL")
	)
	(segment
		(start 39.4208 -8.9916)
		(end 42.3164 -8.9916)
		(width 0.17145)
		(layer "B.Cu")
		(net "DEBUG_HDR_B_UART_SEL")
	)
	(segment
		(start 38.496494 -8.067294)
		(end 39.4208 -8.9916)
		(width 0.17145)
		(layer "B.Cu")
		(net "DEBUG_HDR_B_UART_SEL")
	)
	(segment
		(start 34.655506 -8.067294)
		(end 38.496494 -8.067294)
		(width 0.17145)
		(layer "B.Cu")
		(net "DEBUG_HDR_B_UART_SEL")
	)
	(segment
		(start 26.4922 -7.693152)
		(end 26.936192 -8.137144)
		(width 0.17145)
		(layer "F.Cu")
		(net "DEBUG_HDR_A_UART_SEL")
	)
	(segment
		(start 12.0142 -19.21764)
		(end 13.77696 -19.21764)
		(width 0.17145)
		(layer "F.Cu")
		(net "DEBUG_HDR_A_UART_SEL")
	)
	(segment
		(start 15.494 -17.5006)
		(end 15.494 -15.367)
		(width 0.17145)
		(layer "F.Cu")
		(net "DEBUG_HDR_A_UART_SEL")
	)
	(segment
		(start 15.494 -14.7066)
		(end 15.494 -15.367)
		(width 0.17145)
		(layer "F.Cu")
		(net "DEBUG_HDR_A_UART_SEL")
	)
	(segment
		(start 14.9098 -14.1224)
		(end 15.494 -14.7066)
		(width 0.17145)
		(layer "F.Cu")
		(net "DEBUG_HDR_A_UART_SEL")
	)
	(segment
		(start 25.2222 -6.5278)
		(end 25.2476 -6.5278)
		(width 0.17145)
		(layer "F.Cu")
		(net "DEBUG_HDR_A_UART_SEL")
	)
	(segment
		(start 26.936192 -8.137144)
		(end 26.936192 -9.06399)
		(width 0.17145)
		(layer "F.Cu")
		(net "DEBUG_HDR_A_UART_SEL")
	)
	(segment
		(start 26.4922 -7.2263)
		(end 26.4922 -7.693152)
		(width 0.17145)
		(layer "F.Cu")
		(net "DEBUG_HDR_A_UART_SEL")
	)
	(segment
		(start 25.2476 -6.5278)
		(end 25.9461 -7.2263)
		(width 0.17145)
		(layer "F.Cu")
		(net "DEBUG_HDR_A_UART_SEL")
	)
	(segment
		(start 25.9461 -7.2263)
		(end 26.4922 -7.2263)
		(width 0.17145)
		(layer "F.Cu")
		(net "DEBUG_HDR_A_UART_SEL")
	)
	(segment
		(start 13.77696 -19.21764)
		(end 15.494 -17.5006)
		(width 0.17145)
		(layer "F.Cu")
		(net "DEBUG_HDR_A_UART_SEL")
	)
	(via
		(at 25.2222 -6.5278)
		(size 0.508)
		(drill 0.254)
		(layers "F.Cu" "B.Cu")
		(net "DEBUG_HDR_A_UART_SEL")
	)
	(via
		(at 14.9098 -14.1224)
		(size 0.508)
		(drill 0.254)
		(layers "F.Cu" "B.Cu")
		(net "DEBUG_HDR_A_UART_SEL")
	)
	(via
		(at 15.494 -15.367)
		(size 0.6604)
		(drill 0.3302)
		(layers "F.Cu" "B.Cu")
		(net "DEBUG_HDR_A_UART_SEL")
	)
	(segment
		(start 22.5298 -6.5024)
		(end 14.9098 -14.1224)
		(width 0.17145)
		(layer "B.Cu")
		(net "DEBUG_HDR_A_UART_SEL")
	)
	(segment
		(start 25.1968 -6.5024)
		(end 22.5298 -6.5024)
		(width 0.17145)
		(layer "B.Cu")
		(net "DEBUG_HDR_A_UART_SEL")
	)
	(segment
		(start 25.2222 -6.5278)
		(end 25.1968 -6.5024)
		(width 0.17145)
		(layer "B.Cu")
		(net "DEBUG_HDR_A_UART_SEL")
	)
	(segment
		(start 44.926758 -22.959314)
		(end 41.868598 -22.959314)
		(width 0.17145)
		(layer "F.Cu")
		(net "DEBUG_CARD_B_PRSNT")
	)
	(segment
		(start 43.3959 -13.80236)
		(end 43.3959 -12.3952)
		(width 0.17145)
		(layer "F.Cu")
		(net "DEBUG_CARD_B_PRSNT")
	)
	(segment
		(start 40.272462 -21.726398)
		(end 39.118794 -20.57273)
		(width 0.17145)
		(layer "F.Cu")
		(net "DEBUG_CARD_B_PRSNT")
	)
	(segment
		(start 46.542452 -21.16836)
		(end 45.8724 -21.838412)
		(width 0.17145)
		(layer "F.Cu")
		(net "DEBUG_CARD_B_PRSNT")
	)
	(segment
		(start 47.5996 -21.16836)
		(end 46.542452 -21.16836)
		(width 0.17145)
		(layer "F.Cu")
		(net "DEBUG_CARD_B_PRSNT")
	)
	(segment
		(start 43.3578 -12.3571)
		(end 43.3578 -11.7856)
		(width 0.17145)
		(layer "F.Cu")
		(net "DEBUG_CARD_B_PRSNT")
	)
	(segment
		(start 40.400732 -10.323068)
		(end 41.516808 -10.323068)
		(width 0.17145)
		(layer "F.Cu")
		(net "DEBUG_CARD_B_PRSNT")
	)
	(segment
		(start 41.868598 -22.959314)
		(end 40.841676 -21.932392)
		(width 0.17145)
		(layer "F.Cu")
		(net "DEBUG_CARD_B_PRSNT")
	)
	(segment
		(start 39.118794 -19.824192)
		(end 40.030146 -18.91284)
		(width 0.17145)
		(layer "F.Cu")
		(net "DEBUG_CARD_B_PRSNT")
	)
	(segment
		(start 43.3959 -12.3952)
		(end 43.3578 -12.3571)
		(width 0.17145)
		(layer "F.Cu")
		(net "DEBUG_CARD_B_PRSNT")
	)
	(segment
		(start 40.052244 -16.492982)
		(end 40.052244 -10.671556)
		(width 0.17145)
		(layer "F.Cu")
		(net "DEBUG_CARD_B_PRSNT")
	)
	(segment
		(start 41.895268 -10.323068)
		(end 41.516808 -10.323068)
		(width 0.17145)
		(layer "F.Cu")
		(net "DEBUG_CARD_B_PRSNT")
	)
	(segment
		(start 45.8724 -21.838412)
		(end 45.8724 -22.4536)
		(width 0.17145)
		(layer "F.Cu")
		(net "DEBUG_CARD_B_PRSNT")
	)
	(segment
		(start 39.118794 -20.57273)
		(end 39.118794 -19.824192)
		(width 0.17145)
		(layer "F.Cu")
		(net "DEBUG_CARD_B_PRSNT")
	)
	(segment
		(start 43.3578 -11.7856)
		(end 41.895268 -10.323068)
		(width 0.17145)
		(layer "F.Cu")
		(net "DEBUG_CARD_B_PRSNT")
	)
	(segment
		(start 40.841676 -21.932392)
		(end 40.841676 -21.885148)
		(width 0.17145)
		(layer "F.Cu")
		(net "DEBUG_CARD_B_PRSNT")
	)
	(segment
		(start 45.172122 -22.71395)
		(end 44.926758 -22.959314)
		(width 0.17145)
		(layer "F.Cu")
		(net "DEBUG_CARD_B_PRSNT")
	)
	(segment
		(start 43.3705 -13.82776)
		(end 43.3959 -13.80236)
		(width 0.17145)
		(layer "F.Cu")
		(net "DEBUG_CARD_B_PRSNT")
	)
	(segment
		(start 40.794432 -21.885148)
		(end 40.635682 -21.726398)
		(width 0.17145)
		(layer "F.Cu")
		(net "DEBUG_CARD_B_PRSNT")
	)
	(segment
		(start 40.030146 -16.51508)
		(end 40.052244 -16.492982)
		(width 0.17145)
		(layer "F.Cu")
		(net "DEBUG_CARD_B_PRSNT")
	)
	(segment
		(start 45.61205 -22.71395)
		(end 45.172122 -22.71395)
		(width 0.17145)
		(layer "F.Cu")
		(net "DEBUG_CARD_B_PRSNT")
	)
	(segment
		(start 40.030146 -18.91284)
		(end 40.030146 -16.51508)
		(width 0.17145)
		(layer "F.Cu")
		(net "DEBUG_CARD_B_PRSNT")
	)
	(segment
		(start 40.052244 -10.671556)
		(end 40.400732 -10.323068)
		(width 0.17145)
		(layer "F.Cu")
		(net "DEBUG_CARD_B_PRSNT")
	)
	(segment
		(start 40.635682 -21.726398)
		(end 40.272462 -21.726398)
		(width 0.17145)
		(layer "F.Cu")
		(net "DEBUG_CARD_B_PRSNT")
	)
	(segment
		(start 40.841676 -21.885148)
		(end 40.794432 -21.885148)
		(width 0.17145)
		(layer "F.Cu")
		(net "DEBUG_CARD_B_PRSNT")
	)
	(segment
		(start 45.8724 -22.4536)
		(end 45.61205 -22.71395)
		(width 0.17145)
		(layer "F.Cu")
		(net "DEBUG_CARD_B_PRSNT")
	)
	(via
		(at 45.8724 -22.4536)
		(size 0.6604)
		(drill 0.3302)
		(layers "F.Cu" "B.Cu")
		(net "DEBUG_CARD_B_PRSNT")
	)
	(via
		(at 40.841676 -21.885148)
		(size 0.508)
		(drill 0.254)
		(layers "F.Cu" "B.Cu")
		(net "DEBUG_CARD_B_PRSNT")
	)
	(segment
		(start 54.029102 -56.238394)
		(end 54.029102 -58.564018)
		(width 0.17145)
		(layer "B.Cu")
		(net "DEBUG_CARD_B_PRSNT")
	)
	(segment
		(start 53.893974 -51.564286)
		(end 53.893974 -56.103266)
		(width 0.17145)
		(layer "B.Cu")
		(net "DEBUG_CARD_B_PRSNT")
	)
	(segment
		(start 53.893974 -56.103266)
		(end 54.029102 -56.238394)
		(width 0.17145)
		(layer "B.Cu")
		(net "DEBUG_CARD_B_PRSNT")
	)
	(segment
		(start 44.988988 -30.023562)
		(end 44.988988 -47.38243)
		(width 0.17145)
		(layer "B.Cu")
		(net "DEBUG_CARD_B_PRSNT")
	)
	(segment
		(start 52.59324 -59.99988)
		(end 50.400204 -59.99988)
		(width 0.17145)
		(layer "B.Cu")
		(net "DEBUG_CARD_B_PRSNT")
	)
	(segment
		(start 40.841676 -25.87625)
		(end 44.988988 -30.023562)
		(width 0.17145)
		(layer "B.Cu")
		(net "DEBUG_CARD_B_PRSNT")
	)
	(segment
		(start 46.319948 -48.71339)
		(end 51.043078 -48.71339)
		(width 0.17145)
		(layer "B.Cu")
		(net "DEBUG_CARD_B_PRSNT")
	)
	(segment
		(start 40.841676 -21.885148)
		(end 40.841676 -25.87625)
		(width 0.17145)
		(layer "B.Cu")
		(net "DEBUG_CARD_B_PRSNT")
	)
	(segment
		(start 54.029102 -58.564018)
		(end 52.59324 -59.99988)
		(width 0.17145)
		(layer "B.Cu")
		(net "DEBUG_CARD_B_PRSNT")
	)
	(segment
		(start 51.043078 -48.71339)
		(end 53.893974 -51.564286)
		(width 0.17145)
		(layer "B.Cu")
		(net "DEBUG_CARD_B_PRSNT")
	)
	(segment
		(start 44.988988 -47.38243)
		(end 46.319948 -48.71339)
		(width 0.17145)
		(layer "B.Cu")
		(net "DEBUG_CARD_B_PRSNT")
	)
	(segment
		(start 12.27074 -7.9248)
		(end 13.0556 -7.9248)
		(width 0.17145)
		(layer "F.Cu")
		(net "DEBUG_CARD_A_PRSNT")
	)
	(segment
		(start 7.66064 -21.42236)
		(end 7.4676 -21.6154)
		(width 0.17145)
		(layer "F.Cu")
		(net "DEBUG_CARD_A_PRSNT")
	)
	(segment
		(start 15.85976 -6.89864)
		(end 15.85976 -6.5405)
		(width 0.17145)
		(layer "F.Cu")
		(net "DEBUG_CARD_A_PRSNT")
	)
	(segment
		(start 11.95324 -9.41324)
		(end 11.95324 -8.2423)
		(width 0.17145)
		(layer "F.Cu")
		(net "DEBUG_CARD_A_PRSNT")
	)
	(segment
		(start 8.700008 -59.99988)
		(end 9.700006 -59.99988)
		(width 0.17145)
		(layer "F.Cu")
		(net "DEBUG_CARD_A_PRSNT")
	)
	(segment
		(start 13.0556 -7.9248)
		(end 13.335 -8.2042)
		(width 0.17145)
		(layer "F.Cu")
		(net "DEBUG_CARD_A_PRSNT")
	)
	(segment
		(start 7.4676 -22.4028)
		(end 7.112 -22.7584)
		(width 0.17145)
		(layer "F.Cu")
		(net "DEBUG_CARD_A_PRSNT")
	)
	(segment
		(start 8.7376 -21.42236)
		(end 7.66064 -21.42236)
		(width 0.17145)
		(layer "F.Cu")
		(net "DEBUG_CARD_A_PRSNT")
	)
	(segment
		(start 5.177028 -23.245572)
		(end 5.6642 -22.7584)
		(width 0.17145)
		(layer "F.Cu")
		(net "DEBUG_CARD_A_PRSNT")
	)
	(segment
		(start 7.4676 -21.6154)
		(end 7.4676 -22.4028)
		(width 0.17145)
		(layer "F.Cu")
		(net "DEBUG_CARD_A_PRSNT")
	)
	(segment
		(start 7.112 -22.7584)
		(end 6.3246 -22.7584)
		(width 0.17145)
		(layer "F.Cu")
		(net "DEBUG_CARD_A_PRSNT")
	)
	(segment
		(start 8.222996 -58.857134)
		(end 8.222996 -59.522868)
		(width 0.17145)
		(layer "F.Cu")
		(net "DEBUG_CARD_A_PRSNT")
	)
	(segment
		(start 3.556508 -54.190646)
		(end 8.222996 -58.857134)
		(width 0.17145)
		(layer "F.Cu")
		(net "DEBUG_CARD_A_PRSNT")
	)
	(segment
		(start 14.011148 -7.718552)
		(end 14.080236 -7.718552)
		(width 0.17145)
		(layer "F.Cu")
		(net "DEBUG_CARD_A_PRSNT")
	)
	(segment
		(start 5.6642 -22.7584)
		(end 6.3246 -22.7584)
		(width 0.17145)
		(layer "F.Cu")
		(net "DEBUG_CARD_A_PRSNT")
	)
	(segment
		(start 13.5255 -8.2042)
		(end 14.011148 -7.718552)
		(width 0.17145)
		(layer "F.Cu")
		(net "DEBUG_CARD_A_PRSNT")
	)
	(segment
		(start 12.192 -9.652)
		(end 11.95324 -9.41324)
		(width 0.17145)
		(layer "F.Cu")
		(net "DEBUG_CARD_A_PRSNT")
	)
	(segment
		(start 8.222996 -59.522868)
		(end 8.700008 -59.99988)
		(width 0.17145)
		(layer "F.Cu")
		(net "DEBUG_CARD_A_PRSNT")
	)
	(segment
		(start 14.080236 -7.718552)
		(end 14.245336 -7.553452)
		(width 0.17145)
		(layer "F.Cu")
		(net "DEBUG_CARD_A_PRSNT")
	)
	(segment
		(start 15.204948 -7.553452)
		(end 15.85976 -6.89864)
		(width 0.17145)
		(layer "F.Cu")
		(net "DEBUG_CARD_A_PRSNT")
	)
	(segment
		(start 4.027678 -51.413918)
		(end 3.556508 -51.885088)
		(width 0.17145)
		(layer "F.Cu")
		(net "DEBUG_CARD_A_PRSNT")
	)
	(segment
		(start 3.556508 -51.885088)
		(end 3.556508 -54.190646)
		(width 0.17145)
		(layer "F.Cu")
		(net "DEBUG_CARD_A_PRSNT")
	)
	(segment
		(start 5.177028 -23.261574)
		(end 5.177028 -23.245572)
		(width 0.17145)
		(layer "F.Cu")
		(net "DEBUG_CARD_A_PRSNT")
	)
	(segment
		(start 11.95324 -8.2423)
		(end 12.27074 -7.9248)
		(width 0.17145)
		(layer "F.Cu")
		(net "DEBUG_CARD_A_PRSNT")
	)
	(segment
		(start 14.245336 -7.553452)
		(end 15.204948 -7.553452)
		(width 0.17145)
		(layer "F.Cu")
		(net "DEBUG_CARD_A_PRSNT")
	)
	(segment
		(start 13.335 -8.2042)
		(end 13.5255 -8.2042)
		(width 0.17145)
		(layer "F.Cu")
		(net "DEBUG_CARD_A_PRSNT")
	)
	(segment
		(start 5.019802 -23.4188)
		(end 5.177028 -23.261574)
		(width 0.17145)
		(layer "F.Cu")
		(net "DEBUG_CARD_A_PRSNT")
	)
	(via
		(at 5.019802 -23.4188)
		(size 0.508)
		(drill 0.254)
		(layers "F.Cu" "B.Cu")
		(net "DEBUG_CARD_A_PRSNT")
	)
	(via
		(at 12.192 -9.652)
		(size 0.508)
		(drill 0.254)
		(layers "F.Cu" "B.Cu")
		(net "DEBUG_CARD_A_PRSNT")
	)
	(via
		(at 6.3246 -22.7584)
		(size 0.6604)
		(drill 0.3302)
		(layers "F.Cu" "B.Cu")
		(net "DEBUG_CARD_A_PRSNT")
	)
	(via
		(at 4.027678 -51.413918)
		(size 0.508)
		(drill 0.254)
		(layers "F.Cu" "B.Cu")
		(net "DEBUG_CARD_A_PRSNT")
	)
	(segment
		(start 4.027424 -51.362864)
		(end 4.027424 -48.180752)
		(width 0.17145)
		(layer "B.Cu")
		(net "DEBUG_CARD_A_PRSNT")
	)
	(segment
		(start 7.642352 -16.660876)
		(end 7.642352 -13.668248)
		(width 0.17145)
		(layer "B.Cu")
		(net "DEBUG_CARD_A_PRSNT")
	)
	(segment
		(start 4.597908 -24.840692)
		(end 5.019802 -24.418798)
		(width 0.17145)
		(layer "B.Cu")
		(net "DEBUG_CARD_A_PRSNT")
	)
	(segment
		(start 6.020054 -39.328852)
		(end 4.597908 -37.906706)
		(width 0.17145)
		(layer "B.Cu")
		(net "DEBUG_CARD_A_PRSNT")
	)
	(segment
		(start 5.019802 -24.418798)
		(end 5.019802 -23.4188)
		(width 0.17145)
		(layer "B.Cu")
		(net "DEBUG_CARD_A_PRSNT")
	)
	(segment
		(start 4.027424 -48.180752)
		(end 6.020054 -46.188122)
		(width 0.17145)
		(layer "B.Cu")
		(net "DEBUG_CARD_A_PRSNT")
	)
	(segment
		(start 5.0419 -19.261328)
		(end 7.642352 -16.660876)
		(width 0.17145)
		(layer "B.Cu")
		(net "DEBUG_CARD_A_PRSNT")
	)
	(segment
		(start 4.597908 -37.906706)
		(end 4.597908 -24.840692)
		(width 0.17145)
		(layer "B.Cu")
		(net "DEBUG_CARD_A_PRSNT")
	)
	(segment
		(start 5.019802 -23.4188)
		(end 5.0419 -23.396702)
		(width 0.17145)
		(layer "B.Cu")
		(net "DEBUG_CARD_A_PRSNT")
	)
	(segment
		(start 6.020054 -46.188122)
		(end 6.020054 -39.328852)
		(width 0.17145)
		(layer "B.Cu")
		(net "DEBUG_CARD_A_PRSNT")
	)
	(segment
		(start 4.027678 -51.413918)
		(end 4.027678 -51.363118)
		(width 0.17145)
		(layer "B.Cu")
		(net "DEBUG_CARD_A_PRSNT")
	)
	(segment
		(start 5.0419 -23.396702)
		(end 5.0419 -19.261328)
		(width 0.17145)
		(layer "B.Cu")
		(net "DEBUG_CARD_A_PRSNT")
	)
	(segment
		(start 7.642352 -13.668248)
		(end 10.0838 -11.2268)
		(width 0.17145)
		(layer "B.Cu")
		(net "DEBUG_CARD_A_PRSNT")
	)
	(segment
		(start 10.0838 -11.2268)
		(end 10.6172 -11.2268)
		(width 0.17145)
		(layer "B.Cu")
		(net "DEBUG_CARD_A_PRSNT")
	)
	(segment
		(start 10.6172 -11.2268)
		(end 12.192 -9.652)
		(width 0.17145)
		(layer "B.Cu")
		(net "DEBUG_CARD_A_PRSNT")
	)
	(segment
		(start 4.027678 -51.363118)
		(end 4.027424 -51.362864)
		(width 0.17145)
		(layer "B.Cu")
		(net "DEBUG_CARD_A_PRSNT")
	)
	(zone
		(layer "F.Cu")
		(hatch none 0.5)
		(connect_pads
			(clearance 0)
		)
		(min_thickness 0.25)
		(keepout
			(tracks allowed)
			(vias allowed)
			(pads allowed)
			(copperpour allowed)
			(footprints allowed)
		)
		(placement
			(enabled no)
			(sheetname "")
		)
		(fill
			(thermal_gap 0.5)
			(thermal_bridge_width 0.5)
			(island_removal_mode 0)
		)
		(polygon
			(pts
				(xy 7.1628 -20.955) (xy 7.1628 -18.9611) (xy 9.7409 -18.9611) (xy 9.7409 -20.955)
			)
		)
	)
	(zone
		(layer "F.Cu")
		(hatch none 0.5)
		(connect_pads
			(clearance 0)
		)
		(min_thickness 0.25)
		(keepout
			(tracks allowed)
			(vias allowed)
			(pads allowed)
			(copperpour allowed)
			(footprints allowed)
		)
		(placement
			(enabled no)
			(sheetname "")
		)
		(fill
			(thermal_gap 0.5)
			(thermal_bridge_width 0.5)
			(island_removal_mode 0)
		)
		(polygon
			(pts
				(xy 4.6228 -21.6408) (xy 4.6228 -19.9644) (xy 6.4389 -19.9644) (xy 6.4389 -21.6408)
			)
		)
	)
	(zone
		(layer "F.Cu")
		(hatch none 0.5)
		(connect_pads
			(clearance 0)
		)
		(min_thickness 0.25)
		(keepout
			(tracks allowed)
			(vias allowed)
			(pads allowed)
			(copperpour allowed)
			(footprints allowed)
		)
		(placement
			(enabled no)
			(sheetname "")
		)
		(fill
			(thermal_gap 0.5)
			(thermal_bridge_width 0.5)
			(island_removal_mode 0)
		)
		(polygon
			(pts
				(xy 47.5996 -49.9364) (xy 47.5996 -48.26) (xy 49.53 -48.26) (xy 49.53 -49.9364)
			)
		)
	)
	(zone
		(net "GND")
		(layer "F.Cu")
		(hatch none 0.5)
		(connect_pads
			(clearance 0.5)
		)
		(min_thickness 0.25)
		(fill yes
			(thermal_gap 0.5)
			(thermal_bridge_width 0.5)
			(island_removal_mode 0)
		)
		(polygon
			(pts
				(xy 55.3974 -48.9712) (xy 55.245 -49.1236) (xy 55.245 -49.4284) (xy 55.372 -49.5554) (xy 55.372 -50.2412)
				(xy 56.1848 -51.054) (xy 56.1848 -51.9176) (xy 56.3118 -52.0446) (xy 57.199022 -52.0446) (xy 57.351422 -51.8922)
				(xy 57.351422 -49.657) (xy 57.273952 -49.57953) (xy 56.53913 -49.57953) (xy 56.5277 -49.5681) (xy 56.2991 -49.5681)
				(xy 55.7022 -48.9712)
			)
		)
		(polygon
			(pts
				(xy 56.0324 -50.292) (xy 55.8292 -50.292) (xy 55.8292 -50.4952) (xy 56.0324 -50.4952)
			)
		)
		(polygon
			(pts
				(xy 57.0738 -50.038) (xy 56.8706 -50.038) (xy 56.8706 -50.2412) (xy 57.0738 -50.2412)
			)
		)
		(polygon
			(pts
				(xy 56.515 -50.038) (xy 56.3118 -50.038) (xy 56.3118 -50.2412) (xy 56.515 -50.2412)
			)
		)
		(polygon
			(pts
				(xy 56.0324 -49.7332) (xy 55.8292 -49.7332) (xy 55.8292 -49.9364) (xy 56.0324 -49.9364)
			)
		)
	)
	(zone
		(net "P3V3_STBY_A")
		(layer "F.Cu")
		(hatch none 0.5)
		(connect_pads
			(clearance 0.5)
		)
		(min_thickness 0.25)
		(fill yes
			(thermal_gap 0.5)
			(thermal_bridge_width 0.5)
			(island_removal_mode 0)
		)
		(polygon
			(pts
				(xy 24.2062 -1.0668) (xy 24.2062 -2.7432) (xy 23.9522 -2.9972) (xy 23.9522 -4.5212) (xy 24.0538 -4.6228)
				(xy 24.7396 -4.6228) (xy 24.8793 -4.4831) (xy 24.8793 -2.8321) (xy 24.7396 -2.6924) (xy 24.7396 -1.0668)
			)
		)
	)
	(zone
		(net "GND")
		(layer "F.Cu")
		(hatch none 0.5)
		(connect_pads
			(clearance 0.5)
		)
		(min_thickness 0.25)
		(fill yes
			(thermal_gap 0.5)
			(thermal_bridge_width 0.5)
			(island_removal_mode 0)
		)
		(polygon
			(pts
				(xy 54.423818 -68.260976) (xy 53.204618 -69.480176) (xy 53.204618 -72.413114) (xy 53.390038 -72.598534)
				(xy 54.116478 -72.598534) (xy 55.599584 -71.115428) (xy 55.599584 -68.551298) (xy 55.309262 -68.260976)
			)
		)
		(polygon
			(pts
				(xy 53.865018 -72.173592) (xy 53.661818 -72.173592) (xy 53.661818 -72.376792) (xy 53.865018 -72.376792)
			)
		)
		(polygon
			(pts
				(xy 53.865018 -71.614792) (xy 53.661818 -71.614792) (xy 53.661818 -71.817992) (xy 53.865018 -71.817992)
			)
		)
	)
	(zone
		(net "P5V_USB_A")
		(layer "F.Cu")
		(hatch none 0.5)
		(connect_pads
			(clearance 0.5)
		)
		(min_thickness 0.25)
		(fill yes
			(thermal_gap 0.5)
			(thermal_bridge_width 0.5)
			(island_removal_mode 0)
		)
		(polygon
			(pts
				(xy 27.3304 -1.0668) (xy 27.3304 -2.68224) (xy 27.159458 -2.853182) (xy 26.648918 -2.853182) (xy 26.4922 -3.0099)
				(xy 26.4922 -4.5974) (xy 26.67 -4.7752) (xy 27.7876 -4.7752) (xy 27.9654 -4.5974) (xy 27.9654 -1.0668)
			)
		)
	)
	(zone
		(net "USB_CONN_A_GND")
		(layer "F.Cu")
		(hatch none 0.5)
		(connect_pads
			(clearance 0.5)
		)
		(min_thickness 0.25)
		(fill yes
			(thermal_gap 0.5)
			(thermal_bridge_width 0.5)
			(island_removal_mode 0)
		)
		(polygon
			(pts
				(xy 4.795774 -51.414426) (xy 4.007612 -52.202588) (xy 4.007612 -54.09946) (xy 5.99313 -56.084978)
				(xy 6.718808 -56.084978) (xy 7.728204 -57.094374) (xy 7.728204 -57.696608) (xy 10.0584 -60.026804)
				(xy 10.0584 -64.360552) (xy 8.799322 -65.61963) (xy 4.128516 -65.61963) (xy 3.77698 -65.971166)
				(xy 3.77698 -67.82054) (xy 4.879594 -68.923154) (xy 7.764272 -68.923154) (xy 8.280146 -69.439028)
				(xy 8.280146 -72.448928) (xy 8.54456 -72.713342) (xy 9.72312 -72.713342) (xy 13.676122 -68.76034)
				(xy 13.676122 -54.969664) (xy 10.120884 -51.414426)
			)
		)
		(polygon
			(pts
				(xy 8.9408 -72.3138) (xy 8.7376 -72.3138) (xy 8.7376 -72.517) (xy 8.9408 -72.517)
			)
		)
		(polygon
			(pts
				(xy 8.9408 -71.755) (xy 8.7376 -71.755) (xy 8.7376 -71.9582) (xy 8.9408 -71.9582)
			)
		)
	)
	(zone
		(net "GND")
		(layer "F.Cu")
		(hatch none 0.5)
		(connect_pads
			(clearance 0.5)
		)
		(min_thickness 0.25)
		(fill yes
			(thermal_gap 0.5)
			(thermal_bridge_width 0.5)
			(island_removal_mode 0)
		)
		(polygon
			(pts
				(xy 27.0764 -14.478) (xy 24.2062 -17.3482) (xy 24.2062 -23.8506) (xy 15.6718 -32.385) (xy 15.6718 -32.9946)
				(xy 15.875 -33.1978) (xy 16.5608 -33.1978) (xy 24.1554 -25.6032) (xy 34.8996 -25.6032) (xy 41.6052 -32.3088)
				(xy 42.1894 -32.3088) (xy 42.4942 -32.004) (xy 42.4942 -30.988) (xy 34.8742 -23.368) (xy 34.8742 -15.531338)
				(xy 33.820862 -14.478)
			)
		)
	)
	(zone
		(net "P5V_VBUS_B")
		(layer "F.Cu")
		(hatch none 0.5)
		(connect_pads
			(clearance 0.5)
		)
		(min_thickness 0.25)
		(fill yes
			(thermal_gap 0.5)
			(thermal_bridge_width 0.5)
			(island_removal_mode 0)
		)
		(polygon
			(pts
				(xy 45.431202 -62.213998) (xy 41.5798 -66.0654) (xy 41.5798 -69.227192) (xy 44.386246 -72.033638)
				(xy 45.95241 -72.033638) (xy 46.073314 -71.912734) (xy 46.073314 -69.491098) (xy 44.525692 -67.943476)
				(xy 44.525692 -65.389506) (xy 45.458126 -64.457072) (xy 48.430942 -64.457072) (xy 48.971454 -63.91656)
				(xy 48.971454 -62.60592) (xy 48.579532 -62.213998)
			)
		)
		(polygon
			(pts
				(xy 44.92498 -70.823074) (xy 44.72178 -70.823074) (xy 44.72178 -71.026274) (xy 44.92498 -71.026274)
			)
		)
		(polygon
			(pts
				(xy 44.92498 -69.426074) (xy 44.72178 -69.426074) (xy 44.72178 -69.629274) (xy 44.92498 -69.629274)
			)
		)
	)
	(zone
		(layer "F.Cu")
		(hatch none 0.5)
		(connect_pads
			(clearance 0)
		)
		(min_thickness 0.25)
		(keepout
			(tracks allowed)
			(vias allowed)
			(pads allowed)
			(copperpour allowed)
			(footprints allowed)
		)
		(placement
			(enabled no)
			(sheetname "")
		)
		(fill
			(thermal_gap 0.5)
			(thermal_bridge_width 0.5)
			(island_removal_mode 0)
		)
		(polygon
			(pts
				(xy 11.5189 -19.48815) (xy 11.5189 -17.7546) (xy 13.2207 -17.7546) (xy 13.2207 -19.48815)
			)
		)
	)
	(zone
		(layer "F.Cu")
		(hatch none 0.5)
		(connect_pads
			(clearance 0)
		)
		(min_thickness 0.25)
		(keepout
			(tracks allowed)
			(vias allowed)
			(pads allowed)
			(copperpour allowed)
			(footprints allowed)
		)
		(placement
			(enabled no)
			(sheetname "")
		)
		(fill
			(thermal_gap 0.5)
			(thermal_bridge_width 0.5)
			(island_removal_mode 0)
		)
		(polygon
			(pts
				(xy 53.026818 -11.535664) (xy 51.807618 -11.535664) (xy 51.756818 -11.484864) (xy 51.756818 -10.976864)
				(xy 51.756818 -10.900664) (xy 51.756818 -9.656064) (xy 51.858418 -9.656064) (xy 52.976018 -9.656064)
				(xy 52.976018 -9.325864) (xy 54.398418 -9.325864) (xy 54.398418 -11.002264) (xy 53.509418 -11.002264)
				(xy 53.509418 -11.484864) (xy 53.458618 -11.535664)
			)
		)
	)
	(zone
		(net "GND")
		(layer "F.Cu")
		(hatch none 0.5)
		(connect_pads
			(clearance 0.5)
		)
		(min_thickness 0.25)
		(fill yes
			(thermal_gap 0.5)
			(thermal_bridge_width 0.5)
			(island_removal_mode 0)
		)
		(polygon
			(pts
				(xy 54.9148 -81.5086) (xy 54.0004 -82.423) (xy 54.0004 -84.5566) (xy 53.34 -85.217) (xy 43.7642 -85.217)
				(xy 43.4848 -85.4964) (xy 43.4848 -89.027) (xy 43.688 -89.2302) (xy 58.1152 -89.2302) (xy 58.3184 -89.027)
				(xy 58.3184 -81.8388) (xy 57.9882 -81.5086)
			)
		)
	)
	(zone
		(layer "F.Cu")
		(hatch none 0.5)
		(connect_pads
			(clearance 0)
		)
		(min_thickness 0.25)
		(keepout
			(tracks allowed)
			(vias allowed)
			(pads allowed)
			(copperpour allowed)
			(footprints allowed)
		)
		(placement
			(enabled no)
			(sheetname "")
		)
		(fill
			(thermal_gap 0.5)
			(thermal_bridge_width 0.5)
			(island_removal_mode 0)
		)
		(polygon
			(pts
				(xy 31.1404 -10.93089) (xy 32.826706 -10.93089) (xy 32.826706 -12.1666) (xy 31.1404 -12.1666)
			)
		)
	)
	(zone
		(layer "F.Cu")
		(hatch none 0.5)
		(connect_pads
			(clearance 0)
		)
		(min_thickness 0.25)
		(keepout
			(tracks allowed)
			(vias allowed)
			(pads allowed)
			(copperpour allowed)
			(footprints allowed)
		)
		(placement
			(enabled no)
			(sheetname "")
		)
		(fill
			(thermal_gap 0.5)
			(thermal_bridge_width 0.5)
			(island_removal_mode 0)
		)
		(polygon
			(pts
				(xy 23.6601 -2.9718) (xy 23.6601 -0.762) (xy 25.3619 -0.762) (xy 25.3619 -2.9718)
			)
		)
	)
	(zone
		(layer "F.Cu")
		(hatch none 0.5)
		(connect_pads
			(clearance 0)
		)
		(min_thickness 0.25)
		(keepout
			(tracks allowed)
			(vias allowed)
			(pads allowed)
			(copperpour allowed)
			(footprints allowed)
		)
		(placement
			(enabled no)
			(sheetname "")
		)
		(fill
			(thermal_gap 0.5)
			(thermal_bridge_width 0.5)
			(island_removal_mode 0)
		)
		(polygon
			(pts
				(xy 8.6868 -50.1904) (xy 8.6868 -48.514) (xy 10.3886 -48.514) (xy 10.3886 -50.1904)
			)
		)
	)
	(zone
		(layer "F.Cu")
		(hatch none 0.5)
		(connect_pads
			(clearance 0)
		)
		(min_thickness 0.25)
		(keepout
			(tracks allowed)
			(vias allowed)
			(pads allowed)
			(copperpour allowed)
			(footprints allowed)
		)
		(placement
			(enabled no)
			(sheetname "")
		)
		(fill
			(thermal_gap 0.5)
			(thermal_bridge_width 0.5)
			(island_removal_mode 0)
		)
		(polygon
			(pts
				(xy 29.6418 -7.0104) (xy 32.41548 -7.0104) (xy 32.41548 -9.228582) (xy 29.6418 -9.228582)
			)
		)
	)
	(zone
		(net "GND")
		(layer "F.Cu")
		(hatch none 0.5)
		(connect_pads
			(clearance 0.5)
		)
		(min_thickness 0.25)
		(fill yes
			(thermal_gap 0.5)
			(thermal_bridge_width 0.5)
			(island_removal_mode 0)
		)
		(polygon
			(pts
				(xy 0.886206 -61.155072) (xy 0.784606 -61.256672) (xy 0.784606 -66.05143) (xy 0.937006 -66.20383)
				(xy 2.129282 -66.20383) (xy 2.26949 -66.063622) (xy 2.26949 -62.095888) (xy 2.03708 -61.863224)
				(xy 1.804162 -61.863224) (xy 1.60401 -61.663072) (xy 1.60401 -61.430408) (xy 1.328674 -61.155072)
			)
		)
		(polygon
			(pts
				(xy 1.396238 -65.120266) (xy 1.193038 -65.120266) (xy 1.193038 -65.323466) (xy 1.396238 -65.323466)
			)
		)
		(polygon
			(pts
				(xy 1.396238 -64.256666) (xy 1.193038 -64.256666) (xy 1.193038 -64.459866) (xy 1.396238 -64.459866)
			)
		)
		(polygon
			(pts
				(xy 1.396238 -63.913258) (xy 1.193038 -63.913258) (xy 1.193038 -64.116458) (xy 1.396238 -64.116458)
			)
		)
		(polygon
			(pts
				(xy 1.396238 -63.049658) (xy 1.193038 -63.049658) (xy 1.193038 -63.252858) (xy 1.396238 -63.252858)
			)
		)
		(polygon
			(pts
				(xy 1.395222 -62.703964) (xy 1.192022 -62.703964) (xy 1.192022 -62.907164) (xy 1.395222 -62.907164)
			)
		)
		(polygon
			(pts
				(xy 1.395222 -61.840364) (xy 1.192022 -61.840364) (xy 1.192022 -62.043564) (xy 1.395222 -62.043564)
			)
		)
	)
	(zone
		(layer "F.Cu")
		(hatch none 0.5)
		(connect_pads
			(clearance 0)
		)
		(min_thickness 0.25)
		(keepout
			(tracks allowed)
			(vias allowed)
			(pads allowed)
			(copperpour allowed)
			(footprints allowed)
		)
		(placement
			(enabled no)
			(sheetname "")
		)
		(fill
			(thermal_gap 0.5)
			(thermal_bridge_width 0.5)
			(island_removal_mode 0)
		)
		(polygon
			(pts
				(xy 26.660094 -7.5692) (xy 28.702 -7.5692) (xy 28.702 -9.21131) (xy 26.660094 -9.21131)
			)
		)
	)
	(zone
		(layer "F.Cu")
		(hatch none 0.5)
		(connect_pads
			(clearance 0)
		)
		(min_thickness 0.25)
		(keepout
			(tracks allowed)
			(vias allowed)
			(pads allowed)
			(copperpour allowed)
			(footprints allowed)
		)
		(placement
			(enabled no)
			(sheetname "")
		)
		(fill
			(thermal_gap 0.5)
			(thermal_bridge_width 0.5)
			(island_removal_mode 0)
		)
		(polygon
			(pts
				(xy 6.5532 -27.2415) (xy 7.5692 -27.2415) (xy 7.5692 -29.1592) (xy 6.5532 -29.1592)
			)
		)
	)
	(zone
		(net "P5V_VBUS_A")
		(layer "F.Cu")
		(hatch none 0.5)
		(connect_pads
			(clearance 0.5)
		)
		(min_thickness 0.25)
		(fill yes
			(thermal_gap 0.5)
			(thermal_bridge_width 0.5)
			(island_removal_mode 0)
		)
		(polygon
			(pts
				(xy 1.223772 -57.572402) (xy 1.223772 -59.437016) (xy 1.487424 -59.700668) (xy 3.555238 -59.700668)
				(xy 5.118354 -61.263784) (xy 5.118354 -63.54064) (xy 6.112764 -64.53505) (xy 7.990332 -64.53505)
				(xy 8.581898 -63.943484) (xy 8.581898 -62.761114) (xy 7.946898 -62.126114) (xy 7.048246 -62.126114)
				(xy 6.284468 -61.362336) (xy 6.284468 -60.646564) (xy 4.426458 -58.788554) (xy 4.426458 -58.04535)
				(xy 3.656076 -57.274968) (xy 3.428238 -57.04713) (xy 1.589786 -57.04713) (xy 1.223772 -57.413144)
			)
		)
		(polygon
			(pts
				(xy 3.620262 -58.266838) (xy 3.417062 -58.266838) (xy 3.417062 -58.470038) (xy 3.620262 -58.470038)
			)
		)
		(polygon
			(pts
				(xy 2.223262 -58.266838) (xy 2.020062 -58.266838) (xy 2.020062 -58.470038) (xy 2.223262 -58.470038)
			)
		)
	)
	(zone
		(layer "F.Cu")
		(hatch none 0.5)
		(connect_pads
			(clearance 0)
		)
		(min_thickness 0.25)
		(keepout
			(tracks allowed)
			(vias allowed)
			(pads allowed)
			(copperpour allowed)
			(footprints allowed)
		)
		(placement
			(enabled no)
			(sheetname "")
		)
		(fill
			(thermal_gap 0.5)
			(thermal_bridge_width 0.5)
			(island_removal_mode 0)
		)
		(polygon
			(pts
				(xy 43.580558 -20.05965) (xy 43.580558 -19.05635) (xy 45.116242 -19.05635) (xy 45.116242 -20.05965)
			)
		)
	)
	(zone
		(net "GND")
		(layer "F.Cu")
		(hatch none 0.5)
		(connect_pads
			(clearance 0.5)
		)
		(min_thickness 0.25)
		(fill yes
			(thermal_gap 0.5)
			(thermal_bridge_width 0.5)
			(island_removal_mode 0)
		)
		(polygon
			(pts
				(arc
					(start 0.999998 5.937758)
					(mid 0.831888 5.868124)
					(end 0.762254 5.700014)
				)
				(xy 0.762254 -16.669512) (xy 1.016 -16.923258) (xy 5.301742 -16.923258) (xy 5.809996 -16.415004)
				(xy 5.809996 -12.7) (xy 5.809488 -12.699492) (xy 5.809488 -11.016488) (xy 5.4864 -10.6934) (xy 1.524 -10.6934)
				(xy 1.397 -10.5664) (xy 1.397 -2.9718) (xy 1.6002 -2.7686) (xy 9.1186 -2.7686) (xy 9.2964 -2.5908)
				(xy 9.2964 -1.2446) (xy 9.144 -1.0922) (xy 7.8994 -1.0922) (xy 7.6962 -0.889)
				(arc
					(start 7.6962 -0.857758)
					(mid 7.275312 -0.401655)
					(end 7.122668 0.199898)
				)
				(xy 7.122668 5.937758)
			)
		)
	)
	(zone
		(net "USB_CONN_B_GND")
		(layer "F.Cu")
		(hatch none 0.5)
		(connect_pads
			(clearance 0.5)
		)
		(min_thickness 0.25)
		(fill yes
			(thermal_gap 0.5)
			(thermal_bridge_width 0.5)
			(island_removal_mode 0)
		)
		(polygon
			(pts
				(xy 45.59554 -51.435) (xy 44.782486 -52.248054) (xy 44.782486 -55.89016) (xy 47.781972 -58.889646)
				(xy 48.755046 -58.889646) (xy 49.35982 -59.49442) (xy 49.35982 -64.163194) (xy 48.366426 -65.156588)
				(xy 45.27042 -65.156588) (xy 44.879514 -65.547494) (xy 44.879514 -67.703192) (xy 45.984922 -68.8086)
				(xy 49.900078 -68.8086) (xy 50.6857 -69.594222) (xy 50.6857 -72.36714) (xy 50.775362 -72.456802)
				(xy 52.802028 -72.456802) (xy 52.897278 -72.361552) (xy 52.897278 -69.28739) (xy 54.75478 -67.429888)
				(xy 54.75478 -59.633104) (xy 52.8828 -57.761124) (xy 52.8828 -52.5526) (xy 51.7652 -51.435)
			)
		)
		(polygon
			(pts
				(xy 52.442618 -71.614792) (xy 52.239418 -71.614792) (xy 52.239418 -71.817992) (xy 52.442618 -71.817992)
			)
		)
	)
	(zone
		(layer "F.Cu")
		(hatch none 0.5)
		(connect_pads
			(clearance 0)
		)
		(min_thickness 0.25)
		(keepout
			(tracks allowed)
			(vias allowed)
			(pads allowed)
			(copperpour allowed)
			(footprints allowed)
		)
		(placement
			(enabled no)
			(sheetname "")
		)
		(fill
			(thermal_gap 0.5)
			(thermal_bridge_width 0.5)
			(island_removal_mode 0)
		)
		(polygon
			(pts
				(xy 53.213 -30.2514) (xy 53.213 -29.6164) (xy 54.5592 -29.6164) (xy 54.5592 -30.2514)
			)
		)
	)
	(zone
		(net "GND")
		(layer "F.Cu")
		(hatch none 0.5)
		(connect_pads
			(clearance 0.5)
		)
		(min_thickness 0.25)
		(fill yes
			(thermal_gap 0.5)
			(thermal_bridge_width 0.5)
			(island_removal_mode 0)
		)
		(polygon
			(pts
				(xy 14.859 -72.898) (xy 14.6558 -73.1012) (xy 14.6558 -83.439) (xy 12.9032 -85.1916) (xy 3.6322 -85.1916)
				(xy 1.9558 -83.5152) (xy 1.9558 -74.0156) (xy 1.7526 -73.8124) (xy 0.9906 -73.8124) (xy 0.7874 -74.0156)
				(xy 0.7874 -89.0016) (xy 1.016 -89.2302) (xy 15.3924 -89.2302) (xy 15.621 -89.0016) (xy 15.621 -73.1266)
				(xy 15.3924 -72.898)
			)
		)
	)
	(zone
		(layer "F.Cu")
		(hatch none 0.5)
		(connect_pads
			(clearance 0)
		)
		(min_thickness 0.25)
		(keepout
			(tracks allowed)
			(vias allowed)
			(pads allowed)
			(copperpour allowed)
			(footprints allowed)
		)
		(placement
			(enabled no)
			(sheetname "")
		)
		(fill
			(thermal_gap 0.5)
			(thermal_bridge_width 0.5)
			(island_removal_mode 0)
		)
		(polygon
			(pts
				(xy 54.132734 -54.51602) (xy 55.97779 -54.51602) (xy 55.97779 -56.53532) (xy 54.132734 -56.53532)
			)
		)
	)
	(zone
		(net "GND")
		(layer "F.Cu")
		(hatch none 0.5)
		(connect_pads
			(clearance 0.5)
		)
		(min_thickness 0.25)
		(fill yes
			(thermal_gap 0.5)
			(thermal_bridge_width 0.5)
			(island_removal_mode 0)
		)
		(polygon
			(pts
				(xy 3.5814 -31.8262) (xy 3.3782 -32.0294) (xy 3.3782 -33.4518) (xy 3.556 -33.6296) (xy 13.081 -33.6296)
				(xy 13.1826 -33.528) (xy 13.1826 -32.0294) (xy 12.9794 -31.8262)
			)
		)
	)
	(zone
		(layer "F.Cu")
		(hatch none 0.5)
		(connect_pads
			(clearance 0)
		)
		(min_thickness 0.25)
		(keepout
			(tracks allowed)
			(vias allowed)
			(pads allowed)
			(copperpour allowed)
			(footprints allowed)
		)
		(placement
			(enabled no)
			(sheetname "")
		)
		(fill
			(thermal_gap 0.5)
			(thermal_bridge_width 0.5)
			(island_removal_mode 0)
		)
		(polygon
			(pts
				(xy 43.01998 -10.383012) (xy 43.01998 -9.398) (xy 44.1198 -9.398) (xy 44.1198 -10.383012)
			)
		)
	)
	(zone
		(layer "F.Cu")
		(hatch none 0.5)
		(connect_pads
			(clearance 0)
		)
		(min_thickness 0.25)
		(keepout
			(tracks allowed)
			(vias allowed)
			(pads allowed)
			(copperpour allowed)
			(footprints allowed)
		)
		(placement
			(enabled no)
			(sheetname "")
		)
		(fill
			(thermal_gap 0.5)
			(thermal_bridge_width 0.5)
			(island_removal_mode 0)
		)
		(polygon
			(pts
				(xy 47.498 -11.210036) (xy 47.498 -8.873236) (xy 49.7078 -8.873236) (xy 49.7078 -11.210036)
			)
		)
	)
	(zone
		(layer "F.Cu")
		(hatch none 0.5)
		(connect_pads
			(clearance 0)
		)
		(min_thickness 0.25)
		(keepout
			(tracks allowed)
			(vias allowed)
			(pads allowed)
			(copperpour allowed)
			(footprints allowed)
		)
		(placement
			(enabled no)
			(sheetname "")
		)
		(fill
			(thermal_gap 0.5)
			(thermal_bridge_width 0.5)
			(island_removal_mode 0)
		)
		(polygon
			(pts
				(xy 46.101 -20.701) (xy 46.101 -19.05) (xy 48.392842 -19.05) (xy 48.392842 -20.701)
			)
		)
	)
	(zone
		(layer "F.Cu")
		(hatch none 0.5)
		(connect_pads
			(clearance 0)
		)
		(min_thickness 0.25)
		(keepout
			(tracks allowed)
			(vias allowed)
			(pads allowed)
			(copperpour allowed)
			(footprints allowed)
		)
		(placement
			(enabled no)
			(sheetname "")
		)
		(fill
			(thermal_gap 0.5)
			(thermal_bridge_width 0.5)
			(island_removal_mode 0)
		)
		(polygon
			(pts
				(xy 41.183306 -10.541) (xy 41.183306 -9.4488) (xy 42.2656 -9.4488) (xy 42.2656 -10.541)
			)
		)
	)
	(zone
		(layer "F.Cu")
		(hatch none 0.5)
		(connect_pads
			(clearance 0)
		)
		(min_thickness 0.25)
		(keepout
			(tracks allowed)
			(vias allowed)
			(pads allowed)
			(copperpour allowed)
			(footprints allowed)
		)
		(placement
			(enabled no)
			(sheetname "")
		)
		(fill
			(thermal_gap 0.5)
			(thermal_bridge_width 0.5)
			(island_removal_mode 0)
		)
		(polygon
			(pts
				(xy 17.145 -18.1102) (xy 17.145 -17.0688) (xy 18.669 -17.0688) (xy 18.669 -18.1102)
			)
		)
	)
	(zone
		(net "PWR_BTN_B_CONN")
		(layer "F.Cu")
		(hatch none 0.5)
		(connect_pads
			(clearance 0.5)
		)
		(min_thickness 0.25)
		(fill yes
			(thermal_gap 0.5)
			(thermal_bridge_width 0.5)
			(island_removal_mode 0)
		)
		(polygon
			(pts
				(xy 48.0822 -75.7428) (xy 47.74438 -76.08062) (xy 47.74438 -82.83702) (xy 48.19142 -83.28406) (xy 49.67986 -83.28406)
				(xy 50.12944 -82.83448) (xy 50.12944 -76.34224) (xy 49.53 -75.7428)
			)
		)
	)
	(zone
		(net "GND")
		(layer "F.Cu")
		(hatch none 0.5)
		(connect_pads
			(clearance 0.5)
		)
		(min_thickness 0.25)
		(fill yes
			(thermal_gap 0.5)
			(thermal_bridge_width 0.5)
			(island_removal_mode 0)
		)
		(polygon
			(pts
				(xy 55.7784 -77.343) (xy 55.6514 -77.47) (xy 55.6514 -79.3496) (xy 55.7276 -79.4258) (xy 57.1246 -79.4258)
				(xy 57.2516 -79.2988) (xy 57.2516 -77.3938) (xy 57.2008 -77.343)
			)
		)
	)
	(zone
		(net "GND")
		(layer "F.Cu")
		(hatch none 0.5)
		(connect_pads
			(clearance 0.5)
		)
		(min_thickness 0.25)
		(fill yes
			(thermal_gap 0.5)
			(thermal_bridge_width 0.5)
			(island_removal_mode 0)
		)
		(polygon
			(pts
				(xy 45.876972 -74.672698) (xy 50.620168 -74.672698) (xy 51.018694 -74.274172) (xy 51.018694 -73.078086)
				(xy 50.809398 -72.86879) (xy 46.606968 -72.86879) (xy 46.443138 -72.86879) (xy 45.91304 -72.338692)
				(xy 45.09516 -72.338692) (xy 44.992798 -72.441054) (xy 44.992798 -74.58329) (xy 45.082206 -74.672698)
			)
		)
		(polygon
			(pts
				(xy 50.229516 -73.691496) (xy 50.026316 -73.691496) (xy 50.026316 -73.894696) (xy 50.229516 -73.894696)
			)
		)
		(polygon
			(pts
				(xy 49.365916 -73.691496) (xy 48.857916 -73.691496) (xy 48.857916 -73.894696) (xy 49.365916 -73.894696)
			)
		)
		(polygon
			(pts
				(xy 48.197516 -73.691496) (xy 47.689516 -73.691496) (xy 47.689516 -73.894696) (xy 48.197516 -73.894696)
			)
		)
		(polygon
			(pts
				(xy 47.029116 -73.691496) (xy 46.825916 -73.691496) (xy 46.825916 -73.894696) (xy 47.029116 -73.894696)
			)
		)
	)
	(zone
		(layer "F.Cu")
		(hatch none 0.5)
		(connect_pads
			(clearance 0)
		)
		(min_thickness 0.25)
		(keepout
			(tracks allowed)
			(vias allowed)
			(pads allowed)
			(copperpour allowed)
			(footprints allowed)
		)
		(placement
			(enabled no)
			(sheetname "")
		)
		(fill
			(thermal_gap 0.5)
			(thermal_bridge_width 0.5)
			(island_removal_mode 0)
		)
		(polygon
			(pts
				(xy 43.053 -14.478) (xy 43.053 -13.5128) (xy 43.688 -13.5128) (xy 43.688 -14.478)
			)
		)
	)
	(zone
		(layer "F.Cu")
		(hatch none 0.5)
		(connect_pads
			(clearance 0)
		)
		(min_thickness 0.25)
		(keepout
			(tracks allowed)
			(vias allowed)
			(pads allowed)
			(copperpour allowed)
			(footprints allowed)
		)
		(placement
			(enabled no)
			(sheetname "")
		)
		(fill
			(thermal_gap 0.5)
			(thermal_bridge_width 0.5)
			(island_removal_mode 0)
		)
		(polygon
			(pts
				(xy 19.506692 -16.277844) (xy 19.506692 -15.236444) (xy 21.030692 -15.236444) (xy 21.030692 -16.277844)
			)
		)
	)
	(zone
		(net "PWR_BTN_A_CONN")
		(layer "F.Cu")
		(hatch none 0.5)
		(connect_pads
			(clearance 0.5)
		)
		(min_thickness 0.25)
		(fill yes
			(thermal_gap 0.5)
			(thermal_bridge_width 0.5)
			(island_removal_mode 0)
		)
		(polygon
			(pts
				(xy 7.369302 -75.646788) (xy 7.06755 -75.94854) (xy 7.06755 -82.702654) (xy 7.731506 -83.36661)
				(xy 8.814562 -83.36661) (xy 9.337802 -82.84337) (xy 9.337802 -75.852274) (xy 9.132316 -75.646788)
			)
		)
	)
	(zone
		(layer "F.Cu")
		(hatch none 0.5)
		(connect_pads
			(clearance 0)
		)
		(min_thickness 0.25)
		(keepout
			(tracks allowed)
			(vias allowed)
			(pads allowed)
			(copperpour allowed)
			(footprints allowed)
		)
		(placement
			(enabled no)
			(sheetname "")
		)
		(fill
			(thermal_gap 0.5)
			(thermal_bridge_width 0.5)
			(island_removal_mode 0)
		)
		(polygon
			(pts
				(xy 26.797 -3.0226) (xy 26.797 -0.73279) (xy 27.9654 -0.73279) (xy 27.9654 -3.0226)
			)
		)
	)
	(zone
		(layer "F.Cu")
		(hatch none 0.5)
		(connect_pads
			(clearance 0)
		)
		(min_thickness 0.25)
		(keepout
			(tracks allowed)
			(vias allowed)
			(pads allowed)
			(copperpour allowed)
			(footprints allowed)
		)
		(placement
			(enabled no)
			(sheetname "")
		)
		(fill
			(thermal_gap 0.5)
			(thermal_bridge_width 0.5)
			(island_removal_mode 0)
		)
		(polygon
			(pts
				(xy 7.7724 -27.2669) (xy 8.7884 -27.2669) (xy 8.7884 -28.3083) (xy 7.7724 -28.3083)
			)
		)
	)
	(zone
		(layer "F.Cu")
		(hatch none 0.5)
		(connect_pads
			(clearance 0)
		)
		(min_thickness 0.25)
		(keepout
			(tracks allowed)
			(vias allowed)
			(pads allowed)
			(copperpour allowed)
			(footprints allowed)
		)
		(placement
			(enabled no)
			(sheetname "")
		)
		(fill
			(thermal_gap 0.5)
			(thermal_bridge_width 0.5)
			(island_removal_mode 0)
		)
		(polygon
			(pts
				(xy 54.991 -13.0048) (xy 54.991 -11.7856) (xy 55.9054 -11.7856) (xy 55.9054 -13.0048)
			)
		)
	)
	(zone
		(net "P5V_USB_A")
		(layer "F.Cu")
		(hatch none 0.5)
		(connect_pads
			(clearance 0.5)
		)
		(min_thickness 0.25)
		(fill yes
			(thermal_gap 0.5)
			(thermal_bridge_width 0.5)
			(island_removal_mode 0)
		)
		(polygon
			(pts
				(xy 1.751076 -60.007754) (xy 1.62941 -60.12942) (xy 1.62941 -61.025024) (xy 2.589022 -61.984636)
				(xy 2.589022 -65.14338) (xy 2.821432 -65.37579) (xy 3.892804 -65.37579) (xy 4.683252 -64.585342)
				(xy 4.683252 -61.276992) (xy 3.414014 -60.007754)
			)
		)
		(polygon
			(pts
				(xy 3.682238 -64.256666) (xy 3.479038 -64.256666) (xy 3.479038 -64.459866) (xy 3.682238 -64.459866)
			)
		)
		(polygon
			(pts
				(xy 3.682238 -63.913258) (xy 3.479038 -63.913258) (xy 3.479038 -64.116458) (xy 3.682238 -64.116458)
			)
		)
		(polygon
			(pts
				(xy 3.682238 -63.049658) (xy 3.479038 -63.049658) (xy 3.479038 -63.252858) (xy 3.682238 -63.252858)
			)
		)
		(polygon
			(pts
				(xy 3.681222 -62.703964) (xy 3.478022 -62.703964) (xy 3.478022 -62.907164) (xy 3.681222 -62.907164)
			)
		)
		(polygon
			(pts
				(xy 3.681222 -61.840364) (xy 3.478022 -61.840364) (xy 3.478022 -62.043564) (xy 3.681222 -62.043564)
			)
		)
		(polygon
			(pts
				(xy 3.620262 -61.340238) (xy 3.417062 -61.340238) (xy 3.417062 -61.543438) (xy 3.620262 -61.543438)
			)
		)
		(polygon
			(pts
				(xy 2.223262 -60.197238) (xy 2.020062 -60.197238) (xy 2.020062 -60.400438) (xy 2.223262 -60.400438)
			)
		)
	)
	(zone
		(layer "F.Cu")
		(hatch none 0.5)
		(connect_pads
			(clearance 0)
		)
		(min_thickness 0.25)
		(keepout
			(tracks allowed)
			(vias allowed)
			(pads allowed)
			(copperpour allowed)
			(footprints allowed)
		)
		(placement
			(enabled no)
			(sheetname "")
		)
		(fill
			(thermal_gap 0.5)
			(thermal_bridge_width 0.5)
			(island_removal_mode 0)
		)
		(polygon
			(pts
				(xy 55.289958 -17.1958) (xy 55.289958 -16.6878) (xy 56.825642 -16.6878) (xy 56.825642 -17.1958)
			)
		)
	)
	(zone
		(net "GND")
		(layer "F.Cu")
		(hatch none 0.5)
		(connect_pads
			(clearance 0.5)
		)
		(min_thickness 0.25)
		(fill yes
			(thermal_gap 0.5)
			(thermal_bridge_width 0.5)
			(island_removal_mode 0)
		)
		(polygon
			(pts
				(xy 51.97729 5.937758)
				(arc
					(start 51.97729 0.199898)
					(mid 51.720219 -0.563278)
					(end 51.054 -1.015746)
				)
				(xy 51.054 -4.318) (xy 52.424584 -5.688584) (xy 54.839362 -5.688584) (xy 55.40375 -6.252972) (xy 55.40375 -6.77037)
				(xy 55.487824 -6.854444) (xy 57.115456 -6.854444) (xy 57.908444 -7.647432) (xy 57.908444 -16.39824)
				(xy 57.1246 -17.182084) (xy 57.1246 -23.495) (xy 57.6326 -24.003) (xy 58.039 -24.003) (xy 58.337704 -23.704296)
				(arc
					(start 58.337704 5.700014)
					(mid 58.26807 5.868124)
					(end 58.09996 5.937758)
				)
			)
		)
		(polygon
			(pts
				(xy 56.103012 -6.19887) (xy 55.899812 -6.19887) (xy 55.899812 -6.40207) (xy 56.103012 -6.40207)
			)
		)
	)
	(zone
		(layer "F.Cu")
		(hatch none 0.5)
		(connect_pads
			(clearance 0)
		)
		(min_thickness 0.25)
		(keepout
			(tracks allowed)
			(vias allowed)
			(pads allowed)
			(copperpour allowed)
			(footprints allowed)
		)
		(placement
			(enabled no)
			(sheetname "")
		)
		(fill
			(thermal_gap 0.5)
			(thermal_bridge_width 0.5)
			(island_removal_mode 0)
		)
		(polygon
			(pts
				(xy 26.7208 -10.57529) (xy 28.5242 -10.57529) (xy 28.5242 -13.335) (xy 26.7208 -13.335)
			)
		)
	)
	(zone
		(net "P3V3_STBY_B")
		(layer "F.Cu")
		(hatch none 0.5)
		(connect_pads
			(clearance 0.5)
		)
		(min_thickness 0.25)
		(fill yes
			(thermal_gap 0.5)
			(thermal_bridge_width 0.5)
			(island_removal_mode 0)
		)
		(polygon
			(pts
				(xy 32.4104 -1.0668) (xy 32.4104 -3.2004) (xy 32.9946 -3.7846) (xy 32.9946 -4.4196) (xy 33.528 -4.953)
				(xy 34.163 -4.953) (xy 34.5948 -4.5212) (xy 34.5948 -4.2418) (xy 33.4391 -3.0861) (xy 33.4391 -2.8829)
				(xy 33.0454 -2.4892) (xy 33.0454 -1.0668)
			)
		)
	)
	(zone
		(net "GND")
		(layer "F.Cu")
		(hatch none 0.5)
		(connect_pads
			(clearance 0.5)
		)
		(min_thickness 0.25)
		(fill yes
			(thermal_gap 0.5)
			(thermal_bridge_width 0.5)
			(island_removal_mode 0)
		)
		(polygon
			(pts
				(xy 3.175 -70.3326) (xy 3.048 -70.4596) (xy 3.048 -72.3392) (xy 3.1242 -72.4154) (xy 4.445 -72.4154)
				(xy 4.6482 -72.2122) (xy 4.6482 -70.3834) (xy 4.5974 -70.3326)
			)
		)
	)
	(zone
		(layer "F.Cu")
		(hatch none 0.5)
		(connect_pads
			(clearance 0)
		)
		(min_thickness 0.25)
		(keepout
			(tracks allowed)
			(vias allowed)
			(pads allowed)
			(copperpour allowed)
			(footprints allowed)
		)
		(placement
			(enabled no)
			(sheetname "")
		)
		(fill
			(thermal_gap 0.5)
			(thermal_bridge_width 0.5)
			(island_removal_mode 0)
		)
		(polygon
			(pts
				(xy 6.6548 -29.6037) (xy 7.6708 -29.6037) (xy 7.6708 -30.6451) (xy 6.6548 -30.6451)
			)
		)
	)
	(zone
		(net "P5V_USB_B")
		(layer "F.Cu")
		(hatch none 0.5)
		(connect_pads
			(clearance 0.5)
		)
		(min_thickness 0.25)
		(fill yes
			(thermal_gap 0.5)
			(thermal_bridge_width 0.5)
			(island_removal_mode 0)
		)
		(polygon
			(pts
				(xy 46.795944 -69.15277) (xy 46.377098 -69.571616) (xy 46.377098 -72.378062) (xy 46.550326 -72.55129)
				(xy 50.140362 -72.55129) (xy 50.336196 -72.355456) (xy 50.336196 -69.754242) (xy 49.734724 -69.15277)
			)
		)
		(polygon
			(pts
				(xy 50.229516 -71.405496) (xy 50.026316 -71.405496) (xy 50.026316 -71.608696) (xy 50.229516 -71.608696)
			)
		)
		(polygon
			(pts
				(xy 49.365916 -71.405496) (xy 48.857916 -71.405496) (xy 48.857916 -71.608696) (xy 49.365916 -71.608696)
			)
		)
		(polygon
			(pts
				(xy 48.197516 -71.405496) (xy 47.689516 -71.405496) (xy 47.689516 -71.608696) (xy 48.197516 -71.608696)
			)
		)
		(polygon
			(pts
				(xy 47.029116 -71.405496) (xy 46.825916 -71.405496) (xy 46.825916 -71.608696) (xy 47.029116 -71.608696)
			)
		)
		(polygon
			(pts
				(xy 47.99838 -70.823074) (xy 47.79518 -70.823074) (xy 47.79518 -71.026274) (xy 47.99838 -71.026274)
			)
		)
		(polygon
			(pts
				(xy 46.85538 -70.823074) (xy 46.65218 -70.823074) (xy 46.65218 -71.026274) (xy 46.85538 -71.026274)
			)
		)
		(polygon
			(pts
				(xy 47.99838 -69.426074) (xy 47.79518 -69.426074) (xy 47.79518 -69.629274) (xy 47.99838 -69.629274)
			)
		)
	)
	(zone
		(layer "F.Cu")
		(hatch none 0.5)
		(connect_pads
			(clearance 0)
		)
		(min_thickness 0.25)
		(keepout
			(tracks allowed)
			(vias allowed)
			(pads allowed)
			(copperpour allowed)
			(footprints allowed)
		)
		(placement
			(enabled no)
			(sheetname "")
		)
		(fill
			(thermal_gap 0.5)
			(thermal_bridge_width 0.5)
			(island_removal_mode 0)
		)
		(polygon
			(pts
				(xy 4.56565 -50.2539) (xy 4.56565 -48.6537) (xy 6.40715 -48.6537) (xy 6.40715 -50.2539)
			)
		)
	)
	(zone
		(layer "F.Cu")
		(hatch none 0.5)
		(connect_pads
			(clearance 0)
		)
		(min_thickness 0.25)
		(keepout
			(tracks allowed)
			(vias allowed)
			(pads allowed)
			(copperpour allowed)
			(footprints allowed)
		)
		(placement
			(enabled no)
			(sheetname "")
		)
		(fill
			(thermal_gap 0.5)
			(thermal_bridge_width 0.5)
			(island_removal_mode 0)
		)
		(polygon
			(pts
				(xy 52.555902 -49.3268) (xy 52.555902 -48.26) (xy 53.7718 -48.26) (xy 53.7718 -49.3268)
			)
		)
	)
	(zone
		(layer "F.Cu")
		(hatch none 0.5)
		(connect_pads
			(clearance 0)
		)
		(min_thickness 0.25)
		(keepout
			(tracks allowed)
			(vias allowed)
			(pads allowed)
			(copperpour allowed)
			(footprints allowed)
		)
		(placement
			(enabled no)
			(sheetname "")
		)
		(fill
			(thermal_gap 0.5)
			(thermal_bridge_width 0.5)
			(island_removal_mode 0)
		)
		(polygon
			(pts
				(xy 11.61415 -28.7274) (xy 11.61415 -27.051) (xy 13.43025 -27.051) (xy 13.43025 -28.7274)
			)
		)
	)
	(zone
		(layer "F.Cu")
		(hatch none 0.5)
		(connect_pads
			(clearance 0)
		)
		(min_thickness 0.25)
		(keepout
			(tracks allowed)
			(vias allowed)
			(pads allowed)
			(copperpour allowed)
			(footprints allowed)
		)
		(placement
			(enabled no)
			(sheetname "")
		)
		(fill
			(thermal_gap 0.5)
			(thermal_bridge_width 0.5)
			(island_removal_mode 0)
		)
		(polygon
			(pts
				(xy 13.3604 -13.776452) (xy 11.4554 -13.776452) (xy 11.4554 -13.1826) (xy 10.541 -13.1826) (xy 10.541 -11.573002)
				(xy 13.3604 -11.573002)
			)
		)
	)
	(zone
		(layer "F.Cu")
		(hatch none 0.5)
		(connect_pads
			(clearance 0)
		)
		(min_thickness 0.25)
		(keepout
			(tracks allowed)
			(vias allowed)
			(pads allowed)
			(copperpour allowed)
			(footprints allowed)
		)
		(placement
			(enabled no)
			(sheetname "")
		)
		(fill
			(thermal_gap 0.5)
			(thermal_bridge_width 0.5)
			(island_removal_mode 0)
		)
		(polygon
			(pts
				(xy 51.8287 -30.2641) (xy 51.8287 -29.6291) (xy 53.1749 -29.6291) (xy 53.1749 -30.2641)
			)
		)
	)
	(zone
		(layer "F.Cu")
		(hatch none 0.5)
		(connect_pads
			(clearance 0)
		)
		(min_thickness 0.25)
		(keepout
			(tracks allowed)
			(vias allowed)
			(pads allowed)
			(copperpour allowed)
			(footprints allowed)
		)
		(placement
			(enabled no)
			(sheetname "")
		)
		(fill
			(thermal_gap 0.5)
			(thermal_bridge_width 0.5)
			(island_removal_mode 0)
		)
		(polygon
			(pts
				(xy 51.880008 -9.270238) (xy 51.880008 -8.762238) (xy 53.434742 -8.762238) (xy 53.434742 -9.270238)
			)
		)
	)
	(zone
		(layer "F.Cu")
		(hatch none 0.5)
		(connect_pads
			(clearance 0)
		)
		(min_thickness 0.25)
		(keepout
			(tracks allowed)
			(vias allowed)
			(pads allowed)
			(copperpour allowed)
			(footprints allowed)
		)
		(placement
			(enabled no)
			(sheetname "")
		)
		(fill
			(thermal_gap 0.5)
			(thermal_bridge_width 0.5)
			(island_removal_mode 0)
		)
		(polygon
			(pts
				(xy 2.429002 -42.866818) (xy 2.429002 -41.266618) (xy 4.130802 -41.266618) (xy 4.130802 -42.866818)
			)
		)
	)
	(zone
		(net "GND")
		(layer "F.Cu")
		(hatch none 0.5)
		(connect_pads
			(clearance 0.5)
		)
		(min_thickness 0.25)
		(fill yes
			(thermal_gap 0.5)
			(thermal_bridge_width 0.5)
			(island_removal_mode 0)
		)
		(polygon
			(pts
				(xy 44.069 -30.607) (xy 44.009564 -30.666436) (xy 44.009564 -33.373822) (xy 44.10075 -33.465008)
				(xy 48.626268 -33.465008) (xy 48.627538 -33.463738) (xy 53.658262 -33.463738) (xy 53.721 -33.401)
				(xy 53.721 -32.280098) (xy 53.621686 -32.180784) (xy 51.623722 -32.180784) (xy 51.218338 -31.7754)
				(xy 47.671482 -31.7754) (xy 47.635668 -31.739332) (xy 45.963332 -31.739332) (xy 44.831 -30.607)
			)
		)
	)
	(zone
		(layer "F.Cu")
		(hatch none 0.5)
		(connect_pads
			(clearance 0)
		)
		(min_thickness 0.25)
		(keepout
			(tracks allowed)
			(vias allowed)
			(pads allowed)
			(copperpour allowed)
			(footprints allowed)
		)
		(placement
			(enabled no)
			(sheetname "")
		)
		(fill
			(thermal_gap 0.5)
			(thermal_bridge_width 0.5)
			(island_removal_mode 0)
		)
		(polygon
			(pts
				(xy 10.4775 -9.8552) (xy 10.4775 -7.9121) (xy 12.2936 -7.9121) (xy 12.2936 -9.8552)
			)
		)
	)
	(zone
		(layer "F.Cu")
		(hatch none 0.5)
		(connect_pads
			(clearance 0)
		)
		(min_thickness 0.25)
		(keepout
			(tracks allowed)
			(vias allowed)
			(pads allowed)
			(copperpour allowed)
			(footprints allowed)
		)
		(placement
			(enabled no)
			(sheetname "")
		)
		(fill
			(thermal_gap 0.5)
			(thermal_bridge_width 0.5)
			(island_removal_mode 0)
		)
		(polygon
			(pts
				(xy 15.585694 -6.05409) (xy 16.570706 -6.05409) (xy 16.570706 -7.15391) (xy 15.585694 -7.15391)
			)
		)
	)
	(zone
		(layer "F.Cu")
		(hatch none 0.5)
		(connect_pads
			(clearance 0)
		)
		(min_thickness 0.25)
		(keepout
			(tracks allowed)
			(vias allowed)
			(pads allowed)
			(copperpour allowed)
			(footprints allowed)
		)
		(placement
			(enabled no)
			(sheetname "")
		)
		(fill
			(thermal_gap 0.5)
			(thermal_bridge_width 0.5)
			(island_removal_mode 0)
		)
		(polygon
			(pts
				(xy 18.3896 -13.73505) (xy 15.9004 -13.73505) (xy 15.9004 -11.5316) (xy 18.3896 -11.5316)
			)
		)
	)
	(zone
		(net "GND")
		(layer "F.Cu")
		(hatch none 0.5)
		(connect_pads
			(clearance 0.5)
		)
		(min_thickness 0.25)
		(fill yes
			(thermal_gap 0.5)
			(thermal_bridge_width 0.5)
			(island_removal_mode 0)
		)
		(polygon
			(pts
				(xy 5.6642 -69.342) (xy 5.461 -69.5452) (xy 5.461 -72.263) (xy 5.6134 -72.4154) (xy 7.8994 -72.4154)
				(xy 7.9756 -72.3392) (xy 7.9756 -69.6214) (xy 7.6962 -69.342)
			)
		)
		(polygon
			(pts
				(xy 7.5184 -71.755) (xy 7.3152 -71.755) (xy 7.3152 -71.9582) (xy 7.5184 -71.9582)
			)
		)
	)
	(zone
		(layer "F.Cu")
		(hatch none 0.5)
		(connect_pads
			(clearance 0)
		)
		(min_thickness 0.25)
		(keepout
			(tracks allowed)
			(vias allowed)
			(pads allowed)
			(copperpour allowed)
			(footprints allowed)
		)
		(placement
			(enabled no)
			(sheetname "")
		)
		(fill
			(thermal_gap 0.5)
			(thermal_bridge_width 0.5)
			(island_removal_mode 0)
		)
		(polygon
			(pts
				(xy 50.260758 -27.6352) (xy 50.260758 -25.96515) (xy 51.796442 -25.96515) (xy 51.796442 -27.6352)
			)
		)
	)
	(zone
		(layer "F.Cu")
		(hatch none 0.5)
		(connect_pads
			(clearance 0)
		)
		(min_thickness 0.25)
		(keepout
			(tracks allowed)
			(vias allowed)
			(pads allowed)
			(copperpour allowed)
			(footprints allowed)
		)
		(placement
			(enabled no)
			(sheetname "")
		)
		(fill
			(thermal_gap 0.5)
			(thermal_bridge_width 0.5)
			(island_removal_mode 0)
		)
		(polygon
			(pts
				(xy 49.607216 -17.78) (xy 49.607216 -16.0782) (xy 51.1429 -16.0782) (xy 51.1429 -17.78)
			)
		)
	)
	(zone
		(net "P5V_USB_B")
		(layer "F.Cu")
		(hatch none 0.5)
		(connect_pads
			(clearance 0.5)
		)
		(min_thickness 0.25)
		(fill yes
			(thermal_gap 0.5)
			(thermal_bridge_width 0.5)
			(island_removal_mode 0)
		)
		(polygon
			(pts
				(xy 28.575 -1.0668) (xy 28.575 -4.6228) (xy 28.702 -4.7498) (xy 30.1244 -4.7498) (xy 30.3276 -4.5466)
				(xy 30.3276 -3.7084) (xy 29.3116 -2.6924) (xy 29.3116 -1.0668)
			)
		)
	)
	(zone
		(layers "F.Cu" "B.Cu" "In1.Cu" "In2.Cu")
		(name "Route Keepin")
		(hatch none 0.5)
		(connect_pads
			(clearance 0)
		)
		(min_thickness 0.25)
		(keepout
			(tracks allowed)
			(vias allowed)
			(pads allowed)
			(copperpour allowed)
			(footprints allowed)
		)
		(placement
			(enabled no)
			(sheetname "")
		)
		(fill
			(thermal_gap 0.5)
			(thermal_bridge_width 0.5)
			(island_removal_mode 0)
		)
		(polygon
			(pts
				(arc
					(start 59.312302 -46.957996)
					(mid 58.601326 -46.30848)
					(end 58.337958 -45.38218)
				)
				(arc
					(start 58.337958 5.700014)
					(mid 58.26825 5.868304)
					(end 58.09996 5.938012)
				)
				(xy 51.977036 5.938012)
				(arc
					(start 51.977036 0.199898)
					(mid 51.607368 -0.692306)
					(end 50.715164 -1.061974)
				)
				(arc
					(start 8.384794 -1.061974)
					(mid 7.49259 -0.692306)
					(end 7.122922 0.199898)
				)
				(xy 7.122922 5.938012)
				(arc
					(start 0.999998 5.938012)
					(mid 0.831708 5.868304)
					(end 0.762 5.700014)
				)
				(arc
					(start 0.762 -45.27931)
					(mid 0.429433 -46.309536)
					(end -0.442722 -46.950884)
				)
				(arc
					(start -2.07518 -47.494952)
					(mid -2.193043 -47.581568)
					(end -2.237994 -47.720758)
				)
				(arc
					(start -2.237994 -52.279296)
					(mid -2.193047 -52.418488)
					(end -2.07518 -52.505102)
				)
				(arc
					(start -0.442722 -53.04917)
					(mid 0.429451 -53.690505)
					(end 0.762 -54.720744)
				)
				(arc
					(start 0.762 -89.000076)
					(mid 0.831708 -89.168366)
					(end 0.999998 -89.238074)
				)
				(arc
					(start 15.40002 -89.238074)
					(mid 15.56831 -89.168366)
					(end 15.638018 -89.000076)
				)
				(arc
					(start 15.638018 -72.720708)
					(mid 15.970585 -71.690482)
					(end 16.84274 -71.049134)
				)
				(arc
					(start 18.475198 -70.505066)
					(mid 18.593061 -70.41845)
					(end 18.638012 -70.27926)
				)
				(arc
					(start 18.638012 -65.720722)
					(mid 18.593065 -65.58153)
					(end 18.475198 -65.494916)
				)
				(arc
					(start 16.84274 -64.950848)
					(mid 15.970567 -64.309513)
					(end 15.638018 -63.279274)
				)
				(arc
					(start 15.638018 -34.914078)
					(mid 15.772191 -34.239927)
					(end 16.154146 -33.668462)
				)
				(arc
					(start 23.568406 -26.254202)
					(mid 24.139899 -25.872313)
					(end 24.814022 -25.738074)
				)
				(arc
					(start 34.285936 -25.738074)
					(mid 34.960087 -25.872247)
					(end 35.531552 -26.254202)
				)
				(arc
					(start 42.945812 -33.668462)
					(mid 43.327701 -34.239955)
					(end 43.46194 -34.914078)
				)
				(arc
					(start 43.46194 -63.279274)
					(mid 43.129373 -64.3095)
					(end 42.257218 -64.950848)
				)
				(arc
					(start 40.62476 -65.494916)
					(mid 40.506897 -65.581532)
					(end 40.461946 -65.720722)
				)
				(arc
					(start 40.461946 -70.27926)
					(mid 40.506893 -70.418452)
					(end 40.62476 -70.505066)
				)
				(arc
					(start 42.257218 -71.049134)
					(mid 43.129391 -71.690469)
					(end 43.46194 -72.720708)
				)
				(arc
					(start 43.46194 -89.000076)
					(mid 43.531648 -89.168366)
					(end 43.699938 -89.238074)
				)
				(arc
					(start 58.09996 -89.238074)
					(mid 58.26825 -89.168366)
					(end 58.337958 -89.000076)
				)
				(arc
					(start 58.337958 -54.617874)
					(mid 58.601267 -53.691538)
					(end 59.312302 -53.042058)
				)
				(arc
					(start 60.206382 -52.595018)
					(mid 60.30239 -52.507277)
					(end 60.337954 -52.382166)
				)
				(arc
					(start 60.337954 -47.617888)
					(mid 60.302409 -47.492765)
					(end 60.206382 -47.405036)
				)
			)
		)
	)
	(zone
		(layers "F.Cu" "B.Cu" "In1.Cu" "In2.Cu")
		(hatch none 0.5)
		(connect_pads
			(clearance 0)
		)
		(min_thickness 0.25)
		(keepout
			(tracks not_allowed)
			(vias allowed)
			(pads allowed)
			(copperpour not_allowed)
			(footprints allowed)
		)
		(placement
			(enabled no)
			(sheetname "")
		)
		(fill
			(thermal_gap 0.5)
			(thermal_bridge_width 0.5)
			(island_removal_mode 0)
		)
		(polygon
			(pts
				(arc
					(start 34.147506 -19.99996)
					(mid 24.952706 -19.99996)
					(end 34.147506 -19.99996)
				)
			)
		)
	)
	(zone
		(layers "F.Cu" "B.Cu" "In1.Cu" "In2.Cu")
		(name "Package Keepin")
		(hatch none 0.5)
		(connect_pads
			(clearance 0)
		)
		(min_thickness 0.25)
		(keepout
			(tracks allowed)
			(vias allowed)
			(pads allowed)
			(copperpour allowed)
			(footprints allowed)
		)
		(placement
			(enabled no)
			(sheetname "")
		)
		(fill
			(thermal_gap 0.5)
			(thermal_bridge_width 0.5)
			(island_removal_mode 0)
		)
		(polygon
			(pts
				(arc
					(start 58.744358 -48.094138)
					(mid 57.520869 -46.976306)
					(end 57.067958 -45.38218)
				)
				(xy 57.067958 4.668012) (xy 53.247036 4.668012)
				(arc
					(start 53.247036 0.199644)
					(mid 52.505394 -1.590332)
					(end 50.715418 -2.331974)
				)
				(arc
					(start 8.384794 -2.331974)
					(mid 6.594654 -1.590421)
					(end 5.852922 0.199644)
				)
				(xy 5.852922 4.668012) (xy 2.032 4.668012)
				(arc
					(start 2.032 -45.27931)
					(mid 1.459687 -47.05215)
					(end -0.041148 -48.15586)
				)
				(xy -0.967994 -48.464724) (xy -0.967994 -51.53533)
				(arc
					(start -0.041148 -51.844194)
					(mid 1.45981 -52.947815)
					(end 2.032 -54.720744)
				)
				(xy 2.032 -87.968074) (xy 14.368018 -87.968074)
				(arc
					(start 14.368018 -72.720708)
					(mid 14.940331 -70.947868)
					(end 16.441166 -69.844158)
				)
				(xy 17.368012 -69.535294) (xy 17.368012 -66.464688)
				(arc
					(start 16.441166 -66.155824)
					(mid 14.940208 -65.052203)
					(end 14.368018 -63.279274)
				)
				(arc
					(start 14.368018 -34.914078)
					(mid 14.598781 -33.753866)
					(end 15.256002 -32.770318)
				)
				(arc
					(start 22.670262 -25.356058)
					(mid 23.653842 -24.698914)
					(end 24.814022 -24.468074)
				)
				(arc
					(start 34.285936 -24.468074)
					(mid 35.446148 -24.698837)
					(end 36.429696 -25.356058)
				)
				(arc
					(start 43.843956 -32.770318)
					(mid 44.5011 -33.753898)
					(end 44.73194 -34.914078)
				)
				(arc
					(start 44.73194 -63.279274)
					(mid 44.159724 -65.052233)
					(end 42.658792 -66.155824)
				)
				(xy 41.731946 -66.464688) (xy 41.731946 -69.535294)
				(arc
					(start 42.658792 -69.844158)
					(mid 44.159652 -70.947801)
					(end 44.73194 -72.720708)
				)
				(xy 44.73194 -87.968074) (xy 57.067958 -87.968074)
				(arc
					(start 57.067958 -54.617874)
					(mid 57.520971 -53.023811)
					(end 58.744358 -51.905916)
				)
				(xy 59.067954 -51.744118) (xy 59.067954 -48.255936)
			)
		)
	)
	(zone
		(net "USB_CONN_B_GND")
		(layer "B.Cu")
		(hatch none 0.5)
		(connect_pads
			(clearance 0.5)
		)
		(min_thickness 0.25)
		(fill yes
			(thermal_gap 0.5)
			(thermal_bridge_width 0.5)
			(island_removal_mode 0)
		)
		(polygon
			(pts
				(xy 43.5102 -51.5874) (xy 43.5102 -68.387722) (xy 45.29582 -70.173342) (xy 51.782218 -70.173342)
				(xy 52.5526 -69.40296) (xy 52.5526 -69.3928) (xy 52.832 -69.1134) (xy 52.832 -65.278) (xy 51.9176 -64.3636)
				(xy 46.3804 -64.3636) (xy 45.8978 -63.881) (xy 45.8978 -56.0832) (xy 46.4058 -55.5752) (xy 50.543968 -55.5752)
				(xy 52.121308 -53.99786) (xy 52.121308 -52.893468) (xy 50.12944 -50.9016) (xy 44.196 -50.9016)
			)
		)
	)
	(zone
		(net "GND")
		(layer "B.Cu")
		(hatch none 0.5)
		(connect_pads
			(clearance 0.5)
		)
		(min_thickness 0.25)
		(fill yes
			(thermal_gap 0.5)
			(thermal_bridge_width 0.5)
			(island_removal_mode 0)
		)
		(polygon
			(pts
				(xy 13.716508 -52.883308) (xy 13.716508 -67.254374) (xy 12.213082 -68.7578) (xy 4.2164 -68.7578)
				(xy 3.4544 -67.9958) (xy 3.4544 -59.2582) (xy 2.0574 -57.8612) (xy 0.889 -57.8612) (xy 0.762254 -57.987946)
				(arc
					(start 0.762254 -89.000076)
					(mid 0.831888 -89.168186)
					(end 0.999998 -89.23782)
				)
				(arc
					(start 15.40002 -89.23782)
					(mid 15.56813 -89.168186)
					(end 15.637764 -89.000076)
				)
				(arc
					(start 15.637764 -72.720708)
					(mid 15.844508 -71.8925)
					(end 16.416274 -71.258684)
				)
				(arc
					(start 16.416274 -64.741298)
					(mid 15.844483 -64.107465)
					(end 15.637764 -63.279274)
				)
				(arc
					(start 15.637764 -34.914078)
					(mid 15.771956 -34.23983)
					(end 16.153892 -33.668208)
				)
				(arc
					(start 23.568152 -26.253948)
					(mid 24.139761 -25.871981)
					(end 24.814022 -25.73782)
				)
				(arc
					(start 34.285936 -25.73782)
					(mid 34.960184 -25.872012)
					(end 35.531806 -26.253948)
				)
				(xy 39.564056 -30.285944) (xy 39.9288 -30.285944) (xy 40.95623 -29.258514) (xy 40.95623 -28.718002)
				(xy 38.566598 -26.32837) (xy 38.566598 -18.118328) (xy 39.006526 -17.6784) (xy 41.1988 -17.6784)
				(xy 41.7576 -18.2372) (xy 41.7576 -20.8026) (xy 43.6626 -22.7076) (xy 43.6626 -22.9108) (xy 47.526702 -26.774902)
				(xy 47.526702 -27.302968) (xy 47.525432 -29.645864) (xy 47.6504 -29.770832) (xy 47.6504 -40.54094)
				(xy 48.773588 -41.664128) (xy 48.773588 -45.22343) (xy 50.235358 -46.6852) (xy 52.2986 -46.6852)
				(xy 56.3372 -50.7238) (xy 56.3372 -59.5122) (xy 53.1622 -62.6872) (xy 53.1622 -69.7992) (xy 51.383184 -71.578216)
				(xy 45.188378 -71.578216) (xy 43.462194 -73.3044)
				(arc
					(start 43.462194 -89.000076)
					(mid 43.531828 -89.168186)
					(end 43.699938 -89.23782)
				)
				(arc
					(start 58.09996 -89.23782)
					(mid 58.26807 -89.168186)
					(end 58.337704 -89.000076)
				)
				(arc
					(start 58.337704 -54.617874)
					(mid 58.601081 -53.691356)
					(end 59.312302 -53.041804)
				)
				(arc
					(start 60.206382 -52.594764)
					(mid 60.302227 -52.50711)
					(end 60.3377 -52.382166)
				)
				(arc
					(start 60.3377 -47.617888)
					(mid 60.302223 -47.492947)
					(end 60.206382 -47.40529)
				)
				(arc
					(start 59.312302 -46.95825)
					(mid 58.601162 -46.308648)
					(end 58.337704 -45.38218)
				)
				(arc
					(start 58.337704 5.700014)
					(mid 58.26807 5.868124)
					(end 58.09996 5.937758)
				)
				(xy 51.97729 5.937758)
				(arc
					(start 51.97729 0.199898)
					(mid 51.607547 -0.692485)
					(end 50.715164 -1.062228)
				)
				(arc
					(start 8.384794 -1.062228)
					(mid 7.492411 -0.692485)
					(end 7.122668 0.199898)
				)
				(xy 7.122668 5.937758)
				(arc
					(start 0.999998 5.937758)
					(mid 0.831888 5.868124)
					(end 0.762254 5.700014)
				)
				(xy 0.762254 -16.0274) (xy 0.7747 -16.0147) (xy 0.7747 -16.841216) (xy 1.300988 -17.367504) (xy 4.095496 -17.367504)
				(xy 5.6261 -15.8369) (xy 5.6261 -12.635738) (xy 8.7376 -9.524238) (xy 8.7376 -6.35) (xy 8.89 -6.1976)
				(xy 8.89 -3.6068) (xy 9.2075 -3.2893) (xy 16.5481 -3.2893) (xy 17.3736 -2.4638) (xy 18.9738 -2.4638)
				(xy 19.4818 -2.9718) (xy 19.4818 -4.4958) (xy 18.3007 -5.6769) (xy 14.9733 -5.6769) (xy 13.8176 -6.8326)
				(xy 13.8176 -9.779) (xy 11.303 -12.2936) (xy 10.8712 -12.2936) (xy 10.4394 -12.7254) (xy 10.4394 -13.7414)
				(xy 9.5758 -14.605) (xy 9.5758 -16.3068) (xy 6.4008 -19.4818) (xy 6.4008 -24.0411) (xy 5.3467 -25.0952)
				(xy 5.3467 -25.1079) (xy 4.9784 -25.4762) (xy 4.9784 -37.699442) (xy 6.494272 -39.215314) (xy 6.494272 -45.660564)
			)
		)
	)
	(zone
		(net "USB_CONN_A_GND")
		(layer "B.Cu")
		(hatch none 0.5)
		(connect_pads
			(clearance 0.5)
		)
		(min_thickness 0.25)
		(fill yes
			(thermal_gap 0.5)
			(thermal_bridge_width 0.5)
			(island_removal_mode 0)
		)
		(polygon
			(pts
				(xy 4.18338 -64.5414) (xy 3.77698 -64.9478) (xy 3.77698 -67.82054) (xy 4.43484 -68.4784) (xy 11.938508 -68.4784)
				(xy 13.365226 -67.051682) (xy 13.365226 -53.052218) (xy 11.659108 -51.3461) (xy 4.8641 -51.3461)
				(xy 3.77698 -52.43322) (xy 3.77698 -54.60238) (xy 4.5466 -55.372) (xy 9.398 -55.372) (xy 10.0584 -56.0324)
				(xy 10.0584 -63.9826) (xy 9.4996 -64.5414)
			)
		)
	)
	(zone
		(net "GND")
		(layer "In1.Cu")
		(hatch none 0.5)
		(connect_pads
			(clearance 0.5)
		)
		(min_thickness 0.25)
		(fill yes
			(thermal_gap 0.5)
			(thermal_bridge_width 0.5)
			(island_removal_mode 0)
		)
		(polygon
			(pts
				(arc
					(start 0.999998 5.936996)
					(mid 0.832426 5.867586)
					(end 0.763016 5.700014)
				)
				(arc
					(start 0.763016 -45.27931)
					(mid 0.430233 -46.310162)
					(end -0.442468 -46.9519)
				)
				(arc
					(start -2.074926 -47.495968)
					(mid -2.192219 -47.582211)
					(end -2.236978 -47.720758)
				)
				(arc
					(start -2.236978 -52.279296)
					(mid -2.192246 -52.417862)
					(end -2.074926 -52.504086)
				)
				(arc
					(start -0.442468 -53.048154)
					(mid 0.430274 -53.689862)
					(end 0.763016 -54.720744)
				)
				(arc
					(start 0.763016 -89.000076)
					(mid 0.832426 -89.167648)
					(end 0.999998 -89.237058)
				)
				(arc
					(start 15.40002 -89.237058)
					(mid 15.567592 -89.167648)
					(end 15.637002 -89.000076)
				)
				(arc
					(start 15.637002 -72.720708)
					(mid 15.969785 -71.689856)
					(end 16.842486 -71.048118)
				)
				(arc
					(start 18.474944 -70.50405)
					(mid 18.592237 -70.417807)
					(end 18.636996 -70.27926)
				)
				(arc
					(start 18.636996 -65.720722)
					(mid 18.592264 -65.582156)
					(end 18.474944 -65.495932)
				)
				(arc
					(start 16.842486 -64.951864)
					(mid 15.969744 -64.310156)
					(end 15.637002 -63.279274)
				)
				(arc
					(start 15.637002 -34.914078)
					(mid 15.771252 -34.239538)
					(end 16.153384 -33.6677)
				)
				(arc
					(start 23.567644 -26.25344)
					(mid 24.139486 -25.871317)
					(end 24.814022 -25.737058)
				)
				(arc
					(start 34.285936 -25.737058)
					(mid 34.960476 -25.871308)
					(end 35.532314 -26.25344)
				)
				(arc
					(start 42.946574 -33.6677)
					(mid 43.328697 -34.239542)
					(end 43.462956 -34.914078)
				)
				(arc
					(start 43.462956 -63.279274)
					(mid 43.130173 -64.310126)
					(end 42.257472 -64.951864)
				)
				(arc
					(start 40.625014 -65.495932)
					(mid 40.507721 -65.582175)
					(end 40.462962 -65.720722)
				)
				(arc
					(start 40.462962 -70.27926)
					(mid 40.507694 -70.417826)
					(end 40.625014 -70.50405)
				)
				(arc
					(start 42.257472 -71.048118)
					(mid 43.130214 -71.689826)
					(end 43.462956 -72.720708)
				)
				(arc
					(start 43.462956 -89.000076)
					(mid 43.532366 -89.167648)
					(end 43.699938 -89.237058)
				)
				(arc
					(start 58.09996 -89.237058)
					(mid 58.267532 -89.167648)
					(end 58.336942 -89.000076)
				)
				(arc
					(start 58.336942 -54.617874)
					(mid 58.600403 -53.691004)
					(end 59.311794 -53.041042)
				)
				(arc
					(start 60.205874 -52.594002)
					(mid 60.301521 -52.506702)
					(end 60.336938 -52.382166)
				)
				(arc
					(start 60.336938 -47.617888)
					(mid 60.301448 -47.493397)
					(end 60.205874 -47.406052)
				)
				(arc
					(start 59.311794 -46.959012)
					(mid 58.600359 -46.309077)
					(end 58.336942 -45.38218)
				)
				(arc
					(start 58.336942 5.700014)
					(mid 58.267532 5.867586)
					(end 58.09996 5.936996)
				)
				(xy 51.978052 5.936996)
				(arc
					(start 51.978052 0.199898)
					(mid 51.608086 -0.693024)
					(end 50.715164 -1.06299)
				)
				(arc
					(start 8.384794 -1.06299)
					(mid 7.491872 -0.693024)
					(end 7.121906 0.199898)
				)
				(xy 7.121906 5.936996)
			)
		)
	)
	(zone
		(net "P5V_USB_B")
		(layer "In2.Cu")
		(hatch none 0.5)
		(connect_pads
			(clearance 0.5)
		)
		(min_thickness 0.25)
		(fill yes
			(thermal_gap 0.5)
			(thermal_bridge_width 0.5)
			(island_removal_mode 0)
		)
		(polygon
			(pts
				(xy 28.984194 -3.5941) (xy 28.5369 -4.041394) (xy 28.5369 -12.4333) (xy 36.324794 -12.4333) (xy 43.3705 -19.479006)
				(xy 43.3705 -21.993606) (xy 49.9999 -28.623006) (xy 49.9999 -42.720006) (xy 50.5587 -43.278806)
				(xy 50.5587 -45.260006) (xy 56.3245 -51.025806) (xy 56.3245 -59.819286) (xy 54.3687 -61.775086)
				(arc
					(start 54.3687 -68.006468)
					(mid 54.354116 -68.079315)
					(end 54.31282 -68.141088)
				)
				(xy 52.239418 -70.214744) (xy 48.320706 -70.214744) (xy 47.99965 -70.5358) (xy 47.99965 -71.580248)
				(xy 48.861218 -72.441816) (xy 53.836316 -72.441816) (xy 53.91531 -72.441816) (xy 54.841394 -73.3679)
				(xy 58.336942 -73.3679)
				(arc
					(start 58.336942 -54.617874)
					(mid 58.495 -53.888516)
					(end 58.9407 -53.289962)
				)
				(xy 58.9407 -49.481994) (xy 56.842406 -47.3837) (xy 56.080406 -47.3837) (xy 53.7845 -45.087794)
				(xy 53.7845 -41.607994) (xy 52.641754 -40.465248) (xy 52.641754 -35.131248) (xy 52.6415 -35.130994)
				(xy 52.6415 -34.973006) (xy 53.7845 -33.830006) (xy 53.7845 -27.383994) (xy 47.4345 -21.033994)
				(xy 47.4345 -18.214594) (xy 38.173406 -8.9535) (xy 32.560006 -8.9535) (xy 30.7975 -7.190994) (xy 30.7975 -4.269994)
				(xy 30.121606 -3.5941)
			)
		)
	)
	(zone
		(net "GND")
		(layer "In2.Cu")
		(hatch none 0.5)
		(connect_pads
			(clearance 0.5)
		)
		(min_thickness 0.25)
		(fill yes
			(thermal_gap 0.5)
			(thermal_bridge_width 0.5)
			(island_removal_mode 0)
		)
		(polygon
			(pts
				(arc
					(start 0.999998 5.936996)
					(mid 0.832426 5.867586)
					(end 0.763016 5.700014)
				)
				(arc
					(start 0.763016 -45.27931)
					(mid 0.430233 -46.310162)
					(end -0.442468 -46.9519)
				)
				(arc
					(start -2.074926 -47.495968)
					(mid -2.192219 -47.582211)
					(end -2.236978 -47.720758)
				)
				(arc
					(start -2.236978 -52.279296)
					(mid -2.192246 -52.417862)
					(end -2.074926 -52.504086)
				)
				(arc
					(start -0.442468 -53.048154)
					(mid 0.430274 -53.689862)
					(end 0.763016 -54.720744)
				)
				(arc
					(start 0.763016 -89.000076)
					(mid 0.832426 -89.167648)
					(end 0.999998 -89.237058)
				)
				(arc
					(start 15.40002 -89.237058)
					(mid 15.567592 -89.167648)
					(end 15.637002 -89.000076)
				)
				(xy 15.637002 -73.2663) (xy 4.48691 -73.2663) (xy 1.67513 -70.45452) (xy 1.67513 -61.932312) (xy 2.61112 -60.996322)
				(xy 4.701286 -60.996322) (xy 5.380482 -61.675518) (xy 5.380482 -64.157606) (xy 4.056126 -65.481962)
				(xy 4.056126 -68.06692) (xy 4.95808 -68.968874) (xy 11.570208 -68.968874) (xy 13.4239 -67.115182)
				(xy 13.4239 -52.6669) (xy 11.655806 -52.6669) (xy 9.8425 -50.853594) (xy 9.8425 -35.892994) (xy 5.2705 -31.320994)
				(xy 5.2705 -30.147006) (xy 6.1595 -29.258006) (xy 6.1595 -19.352006) (xy 9.9695 -15.542006) (xy 9.9695 -12.748006)
				(xy 10.589006 -12.1285) (xy 11.45921 -12.1285) (xy 13.6525 -9.960864) (xy 13.6525 -6.144006) (xy 14.399006 -5.3975)
				(xy 18.844006 -5.3975) (xy 21.028406 -3.2131) (xy 30.279594 -3.2131) (xy 31.1785 -4.112006) (xy 31.1785 -4.366006)
				(xy 31.320994 -4.5085) (xy 32.433006 -4.5085) (xy 33.195006 -3.7465) (xy 34.368994 -3.7465) (xy 35.080194 -4.4577)
				(xy 53.622194 -4.4577) (xy 57.3659 -8.201406) (xy 57.3659 -36.121594) (xy 55.435754 -38.05174) (xy 55.435754 -39.03726)
				(xy 57.3659 -40.967406) (xy 57.3659 -46.865794) (xy 57.114694 -47.117) (xy 59.3217 -49.324006) (xy 59.3217 -53.036216)
				(arc
					(start 60.205874 -52.594002)
					(mid 60.301521 -52.506702)
					(end 60.336938 -52.382166)
				)
				(arc
					(start 60.336938 -47.617888)
					(mid 60.301448 -47.493397)
					(end 60.205874 -47.406052)
				)
				(arc
					(start 59.311794 -46.959012)
					(mid 58.600359 -46.309077)
					(end 58.336942 -45.38218)
				)
				(arc
					(start 58.336942 5.700014)
					(mid 58.267532 5.867586)
					(end 58.09996 5.936996)
				)
				(xy 51.978052 5.936996)
				(arc
					(start 51.978052 0.199898)
					(mid 51.608086 -0.693024)
					(end 50.715164 -1.06299)
				)
				(arc
					(start 8.384794 -1.06299)
					(mid 7.491872 -0.693024)
					(end 7.121906 0.199898)
				)
				(xy 7.121906 5.936996)
			)
		)
	)
	(zone
		(net "P3V3_STBY_B")
		(layer "In2.Cu")
		(hatch none 0.5)
		(connect_pads
			(clearance 0.5)
		)
		(min_thickness 0.25)
		(fill yes
			(thermal_gap 0.5)
			(thermal_bridge_width 0.5)
			(island_removal_mode 0)
		)
		(polygon
			(pts
				(xy 33.352994 -4.1275) (xy 32.590994 -4.8895) (xy 31.45409 -4.8895) (xy 31.1785 -5.16509) (xy 31.1785 -7.033006)
				(xy 32.717994 -8.5725) (xy 38.331394 -8.5725) (xy 47.8155 -18.056606) (xy 47.8155 -20.876006) (xy 54.1655 -27.226006)
				(xy 54.1655 -33.987994) (xy 53.022754 -35.13074) (xy 53.022754 -40.30726) (xy 54.1655 -41.450006)
				(xy 54.1655 -44.929806) (xy 56.238394 -47.0027) (xy 56.690006 -47.0027) (xy 56.9849 -46.707806)
				(xy 56.9849 -41.125394) (xy 55.054754 -39.195248) (xy 55.054754 -38.052248) (xy 55.0545 -38.051994)
				(xy 55.0545 -37.894006) (xy 56.9849 -35.963606) (xy 56.9849 -8.359394) (xy 53.464206 -4.8387) (xy 34.922206 -4.8387)
				(xy 34.211006 -4.1275)
			)
		)
	)
	(zone
		(net "GND")
		(layer "In2.Cu")
		(hatch none 0.5)
		(connect_pads
			(clearance 0.5)
		)
		(min_thickness 0.25)
		(fill yes
			(thermal_gap 0.5)
			(thermal_bridge_width 0.5)
			(island_removal_mode 0)
		)
		(polygon
			(pts
				(xy 28.425394 -12.8143) (xy 24.0411 -17.198594) (xy 24.0411 -24.310594) (xy 16.2687 -32.082994)
				(xy 16.2687 -33.552384)
				(arc
					(start 23.567644 -26.25344)
					(mid 24.139486 -25.871317)
					(end 24.814022 -25.737058)
				)
				(arc
					(start 34.285936 -25.737058)
					(mid 34.960476 -25.871308)
					(end 35.532314 -26.25344)
				)
				(arc
					(start 42.946574 -33.6677)
					(mid 43.328697 -34.239542)
					(end 43.462956 -34.914078)
				)
				(arc
					(start 43.462956 -63.279274)
					(mid 43.130173 -64.310126)
					(end 42.257472 -64.951864)
				)
				(arc
					(start 40.625014 -65.495932)
					(mid 40.507721 -65.582175)
					(end 40.462962 -65.720722)
				)
				(arc
					(start 40.462962 -70.27926)
					(mid 40.507694 -70.417826)
					(end 40.625014 -70.50405)
				)
				(arc
					(start 42.257472 -71.048118)
					(mid 43.130214 -71.689826)
					(end 43.462956 -72.720708)
				)
				(arc
					(start 43.462956 -89.000076)
					(mid 43.532366 -89.167648)
					(end 43.699938 -89.237058)
				)
				(arc
					(start 58.09996 -89.237058)
					(mid 58.267532 -89.167648)
					(end 58.336942 -89.000076)
				)
				(xy 58.336942 -73.7489) (xy 54.683406 -73.7489) (xy 53.757322 -72.822816) (xy 48.70323 -72.822816)
				(xy 47.61865 -71.738236) (xy 47.61865 -70.377812) (xy 48.162718 -69.833744) (xy 52.08143 -69.833744)
				(xy 53.9877 -67.927474)
				(arc
					(start 53.9877 -61.696092)
					(mid 54.002284 -61.623245)
					(end 54.04358 -61.561472)
				)
				(xy 55.9435 -59.661298) (xy 55.9435 -51.183794) (xy 50.1777 -45.417994) (xy 50.1777 -43.436794)
				(xy 49.6189 -42.877994) (xy 49.6189 -28.780994) (xy 42.9895 -22.151594) (xy 42.9895 -19.636994)
				(xy 36.166806 -12.8143)
			)
		)
	)
	(zone
		(net "P3V3_STBY_A")
		(layer "In2.Cu")
		(hatch none 0.5)
		(connect_pads
			(clearance 0.5)
		)
		(min_thickness 0.25)
		(fill yes
			(thermal_gap 0.5)
			(thermal_bridge_width 0.5)
			(island_removal_mode 0)
		)
		(polygon
			(pts
				(xy 21.186394 -3.5941) (xy 19.001994 -5.7785) (xy 14.556994 -5.7785) (xy 14.0335 -6.301994) (xy 14.0335 -10.119868)
				(xy 11.615674 -12.5095) (xy 10.746994 -12.5095) (xy 10.3505 -12.905994) (xy 10.3505 -15.699994)
				(xy 6.5405 -19.509994) (xy 6.5405 -29.415994) (xy 5.6515 -30.304994) (xy 5.6515 -31.163006) (xy 10.2235 -35.735006)
				(xy 10.2235 -50.695606) (xy 11.813794 -52.2859) (xy 13.4239 -52.2859) (xy 13.4239 -29.969206) (xy 20.8153 -22.577806)
				(xy 20.8153 -17.630394) (xy 20.0533 -16.868394) (xy 20.0533 -15.008606) (xy 25.5397 -9.522206) (xy 25.5397 -3.888994)
				(xy 25.244806 -3.5941)
			)
		)
	)
	(zone
		(net "P5V_USB_A")
		(layer "In2.Cu")
		(hatch none 0.5)
		(connect_pads
			(clearance 0.5)
		)
		(min_thickness 0.25)
		(fill yes
			(thermal_gap 0.5)
			(thermal_bridge_width 0.5)
			(island_removal_mode 0)
		)
		(polygon
			(pts
				(xy 26.215594 -3.5941) (xy 25.9207 -3.888994) (xy 25.9207 -9.680194) (xy 20.4343 -15.166594) (xy 20.4343 -16.710406)
				(xy 21.1963 -17.472406) (xy 21.1963 -22.735794) (xy 13.8049 -30.127194) (xy 13.8049 -67.194176)
				(xy 13.8049 -67.27317) (xy 11.728196 -69.349874) (xy 4.800092 -69.349874) (xy 3.675126 -68.224908)
				(xy 3.675126 -65.323974) (xy 4.999482 -63.999618) (xy 4.999482 -61.833506) (xy 4.543298 -61.377322)
				(xy 2.769108 -61.377322) (xy 2.05613 -62.0903) (xy 2.05613 -70.296532) (xy 4.644898 -72.8853) (xy 15.637002 -72.8853)
				(arc
					(start 15.637002 -72.720708)
					(mid 15.969785 -71.689856)
					(end 16.842486 -71.048118)
				)
				(arc
					(start 18.474944 -70.50405)
					(mid 18.592237 -70.417807)
					(end 18.636996 -70.27926)
				)
				(arc
					(start 18.636996 -65.720722)
					(mid 18.592264 -65.582156)
					(end 18.474944 -65.495932)
				)
				(arc
					(start 16.842486 -64.951864)
					(mid 15.969744 -64.310156)
					(end 15.637002 -63.279274)
				)
				(arc
					(start 15.637002 -34.914078)
					(mid 15.70085 -34.444169)
					(end 15.8877 -34.008314)
				)
				(xy 15.8877 -31.925006) (xy 23.6601 -24.152606) (xy 23.6601 -17.040606) (xy 28.1559 -12.544806)
				(xy 28.1559 -4.041394) (xy 27.708606 -3.5941)
			)
		)
	)
)
